(kicad_pcb
	(version 20241229)
	(generator "pcbnew")
	(generator_version "9.0")
	(general
		(thickness 1.6642)
		(legacy_teardrops no)
	)
	(paper "A3")
	(title_block
		(title "PolarFire SoM")
		(date "2025-07-22")
		(rev "1.1.4")
		(company "Antmicro Ltd")
		(comment 1 "www.antmicro.com")
	)
	(layers
		(0 "F.Cu" mixed)
		(4 "In1.Cu" power)
		(6 "In2.Cu" signal)
		(8 "In3.Cu" power)
		(10 "In4.Cu" signal)
		(12 "In5.Cu" power)
		(14 "In6.Cu" power)
		(16 "In7.Cu" signal)
		(18 "In8.Cu" power)
		(20 "In9.Cu" signal)
		(22 "In10.Cu" power)
		(24 "In11.Cu" signal)
		(26 "In12.Cu" signal)
		(2 "B.Cu" mixed)
		(9 "F.Adhes" user "F.Adhesive")
		(11 "B.Adhes" user "B.Adhesive")
		(13 "F.Paste" user)
		(15 "B.Paste" user)
		(5 "F.SilkS" user "F.Silkscreen")
		(7 "B.SilkS" user "B.Silkscreen")
		(1 "F.Mask" user)
		(3 "B.Mask" user)
		(17 "Dwgs.User" user "User.Drawings")
		(19 "Cmts.User" user "User.Comments")
		(21 "Eco1.User" user "User.Eco1")
		(23 "Eco2.User" user "User.Eco2")
		(25 "Edge.Cuts" user)
		(27 "Margin" user)
		(31 "F.CrtYd" user "F.Courtyard")
		(29 "B.CrtYd" user "B.Courtyard")
		(35 "F.Fab" user)
		(33 "B.Fab" user)
	)
	(setup
		(stackup
			(layer "F.SilkS"
				(type "Top Silk Screen")
			)
			(layer "F.Paste"
				(type "Top Solder Paste")
			)
			(layer "F.Mask"
				(type "Top Solder Mask")
				(color "Black")
				(thickness 0.03)
			)
			(layer "F.Cu"
				(type "copper")
				(thickness 0.035)
			)
			(layer "dielectric 1"
				(type "prepreg")
				(thickness 0.0964)
				(material "PR2313")
				(epsilon_r 4.31)
				(loss_tangent 0.02)
			)
			(layer "In1.Cu"
				(type "copper")
				(thickness 0.0152)
			)
			(layer "dielectric 2"
				(type "core")
				(thickness 0.1)
				(material "S1000-2M")
				(epsilon_r 4.35)
				(loss_tangent 0.022)
			)
			(layer "In2.Cu"
				(type "copper")
				(thickness 0.0152)
			)
			(layer "dielectric 3"
				(type "prepreg")
				(thickness 0.1118)
				(material "PR2116")
				(epsilon_r 4.29)
				(loss_tangent 0.0022)
			)
			(layer "In3.Cu"
				(type "copper")
				(thickness 0.0152)
			)
			(layer "dielectric 4"
				(type "core")
				(thickness 0.1)
				(material "S1000-2M")
				(epsilon_r 4.35)
				(loss_tangent 0.022)
			)
			(layer "In4.Cu"
				(type "copper")
				(thickness 0.0152)
			)
			(layer "dielectric 5"
				(type "prepreg")
				(thickness 0.1118)
				(material "PR2116")
				(epsilon_r 4.29)
				(loss_tangent 0.0022)
			)
			(layer "In5.Cu"
				(type "copper")
				(thickness 0.0152)
			)
			(layer "dielectric 6"
				(type "core")
				(thickness 0.1)
				(material "S1000-2M")
				(epsilon_r 4.35)
				(loss_tangent 0.022)
			)
			(layer "In6.Cu"
				(type "copper")
				(thickness 0.0152)
			)
			(layer "dielectric 7"
				(type "prepreg")
				(thickness 0.1118)
				(material "PR2116")
				(epsilon_r 4.29)
				(loss_tangent 0.0022)
			)
			(layer "In7.Cu"
				(type "copper")
				(thickness 0.0152)
			)
			(layer "dielectric 8"
				(type "core")
				(thickness 0.1)
				(material "S1000-2M")
				(epsilon_r 4.35)
				(loss_tangent 0.022)
			)
			(layer "In8.Cu"
				(type "copper")
				(thickness 0.0152)
			)
			(layer "dielectric 9"
				(type "prepreg")
				(thickness 0.1118)
				(material "PR2116")
				(epsilon_r 4.29)
				(loss_tangent 0.0022)
			)
			(layer "In9.Cu"
				(type "copper")
				(thickness 0.0152)
			)
			(layer "dielectric 10"
				(type "core")
				(thickness 0.1)
				(material "S1000-2M")
				(epsilon_r 4.35)
				(loss_tangent 0.02)
			)
			(layer "In10.Cu"
				(type "copper")
				(thickness 0.0152)
			)
			(layer "dielectric 11"
				(type "prepreg")
				(thickness 0.1118)
				(material "PR2116")
				(epsilon_r 4.31)
				(loss_tangent 0.02)
			)
			(layer "In11.Cu"
				(type "copper")
				(thickness 0.0152)
			)
			(layer "dielectric 12"
				(type "core")
				(thickness 0.1)
				(material "S1000-2M")
				(epsilon_r 4.5)
				(loss_tangent 0.02)
			)
			(layer "In12.Cu"
				(type "copper")
				(thickness 0.0152)
			)
			(layer "dielectric 13"
				(type "prepreg")
				(thickness 0.0964)
				(material "PR2313")
				(epsilon_r 4.5)
				(loss_tangent 0.02)
			)
			(layer "B.Cu"
				(type "copper")
				(thickness 0.035)
			)
			(layer "B.Mask"
				(type "Bottom Solder Mask")
				(color "Black")
				(thickness 0.03)
			)
			(layer "B.Paste"
				(type "Bottom Solder Paste")
			)
			(layer "B.SilkS"
				(type "Bottom Silk Screen")
			)
			(copper_finish "None")
			(dielectric_constraints yes)
		)
		(pad_to_mask_clearance 0)
		(allow_soldermask_bridges_in_footprints no)
		(tenting front back)
		(pcbplotparams
			(layerselection 0x00000000_00000000_55555555_5755f5ff)
			(plot_on_all_layers_selection 0x00000000_00000000_00000000_00000000)
			(disableapertmacros no)
			(usegerberextensions no)
			(usegerberattributes yes)
			(usegerberadvancedattributes yes)
			(creategerberjobfile yes)
			(dashed_line_dash_ratio 12.000000)
			(dashed_line_gap_ratio 3.000000)
			(svgprecision 6)
			(plotframeref no)
			(mode 1)
			(useauxorigin no)
			(hpglpennumber 1)
			(hpglpenspeed 20)
			(hpglpendiameter 15.000000)
			(pdf_front_fp_property_popups yes)
			(pdf_back_fp_property_popups yes)
			(pdf_metadata yes)
			(pdf_single_document no)
			(dxfpolygonmode yes)
			(dxfimperialunits yes)
			(dxfusepcbnewfont yes)
			(psnegative no)
			(psa4output no)
			(plot_black_and_white yes)
			(sketchpadsonfab no)
			(plotpadnumbers no)
			(hidednponfab no)
			(sketchdnponfab yes)
			(crossoutdnponfab yes)
			(subtractmaskfromsilk no)
			(outputformat 1)
			(mirror no)
			(drillshape 1)
			(scaleselection 1)
			(outputdirectory "")
		)
	)
	(net 0 "")
	(net 1 "/FPGA Supply/XCVR_VREF")
	(net 2 "+1V1")
	(net 3 "Net-(U7-AVIN)")
	(net 4 "/Bottom Connector/PCIE.CLK_N")
	(net 5 "/Bottom Connector/PCIE.CLK_P")
	(net 6 "unconnected-(J1-Pad20)")
	(net 7 "unconnected-(J1-Pad21)")
	(net 8 "GPIO26")
	(net 9 "MSS_REFCLK_N")
	(net 10 "MSS_REFCLK_P")
	(net 11 "GPIO16")
	(net 12 "GPIO6")
	(net 13 "/Ethernet/X_I")
	(net 14 "Net-(C111-Pad1)")
	(net 15 "/Bottom Connector/CONN.D_N")
	(net 16 "/Bottom Connector/CONN.D_P")
	(net 17 "GPIO7")
	(net 18 "GPIO11")
	(net 19 "/Bottom Connector/PCIE.TXD0_P")
	(net 20 "SPI6_SCLK{slash}RPI_GPIO21")
	(net 21 "GPIO25")
	(net 22 "GPIO10")
	(net 23 "GPIO24")
	(net 24 "SPI6_MISO{slash}RPI_GPIO19")
	(net 25 "SPI6_MOSI{slash}RPI_GPIO20")
	(net 26 "GPIO27")
	(net 27 "UART5_TX{slash}RPI_GPIO13")
	(net 28 "GPIO17")
	(net 29 "UART5_TX{slash}RPI_GPIO12")
	(net 30 "UART3_RX{slash}RPI_GPIO05")
	(net 31 "UART4_TX{slash}RPI_GPIO08")
	(net 32 "UART4_RX{slash}RPI_GPIO09")
	(net 33 "/Bottom Connector/PCIE.TXD0_N")
	(net 34 "Net-(J1-Pad43)")
	(net 35 "/Bottom Connector/PCIE.TXD1_P")
	(net 36 "/Bottom Connector/PCIE.TXD1_N")
	(net 37 "/Bottom Connector/PCIE.TXD2_P")
	(net 38 "/Bottom Connector/PCIE.TXD2_N")
	(net 39 "/Bottom Connector/PCIE.TXD3_P")
	(net 40 "/Bottom Connector/PCIE.TXD3_N")
	(net 41 "/Ethernet/SGMII.RX0_N")
	(net 42 "/Ethernet/SGMII.RX0_P")
	(net 43 "/Ethernet/SGMII.TX0_P")
	(net 44 "SD_PWR_ON")
	(net 45 "unconnected-(J1-Pad76)")
	(net 46 "/PCIe/XCVR_TX1_N")
	(net 47 "+1V05")
	(net 48 "+1V8")
	(net 49 "VDDAUX")
	(net 50 "+3V3")
	(net 51 "/PCIe/XCVR_TX1_P")
	(net 52 "/Memory/eMMC_VDDI")
	(net 53 "/PCIe/XCVR_TX0_N")
	(net 54 "unconnected-(J1-Pad92)")
	(net 55 "unconnected-(J1-Pad93)")
	(net 56 "unconnected-(J1-Pad94)")
	(net 57 "/HDMI/PI3HDX_C_TX2_P")
	(net 58 "unconnected-(J1-Pad96)")
	(net 59 "unconnected-(J1-Pad97)")
	(net 60 "/FPGA GPIO/HDMI_FPGA.TX2_N")
	(net 61 "unconnected-(J1-Pad100)")
	(net 62 "USB_OTG_ID")
	(net 63 "SDA6{slash}RPI_GPIO22")
	(net 64 "/PCIe/XCVR_TX0_P")
	(net 65 "unconnected-(J4-Pad4)")
	(net 66 "/PCIe/XCVR_TX3_N")
	(net 67 "unconnected-(J4-Pad6)")
	(net 68 "/Ethernet/SGMII.TX0_N")
	(net 69 "unconnected-(J4-Pad11)")
	(net 70 "/Ethernet/ETH.TXRX_D_P")
	(net 71 "/Ethernet/ETH.TXRX_B_P")
	(net 72 "/Ethernet/ETH.TXRX_D_N")
	(net 73 "/Ethernet/ETH.TXRX_B_N")
	(net 74 "/Ethernet/ETH.TXRX_C_N")
	(net 75 "/Ethernet/ETH.TXRX_A_N")
	(net 76 "/Ethernet/ETH.TXRX_C_P")
	(net 77 "/Ethernet/ETH.TXRX_A_P")
	(net 78 "/Ethernet/ETH.LED2")
	(net 79 "/Ethernet/ETH.SYNC_IN")
	(net 80 "/Ethernet/ETH.LED1")
	(net 81 "/Ethernet/ETH.SYNC_OUT")
	(net 82 "/FPGA GPIO/HDMI_FPGA.TX2_P")
	(net 83 "/FPGA GPIO/HDMI_FPGA.TX1_N")
	(net 84 "/FPGA GPIO/HDMI_FPGA.TX1_P")
	(net 85 "/FPGA MSSIO/PF_BT.TX")
	(net 86 "/FPGA GPIO/HDMI_FPGA.TX0_N")
	(net 87 "/FPGA GPIO/HDMI_FPGA.TX0_P")
	(net 88 "/FPGA GPIO/HDMI_FPGA.CLK_N")
	(net 89 "/FPGA GPIO/HDMI_FPGA.CLK_P")
	(net 90 "+5V")
	(net 91 "/PCIe/XCVR_TX3_P")
	(net 92 "/FPGA MSSIO/SUPPLY.SCL")
	(net 93 "/PCIe/XCVR_TX2_N")
	(net 94 "/FPGA MSSIO/ID.SCL")
	(net 95 "/PCIe/XCVR_TX2_P")
	(net 96 "+1V2")
	(net 97 "HDMI0_HOTPLUG")
	(net 98 "/Top Connector/PI_LED_nPWR")
	(net 99 "/Bottom Connector/CAM1.D0_N")
	(net 100 "/FPGA MSSIO/SUPPLY.SDA")
	(net 101 "/FPGA MSSIO/ID.SDA")
	(net 102 "/Bottom Connector/PCIE.RXD0_P")
	(net 103 "2V5_CL")
	(net 104 "/Bottom Connector/CAM1.D0_P")
	(net 105 "/Bottom Connector/PCIE.RXD0_N")
	(net 106 "/Bottom Connector/CAM1.D1_N")
	(net 107 "/Bottom Connector/CAM1.D1_P")
	(net 108 "/Bottom Connector/CAM1.C_N")
	(net 109 "/Bottom Connector/CAM0.D0_N")
	(net 110 "/Bottom Connector/CAM1.C_P")
	(net 111 "/Bottom Connector/CAM0.D0_P")
	(net 112 "/Bottom Connector/CAM1.D2_N")
	(net 113 "/Bottom Connector/CAM0.D1_N")
	(net 114 "/Bottom Connector/CAM1.D2_P")
	(net 115 "/Bottom Connector/CAM0.D1_P")
	(net 116 "/Bottom Connector/CAM1.D3_N")
	(net 117 "/FPGA MSSIO/PF_BT.RX")
	(net 118 "/Bottom Connector/CAM0.C_N")
	(net 119 "/Bottom Connector/CAM1.D3_P")
	(net 120 "/Bottom Connector/CAM0.C_P")
	(net 121 "/Bottom Connector/PCIE.RXD1_P")
	(net 122 "/USB/WL_BT.D_N")
	(net 123 "JTAG_TMS")
	(net 124 "JTAG_TCK")
	(net 125 "JTAG_TDO")
	(net 126 "JTAG_TDI")
	(net 127 "JTAG_RESET_n")
	(net 128 "/FPGA GPIO/WiFi.DAT3")
	(net 129 "/FPGA GPIO/WiFi.CLK")
	(net 130 "/FPGA HSIO/Crosslink_B2.D6")
	(net 131 "/FPGA HSIO/Crosslink_B2.D2")
	(net 132 "SCL6{slash}RPI_GPIO23")
	(net 133 "SPI6_CEO_N{slash}RPI_GPIO18")
	(net 134 "UART0_RX{slash}RPI_GPIO15")
	(net 135 "UART3_TX{slash}RPI_GPIO04")
	(net 136 "/FPGA HSIO/Crosslink_B2.D5")
	(net 137 "SD_VDD")
	(net 138 "/Bottom Connector/PCIE.RXD1_N")
	(net 139 "/Bottom Connector/PCIE.RXD2_N")
	(net 140 "/Bottom Connector/PCIE.RXD2_P")
	(net 141 "/Bottom Connector/PCIE.RXD3_P")
	(net 142 "/Bottom Connector/PCIE.RXD3_N")
	(net 143 "/Bottom Connector/HDMI0.TX2_P")
	(net 144 "/Bottom Connector/HDMI0.TX2_N")
	(net 145 "/FPGA HSIO/Crosslink_B2.D9")
	(net 146 "/Bottom Connector/DSI1.D0_N")
	(net 147 "/Bottom Connector/HDMI0.TX1_P")
	(net 148 "/Supply/1V05_VCC")
	(net 149 "/Supply/1V05_BS")
	(net 150 "/Supply/1V05_SW")
	(net 151 "Net-(U26A-VIN_LDO)")
	(net 152 "/USB/VDDIO")
	(net 153 "/USB/VDD33")
	(net 154 "/FPGA HSIO/Crosslink_B2.D4")
	(net 155 "unconnected-(J4-Pad51)")
	(net 156 "/Bottom Connector/DSI1.D0_P")
	(net 157 "/Bottom Connector/HDMI0.TX1_N")
	(net 158 "/Bottom Connector/DSI1.D1_N")
	(net 159 "/Bottom Connector/HDMI0.TX0_P")
	(net 160 "/Bottom Connector/DSI1.D1_P")
	(net 161 "/Bottom Connector/HDMI0.TX0_N")
	(net 162 "/Bottom Connector/DSI1.C_N")
	(net 163 "/Bottom Connector/HDMI0.CLK_P")
	(net 164 "/Ethernet/SGMII_SI_P")
	(net 165 "/Ethernet/SGMII_CO_N")
	(net 166 "/Ethernet/SGMII_SO_N")
	(net 167 "/Ethernet/SGMII_SI_N")
	(net 168 "Net-(U7-SW1)")
	(net 169 "/Ethernet/SGMII_CO_P")
	(net 170 "/Ethernet/SGMII_SO_P")
	(net 171 "WL_REG_ON")
	(net 172 "BT_REG_ON")
	(net 173 "UART0_TX{slash}RPI_GPIO14")
	(net 174 "SCL1{slash}RPI_GPIO03")
	(net 175 "Net-(U7-SW2)")
	(net 176 "/MIPI CrossLink/CL_VCC")
	(net 177 "SDA1{slash}RPI_GPIO02")
	(net 178 "Net-(J3-Pad1)")
	(net 179 "Net-(U28-PLLFILT)")
	(net 180 "/MIPI CrossLink/CL_VCCGPLL")
	(net 181 "Net-(U7-SW3)")
	(net 182 "Net-(U28-CRFILT)")
	(net 183 "/MIPI CrossLink/CL_VCCIO0")
	(net 184 "Net-(U7-SW4)")
	(net 185 "/MIPI CrossLink/CL_VCCIO1")
	(net 186 "/Supply/PR")
	(net 187 "/Supply/PWRON")
	(net 188 "Net-(R9-Pad1)")
	(net 189 "Net-(U1D-TDO)")
	(net 190 "/USB/WL_BT.D_P")
	(net 191 "/MIPI CrossLink/CL_VCCIO2")
	(net 192 "PF_TDO")
	(net 193 "/FPGA MSSIO/BT_UART_TX")
	(net 194 "/FPGA MSSIO/BT_UART_RX")
	(net 195 "/Bottom Connector/DSI1.C_P")
	(net 196 "/Bottom Connector/HDMI0.CLK_N")
	(net 197 "/Bottom Connector/DSI1.D2_N")
	(net 198 "/Bottom Connector/DSI1.D3_N")
	(net 199 "/Bottom Connector/DSI1.D2_P")
	(net 200 "PCIe_CLK_nREQ")
	(net 201 "/Bottom Connector/DSI1.D3_P")
	(net 202 "PCIe_nRST")
	(net 203 "/MIPI CrossLink/CL_VCCA_DPHY0")
	(net 204 "/MIPI CrossLink/CL_VCCPLL_DPHY0")
	(net 205 "/MIPI CrossLink/CL_VCCA_DPHY1")
	(net 206 "/Bottom Connector/HDMI0.SDA")
	(net 207 "/FPGA MSSIO/EMMC.DAT3")
	(net 208 "/FPGA MSSIO/EMMC.DAT0")
	(net 209 "/Supply/SENSE1_P")
	(net 210 "/FPGA HSIO/Crosslink_B2.D3")
	(net 211 "/MIPI CrossLink/CL_VCCPLL_DPHY1")
	(net 212 "GLOBAL_EN")
	(net 213 "/FPGA MSSIO/EMMC.DAT5")
	(net 214 "/FPGA MSSIO/EMMC.DAT7")
	(net 215 "/FPGA MSSIO/MEM.DAT7")
	(net 216 "/FPGA MSSIO/MEM.DAT5")
	(net 217 "ETH_PWDN_n")
	(net 218 "/Bottom Connector/HDMI0.SCL")
	(net 219 "unconnected-(U1B-GPIO184NB1-PadF13)")
	(net 220 "Net-(U26A-SR_VLX)")
	(net 221 "VBUS")
	(net 222 "Net-(U11-RBIAS)")
	(net 223 "/FPGA HSIO/Crosslink_B2.D0")
	(net 224 "/FPGA GPIO/USER_LED_B")
	(net 225 "/FPGA GPIO/WiFi.DAT2")
	(net 226 "/FPGA GPIO/WiFi.DAT1")
	(net 227 "Net-(U11-GTX_CLK)")
	(net 228 "/Supply/1V05_SS")
	(net 229 "unconnected-(U7-LSWO-Pad24)")
	(net 230 "~{PG}")
	(net 231 "/FPGA GPIO/WiFi.CMD")
	(net 232 "Net-(U26A-WL_ANT)")
	(net 233 "unconnected-(U28-NC-Pad6)")
	(net 234 "unconnected-(U28-PWR_{PRT1}-Pad7)")
	(net 235 "/FPGA MSSIO/MEM.DAT0")
	(net 236 "/FPGA MSSIO/MEM.DAT3")
	(net 237 "1V8_CL")
	(net 238 "unconnected-(J4-Pad69)")
	(net 239 "unconnected-(U28-OSC_{N1}-Pad8)")
	(net 240 "/FPGA GPIO/WiFi.DAT0")
	(net 241 "unconnected-(J4-Pad71)")
	(net 242 "unconnected-(U28-PWR_{PRT2}-Pad11)")
	(net 243 "/FPGA MSSIO/EMMC.DAT1")
	(net 244 "unconnected-(U28-OSC_{N2}-Pad12)")
	(net 245 "Net-(J1-Pad50)")
	(net 246 "SD_VDD_OVERRIDE")
	(net 247 "unconnected-(U28-XTAL_{OUT}-Pad21)")
	(net 248 "/FPGA MSSIO/EMMC.DAT2")
	(net 249 "/FPGA MSSIO/EMMC.DAT6")
	(net 250 "/FPGA MSSIO/EMMC.DAT4")
	(net 251 "/FPGA MSSIO/MEM.DAT4")
	(net 252 "/FPGA MSSIO/MEM.DAT6")
	(net 253 "ETH_RESET_n")
	(net 254 "Net-(U1D-FF_EXIT_N)")
	(net 255 "Net-(U1D-IO_CFG_INTF)")
	(net 256 "Net-(U1D-SPI_EN)")
	(net 257 "WL_BT_TDO")
	(net 258 "Net-(U3-W#{slash}DQ2)")
	(net 259 "Net-(U3-HOLD#{slash}DQ3)")
	(net 260 "Net-(U6-ADDRSEL)")
	(net 261 "/FPGA MSSIO/MEM.DAT2")
	(net 262 "/FPGA MSSIO/MEM.DAT1")
	(net 263 "Net-(U6-~{PWRDN})")
	(net 264 "/FPGA MSSIO/EMMC.CLK")
	(net 265 "/FPGA MSSIO/MEM.CLK")
	(net 266 "/FPGA MSSIO/SD.DAT3")
	(net 267 "/FPGA MSSIO/SD.DAT0")
	(net 268 "/FPGA MSSIO/SD.DAT5")
	(net 269 "/FPGA MSSIO/SD.DAT7")
	(net 270 "Net-(U1G-MSS_DDR_VREF_IN)")
	(net 271 "Net-(U12A-ZQ0)")
	(net 272 "/Supply/SENSE3_P")
	(net 273 "/FPGA MSSIO/SD.DAT1")
	(net 274 "/FPGA MSSIO/SD.DAT2")
	(net 275 "Net-(Q3-REF)")
	(net 276 "/FPGA MSSIO/SD.DAT6")
	(net 277 "/FPGA MSSIO/SD.DAT4")
	(net 278 "/FPGA MSSIO/SD.CLK")
	(net 279 "Net-(U13-CLKOUT)")
	(net 280 "Net-(U13-RBIAS)")
	(net 281 "Net-(U26A-USB2_RREF)")
	(net 282 "/Ethernet/ETH_RXCTRL")
	(net 283 "/FPGA GPIO/PI3HDX511F.SCL")
	(net 284 "unconnected-(U1C-MSSIO28B2-PadD3)")
	(net 285 "Net-(U1C-MSSIO35B2)")
	(net 286 "/FPGA Config/Flash.CLK")
	(net 287 "/FPGA Config/Flash.MOSI")
	(net 288 "/FPGA Config/Flash.CS")
	(net 289 "~{Crosslink_RESET}")
	(net 290 "/FPGA Config/Flash.MISO")
	(net 291 "/FPGA HSIO/Crosslink_B1.D9")
	(net 292 "/FPGA HSIO/Crosslink_B1.D8")
	(net 293 "/FPGA HSIO/Crosslink_B1.D7")
	(net 294 "/FPGA HSIO/Crosslink_B2.D8")
	(net 295 "Net-(U1C-MSSIO36B2)")
	(net 296 "Net-(R10-Pad2)")
	(net 297 "Net-(U26A-BT_UART_CTS_N)")
	(net 298 "/FPGA HSIO/Crosslink_B1.D2")
	(net 299 "/FPGA HSIO/Crosslink_B1.D3")
	(net 300 "/FPGA HSIO/Crosslink_B1.D1")
	(net 301 "/FPGA MSS/MSS_CLK_P")
	(net 302 "/FPGA MSS/MSS_CLK_N")
	(net 303 "/FPGA HSIO/Crosslink_B1.D0")
	(net 304 "/FPGA HSIO/Crosslink_B2.D7")
	(net 305 "/FPGA MSS/LPDDR4.DQ3")
	(net 306 "/FPGA MSS/LPDDR4.DQS0_P")
	(net 307 "/FPGA MSS/LPDDR4.DQS0_N")
	(net 308 "/FPGA MSS/LPDDR4.DQ5")
	(net 309 "/FPGA MSS/LPDDR4.DQ11")
	(net 310 "/FPGA MSS/LPDDR4.DMI1")
	(net 311 "/FPGA MSS/LPDDR4.DQ15")
	(net 312 "/FPGA MSS/LPDDR4.DQS2_N")
	(net 313 "/FPGA MSS/LPDDR4.DQS2_P")
	(net 314 "Net-(U17-CLK1-)")
	(net 315 "Net-(U17-CLK1+)")
	(net 316 "/FPGA MSS/LPDDR4.DQ6")
	(net 317 "/USB/~{HUB_RST}")
	(net 318 "Net-(U28-SUSP_IND)")
	(net 319 "/FPGA MSS/LPDDR4.DQ7")
	(net 320 "/FPGA MSS/LPDDR4.DMI0")
	(net 321 "/FPGA MSS/LPDDR4.DQ10")
	(net 322 "/FPGA MSS/LPDDR4.DQ12")
	(net 323 "/FPGA MSS/LPDDR4.DQ13")
	(net 324 "/FPGA MSS/LPDDR4.DQ18")
	(net 325 "Net-(U28-R_{BIAS})")
	(net 326 "/FPGA MSS/LPDDR4.DQ19")
	(net 327 "/FPGA HSIO/Crosslink_B1.D4")
	(net 328 "/FPGA HSIO/Crosslink_B1.D6")
	(net 329 "/FPGA HSIO/Crosslink_B2.D1")
	(net 330 "Net-(U13-CPEN)")
	(net 331 "/FPGA HSIO/Crosslink_B2.PCLK")
	(net 332 "Net-(U16-PB49{slash}PMU_WKUPN{slash}CDONE)")
	(net 333 "GPIO_VREF")
	(net 334 "VREF_FLAG")
	(net 335 "/FPGA HSIO/Crosslink_B1.HSYNC")
	(net 336 "/FPGA HSIO/PF_CLK")
	(net 337 "/FPGA HSIO/Crosslink_B1.D5")
	(net 338 "/FPGA HSIO/Crosslink_B2.HSYNC")
	(net 339 "/FPGA HSIO/Crosslink_B1.VSYNC")
	(net 340 "/FPGA HSIO/Crosslink_B1.PCLK")
	(net 341 "/FPGA GPIO/USER_LED_G")
	(net 342 "/FPGA GPIO/USER_LED_R")
	(net 343 "/Ethernet/ETH.MDIO")
	(net 344 "/FPGA GPIO/PF_ETH_MDC")
	(net 345 "/FPGA GPIO/Crosslink.CS")
	(net 346 "/FPGA GPIO/Crosslink.MOSI")
	(net 347 "/FPGA HSIO/Crosslink_B2.VSYNC")
	(net 348 "/FPGA GPIO/HDMI0_SDA_SRC")
	(net 349 "/FPGA GPIO/PF_ETH_MDIO")
	(net 350 "/FPGA GPIO/SCL0_PF")
	(net 351 "/FPGA GPIO/WiFi_DATA_3")
	(net 352 "/FPGA GPIO/WiFi_CLK")
	(net 353 "/FPGA GPIO/HDMI0_SCL_SRC")
	(net 354 "/FPGA GPIO/WiFi_DATA_2")
	(net 355 "/FPGA GPIO/WiFi_DATA_1")
	(net 356 "/FPGA GPIO/HDMI0_HPD_SRC")
	(net 357 "unconnected-(U1C-MSSIO33B2-PadA2)")
	(net 358 "/FPGA GPIO/WiFi_CMD")
	(net 359 "unconnected-(U1B-GPIO177PB1{slash}CCC_SW_PLL0_OUT0-PadA10)")
	(net 360 "unconnected-(U1A-HSIO88PB0-PadAA12)")
	(net 361 "unconnected-(U1A-HSIO86PB0{slash}CLKIN_N_4{slash}CCC_NW_PLL0_OUT0-PadAA13)")
	(net 362 "unconnected-(U1A-HSIO85NB0-PadAA15)")
	(net 363 "unconnected-(U1A-HSIO82PB0-PadAA16)")
	(net 364 "unconnected-(U1A-HSIO81NB0{slash}DQS-PadAA17)")
	(net 365 "unconnected-(U1A-HSIO69PB0{slash}DQS{slash}CCC_NE_PLL0_OUT0-PadAA21)")
	(net 366 "unconnected-(U1A-HSIO88NB0-PadAB12)")
	(net 367 "unconnected-(U1A-HSIO86NB0-PadAB13)")
	(net 368 "unconnected-(U1A-HSIO84PB0{slash}CLKIN_N_5-PadAB14)")
	(net 369 "unconnected-(U1A-HSIO84NB0-PadAB15)")
	(net 370 "unconnected-(U1A-HSIO81PB0{slash}DQS-PadAB17)")
	(net 371 "unconnected-(U1C-MSSIO32B2-PadB2)")
	(net 372 "unconnected-(U1C-MSSIO34B2-PadB3)")
	(net 373 "unconnected-(U1B-GPIO173NB1-PadB7)")
	(net 374 "/FPGA GPIO/WiFi_DATA_0")
	(net 375 "unconnected-(U1B-GPIO171NB1-PadC7)")
	(net 376 "unconnected-(U1B-GPIO4PB1{slash}LPRB_A-PadC14)")
	(net 377 "unconnected-(U1B-GPIO4NB1{slash}LPRB_B-PadC15)")
	(net 378 "unconnected-(U1B-GPIO23PB9-PadC22)")
	(net 379 "/USB/RESETB")
	(net 380 "unconnected-(U1C-MSSIO37B2-PadD4)")
	(net 381 "unconnected-(U1B-GPIO168PB1{slash}CCC_SW_CLKIN_S_0-PadD7)")
	(net 382 "unconnected-(U1B-GPIO10NB1-PadD16)")
	(net 383 "unconnected-(U1C-MSSIO29B2-PadC2)")
	(net 384 "unconnected-(U1C-MSSIO31B2-PadE4)")
	(net 385 "Net-(D6-C_{R})")
	(net 386 "unconnected-(U1B-GPIO9PB1{slash}CLKIN_S_8{slash}CCC_SE_CLKIN_S_8{slash}CCC_SE_PLL0_OUT0-PadE15)")
	(net 387 "/FPGA MSSIO/EMMC.RST_n")
	(net 388 "/FPGA MSSIO/SD.CMD")
	(net 389 "/FPGA MSS/LPDDR4.CKE0_A")
	(net 390 "/FPGA MSSIO/EMMC.STRB")
	(net 391 "/FPGA MSSIO/EMMC.CMD")
	(net 392 "unconnected-(U1B-GPIO11PB1{slash}CLKIN_S_9{slash}CCC_SE_CLKIN_S_9-PadF17)")
	(net 393 "/FPGA MSS/LPDDR4.ODT_CA_A")
	(net 394 "/FPGA MSS/LPDDR4.RESET_n")
	(net 395 "/FPGA MSS/LPDDR4.CS0_A")
	(net 396 "unconnected-(U1B-GPIO185PB1-PadG13)")
	(net 397 "unconnected-(U1B-GPIO8PB1{slash}DQS{slash}CCC_SE_PLL0_OUT0-PadG17)")
	(net 398 "/Supply/1V05_FB")
	(net 399 "unconnected-(U1H-XCVR_0C_REFCLK_P-PadJ19)")
	(net 400 "unconnected-(U1H-XCVR_0C_REFCLK_N-PadJ20)")
	(net 401 "unconnected-(U1F-MSS_SGMII_RXP1-PadK6)")
	(net 402 "unconnected-(U1F-MSS_SGMII_RXN1-PadK7)")
	(net 403 "unconnected-(U1G-MSS_DDR_BG1-PadM2)")
	(net 404 "unconnected-(U1G-MSS_DDR_CS1-PadM3)")
	(net 405 "unconnected-(U1G-MSS_DDR_ODT1-PadM4)")
	(net 406 "/Supply/SENSE2_P")
	(net 407 "unconnected-(U1G-MSS_DDR_PARITY-PadM5)")
	(net 408 "unconnected-(U1F-MSS_SGMII_TXP1-PadM7)")
	(net 409 "/Supply/SENSE4_P")
	(net 410 "Net-(Q3-D)")
	(net 411 "Net-(Q3-BIAS)")
	(net 412 "unconnected-(U1G-MSS_DDR_BG0-PadN1)")
	(net 413 "unconnected-(U1G-MSS_DDR_CKE1-PadN2)")
	(net 414 "unconnected-(U1G-MSS_DDR_ALERT_N-PadN4)")
	(net 415 "unconnected-(U1G-MSS_DDR_ACT_N-PadN5)")
	(net 416 "unconnected-(U1F-MSS_SGMII_TXN1-PadN8)")
	(net 417 "GND")
	(net 418 "+2V5")
	(net 419 "unconnected-(U1H-XCVR_0B_REFCLK_P-PadN19)")
	(net 420 "unconnected-(U1H-XCVR_0B_REFCLK_N-PadN20)")
	(net 421 "/WiFi_Bluetooth/STRAP_0")
	(net 422 "/WiFi_Bluetooth/STRAP_1")
	(net 423 "/WiFi_Bluetooth/STRAP_2")
	(net 424 "/WiFi_Bluetooth/JTAG_SEL")
	(net 425 "unconnected-(U1G-MSS_DDR_A12-PadP1)")
	(net 426 "unconnected-(U1G-MSS_DDR_A13-PadP2)")
	(net 427 "unconnected-(U1G-MSS_DDR_A14-PadP3)")
	(net 428 "PAC1934_SLOW")
	(net 429 "unconnected-(U1G-MSS_DDR_BA0-PadP4)")
	(net 430 "/WiFi_Bluetooth/LPO_IN")
	(net 431 "unconnected-(U1G-MSS_DDR_A6-PadP6)")
	(net 432 "unconnected-(U1G-MSS_DDR_A8-PadP7)")
	(net 433 "unconnected-(U1G-MSS_DDR_A11-PadR1)")
	(net 434 "unconnected-(U1G-MSS_DDR_A15-PadR3)")
	(net 435 "unconnected-(U1G-MSS_DDR_A16-PadR4)")
	(net 436 "unconnected-(U1A-HSIO95PB0{slash}CCC_NW_CLKIN_N_0-PadR12)")
	(net 437 "unconnected-(U1G-MSS_DDR_CK1{slash}DDR_PLL0_OUT0-PadT1)")
	(net 438 "unconnected-(U1G-MSS_DDR_CK_N1-PadT2)")
	(net 439 "unconnected-(U1G-MSS_DDR_BA1-PadT3)")
	(net 440 "unconnected-(U1G-MSS_DDR_A7-PadT7)")
	(net 441 "unconnected-(U1A-HSIO94NB0-PadT12)")
	(net 442 "unconnected-(U1A-HSIO95NB0-PadT13)")
	(net 443 "unconnected-(U1A-HSIO91NB0-PadT15)")
	(net 444 "unconnected-(U1G-MSS_DDR_A10-PadU2)")
	(net 445 "unconnected-(U1G-MSS_DDR3_WE_N-PadU3)")
	(net 446 "unconnected-(U1G-MSS_DDR_A9-PadU7)")
	(net 447 "unconnected-(U1A-HSIO94PB0{slash}CCC_NW_CLKIN_N_1-PadU12)")
	(net 448 "unconnected-(U1A-HSIO93NB0{slash}DQS-PadU13)")
	(net 449 "unconnected-(U1A-HSIO93PB0{slash}DQS{slash}CCC_NW_PLL1_OUT0-PadU14)")
	(net 450 "unconnected-(U1A-HSIO91PB0{slash}CCC_NW_PLL1_OUT1-PadU15)")
	(net 451 "unconnected-(U1G-MSS_DDR_DQS_N4-PadV1)")
	(net 452 "unconnected-(U1G-MSS_DDR_DQS_P4-PadV2)")
	(net 453 "unconnected-(U1G-MSS_DDR_DM4-PadV5)")
	(net 454 "unconnected-(U1A-HSIO92NB0-PadV12)")
	(net 455 "unconnected-(U1A-HSIO90PB0{slash}CLKIN_N_3{slash}CCC_NW_CLKIN_N_3-PadV14)")
	(net 456 "unconnected-(U1A-HSIO90NB0-PadV15)")
	(net 457 "unconnected-(U1G-MSS_DDR_DQ35-PadW1)")
	(net 458 "unconnected-(U1G-MSS_DDR_DQ34-PadW2)")
	(net 459 "unconnected-(U1G-MSS_DDR_DQ33-PadW3)")
	(net 460 "unconnected-(U1G-MSS_DDR_DQ32-PadW4)")
	(net 461 "/PCIe/PF_PCIe_CLK_P")
	(net 462 "unconnected-(U1A-HSIO89PB0-PadW13)")
	(net 463 "unconnected-(U1A-HSIO87NB0{slash}DQS-PadW14)")
	(net 464 "unconnected-(U1A-HSIO83PB0-PadW16)")
	(net 465 "unconnected-(U1A-HSIO83NB0-PadW17)")
	(net 466 "unconnected-(U1A-HSIO79NB0-PadW18)")
	(net 467 "unconnected-(U1A-HSIO89NB0-PadY13)")
	(net 468 "unconnected-(U1A-HSIO87PB0{slash}DQS{slash}CCC_NW_PLL0_OUT0-PadY14)")
	(net 469 "unconnected-(U1A-HSIO85PB0{slash}CCC_NW_PLL0_OUT1-PadY15)")
	(net 470 "unconnected-(U1A-HSIO82NB0-PadY16)")
	(net 471 "unconnected-(U1A-HSIO80NB0-PadY18)")
	(net 472 "unconnected-(U1A-HSIO80PB0{slash}CLKIN_N_6-PadY19)")
	(net 473 "unconnected-(U2B-NC-PadP2)")
	(net 474 "unconnected-(U2B-NC-PadC12)")
	(net 475 "unconnected-(U2A-VSF-PadE9)")
	(net 476 "unconnected-(U2B-NC-PadM7)")
	(net 477 "unconnected-(U5-ST-Pad8)")
	(net 478 "unconnected-(U12A-DNU-PadA1)")
	(net 479 "unconnected-(U12A-DNU-PadA2)")
	(net 480 "unconnected-(U12B-NC-PadA8)")
	(net 481 "unconnected-(U12B-DNU-PadA11)")
	(net 482 "unconnected-(U12B-DNU-PadA12)")
	(net 483 "unconnected-(U12B-DNU-PadAA1)")
	(net 484 "unconnected-(U12B-DNU-PadAA12)")
	(net 485 "unconnected-(U12B-DNU-PadAB1)")
	(net 486 "unconnected-(U12B-DNU-PadAB2)")
	(net 487 "unconnected-(U12B-DNU-PadAB11)")
	(net 488 "unconnected-(U12B-DNU-PadAB12)")
	(net 489 "unconnected-(U12A-DNU-PadB1)")
	(net 490 "unconnected-(U12B-DNU-PadB12)")
	(net 491 "unconnected-(U12B-NC-PadG11)")
	(net 492 "unconnected-(U12A-NC-PadH3)")
	(net 493 "unconnected-(U12A-NC-PadK5)")
	(net 494 "unconnected-(U12A-NC-PadK8)")
	(net 495 "unconnected-(U12A-NC-PadN5)")
	(net 496 "unconnected-(U12A-NC-PadN8)")
	(net 497 "unconnected-(U12A-NC-PadR3)")
	(net 498 "/USB/USB_N")
	(net 499 "/USB/USB_P")
	(net 500 "/USB/REF_CLK")
	(net 501 "unconnected-(U16-PB16B{slash}PCLKC2_0-PadD10)")
	(net 502 "unconnected-(U16-PB34B-PadE2)")
	(net 503 "unconnected-(U16-PB12A{slash}GPLLT2_0-PadE9)")
	(net 504 "unconnected-(U16-PB12B{slash}GPLLC2_0-PadE10)")
	(net 505 "PI3HDX511F_HOTPLUG")
	(net 506 "Net-(U26A-BT_UART_RTS_N)")
	(net 507 "Net-(U26A-BT_PCM_IN)")
	(net 508 "Net-(U26A-BT_PCM_CLK)")
	(net 509 "/FPGA GPIO/SDA0_PF")
	(net 510 "/USB/USB_BYP_N")
	(net 511 "/USB/USB_BYP_P")
	(net 512 "/USB/USB_UP_N")
	(net 513 "/USB/USB_UP_P")
	(net 514 "/USB/USB_DN1_N")
	(net 515 "/USB/USB_DN1_P")
	(net 516 "Net-(R50-Pad1)")
	(net 517 "SD_VDD_FLAG")
	(net 518 "Net-(R56-Pad1)")
	(net 519 "SD_VDD_AUX")
	(net 520 "Net-(U26A-BT_PCM_SYNC)")
	(net 521 "Net-(U26A-BT_PCM_OUT)")
	(net 522 "/Supply/1V05_REG")
	(net 523 "unconnected-(U10-ST-Pad8)")
	(net 524 "Net-(U26A-BT_DEV_WAKE)")
	(net 525 "Net-(U26A-WL_HOST_WAKE)")
	(net 526 "Net-(U26A-BT_HOST_WAKE)")
	(net 527 "Net-(U26A-BT_GPIO_2)")
	(net 528 "Net-(U26A-BT_GPIO_3)")
	(net 529 "Net-(U26A-BT_GPIO_5)")
	(net 530 "Net-(U26A-GPIO_1)")
	(net 531 "unconnected-(U11-X_O-Pad14)")
	(net 532 "unconnected-(U11-CLK_OUT-Pad18)")
	(net 533 "unconnected-(U11-RX_CLK-Pad32)")
	(net 534 "unconnected-(U26A-USB2_MONCDR-Pad48)")
	(net 535 "unconnected-(U12A-NC-PadP5)")
	(net 536 "unconnected-(U12A-NC-PadJ5)")
	(net 537 "/FPGA GPIO/Crosslink.SDA")
	(net 538 "Net-(D6-C_{G})")
	(net 539 "Net-(D6-C_{B})")
	(net 540 "Net-(Q5-D)")
	(net 541 "Net-(Q7-D)")
	(net 542 "Net-(Q8-D)")
	(net 543 "/FPGA GPIO/PCIe_nRST_PF")
	(net 544 "/FPGA GPIO/PCIe_CLK_nREQ_PF")
	(net 545 "/FPGA GPIO/Crosslink.CLK")
	(net 546 "/HDMI/PI3HDX_C_TX1_P")
	(net 547 "/HDMI/PI3HDX_C_TX0_P")
	(net 548 "/HDMI/PI3HDX_C_CLK_P")
	(net 549 "/HDMI/PI3HDX_C_TX2_N")
	(net 550 "/HDMI/PI3HDX_C_TX1_N")
	(net 551 "/HDMI/PI3HDX_C_TX0_N")
	(net 552 "/HDMI/PI3HDX_C_CLK_N")
	(net 553 "/HDMI/HDMI_3V3")
	(net 554 "Net-(U15-CEXT)")
	(net 555 "Net-(U15-OC_S0)")
	(net 556 "Net-(U15-OEB)")
	(net 557 "Net-(U15-EQ_S0)")
	(net 558 "unconnected-(U1B-GPIO177NB1-PadA11)")
	(net 559 "unconnected-(U1B-GPIO178PB1{slash}CCC_SW_PLL0_OUT1-PadC11)")
	(net 560 "Net-(U11-JTAG_TDO)")
	(net 561 "unconnected-(U11-VDDA1P8-Pad13)")
	(net 562 "/PCIe/PF_PCIe_CLK_N")
	(net 563 "/FPGA GPIO/Crosslink.MISO")
	(net 564 "/FPGA GPIO/Crosslink.SCL")
	(net 565 "/FPGA GPIO/PF_ETH_PWDN_n")
	(net 566 "/FPGA GPIO/PF_ETH_RESET_n")
	(net 567 "/FPGA MSS/LPDDR4.DQ31")
	(net 568 "/FPGA MSS/LPDDR4.CA5_A")
	(net 569 "unconnected-(U17-NC-Pad2)")
	(net 570 "unconnected-(U17-NC-Pad3)")
	(net 571 "unconnected-(U17-NC-Pad5)")
	(net 572 "unconnected-(U17-NC-Pad6)")
	(net 573 "unconnected-(U17-NC-Pad7)")
	(net 574 "unconnected-(U17-NC-Pad14)")
	(net 575 "unconnected-(Y3-NC-Pad2)")
	(net 576 "Net-(U6-SENSE1+)")
	(net 577 "Net-(U6-SENSE2+)")
	(net 578 "Net-(U6-SENSE3+)")
	(net 579 "Net-(U6-SENSE4+)")
	(net 580 "unconnected-(U28-SMBDATA-Pad13)")
	(net 581 "unconnected-(U28-SMBCLK-Pad14)")
	(net 582 "unconnected-(U2B-NC-PadC3)")
	(net 583 "/FPGA MSS/LPDDR4.CA4_A")
	(net 584 "/FPGA MSS/LPDDR4.DQ30")
	(net 585 "/FPGA MSS/LPDDR4.DQ29")
	(net 586 "/FPGA MSS/LPDDR4.DQ28")
	(net 587 "/FPGA MSS/LPDDR4.CA0_A")
	(net 588 "/FPGA MSS/LPDDR4.CA1_A")
	(net 589 "/FPGA MSS/LPDDR4.DQ25")
	(net 590 "/FPGA MSS/LPDDR4.DMI3")
	(net 591 "/FPGA MSS/LPDDR4.DQ26")
	(net 592 "/FPGA MSS/LPDDR4.CK_N")
	(net 593 "/FPGA MSS/LPDDR4.CK_P")
	(net 594 "/FPGA MSS/LPDDR4.DQ24")
	(net 595 "/FPGA MSS/LPDDR4.DQS3_P")
	(net 596 "/FPGA MSS/LPDDR4.DQ27")
	(net 597 "/FPGA MSS/LPDDR4.CA3_A")
	(net 598 "/FPGA MSS/LPDDR4.CA2_A")
	(net 599 "/FPGA MSS/LPDDR4.DQS3_N")
	(net 600 "/FPGA MSS/LPDDR4.DQ21")
	(net 601 "/FPGA MSS/LPDDR4.DQ20")
	(net 602 "/FPGA MSS/LPDDR4.DQS1_N")
	(net 603 "/FPGA MSS/LPDDR4.DQ9")
	(net 604 "/FPGA MSS/LPDDR4.DQ8")
	(net 605 "/FPGA MSS/LPDDR4.DQ17")
	(net 606 "/FPGA MSS/LPDDR4.DQ23")
	(net 607 "/FPGA MSS/LPDDR4.DQ2")
	(net 608 "/FPGA MSS/LPDDR4.DQ0")
	(net 609 "/FPGA MSS/LPDDR4.DQ1")
	(net 610 "/FPGA MSS/LPDDR4.DQ4")
	(net 611 "/FPGA MSS/LPDDR4.DQS1_P")
	(net 612 "/FPGA MSS/LPDDR4.DQ14")
	(net 613 "/FPGA MSS/LPDDR4.DQ16")
	(net 614 "/FPGA MSS/LPDDR4.DMI2")
	(net 615 "/FPGA MSS/LPDDR4.DQ22")
	(net 616 "unconnected-(J1-Pad19)")
	(net 617 "/Ethernet/LED0")
	(net 618 "/Ethernet/ETH.MDC")
	(net 619 "/FPGA GPIO/I^{2}C0.SDA")
	(net 620 "Net-(U26A-RF_SW_CTRL_0)")
	(net 621 "Net-(U26A-RF_SW_CTRL_5)")
	(net 622 "/FPGA GPIO/PI3HDX511F.SDA")
	(net 623 "/FPGA GPIO/I^{2}C0.SCL")
	(net 624 "/FPGA MSSIO/MEM.STRB")
	(net 625 "/FPGA MSSIO/MEM.CMD")
	(net 626 "unconnected-(U1E-MSSIO12B4-PadH5)")
	(net 627 "unconnected-(U1E-MSSIO13B4-PadJ2)")
	(net 628 "unconnected-(R27-R1.2-Pad8)")
	(net 629 "unconnected-(R27-R1.1-Pad1)")
	(net 630 "unconnected-(R24-R4.1-Pad4)")
	(net 631 "unconnected-(R24-R4.2-Pad5)")
	(net 632 "Net-(U7-OUT2)")
	(net 633 "Net-(U7-OUT4)")
	(net 634 "Net-(U7-OUT5)")
	(net 635 "/FPGA GPIO/ULPI.RESET")
	(net 636 "/FPGA GPIO/ULPI.CLK")
	(net 637 "/FPGA GPIO/ULPI.DATA4")
	(net 638 "/FPGA GPIO/ULPI.DATA5")
	(net 639 "/FPGA GPIO/ULPI.DATA1")
	(net 640 "/FPGA GPIO/ULPI.DIR")
	(net 641 "/FPGA GPIO/ULPI.DATA0")
	(net 642 "/FPGA GPIO/ULPI.DATA7")
	(net 643 "/FPGA GPIO/ULPI.DATA3")
	(net 644 "/FPGA GPIO/ULPI.DATA6")
	(net 645 "/FPGA GPIO/ULPI.DATA2")
	(net 646 "/FPGA GPIO/ULPI.STP")
	(net 647 "/FPGA GPIO/ULPI.NXT")
	(net 648 "unconnected-(J2-Pad4)")
	(net 649 "VDD")
	(net 650 "Net-(D5-A)")
	(net 651 "unconnected-(J2-Pad7)")
	(net 652 "unconnected-(U11-VDDA1P8-Pad13)_1")
	(net 653 "unconnected-(Q3-NC-Pad1)")
	(net 654 "unconnected-(Q3-NC-Pad5)")
	(net 655 "/FPGA Config/DEVRST_N")
	(net 656 "/Supply/PG")
	(net 657 "unconnected-(U2A-RFU-PadK7)")
	(net 658 "unconnected-(U2B-NC-PadP12)")
	(net 659 "unconnected-(U2B-NC-PadC8)")
	(net 660 "unconnected-(U2B-NC-PadG2)")
	(net 661 "unconnected-(U2B-NC-PadB8)")
	(net 662 "unconnected-(U2B-NC-PadK2)")
	(net 663 "unconnected-(U2B-NC-PadA2)")
	(net 664 "unconnected-(U2B-NC-PadD2)")
	(net 665 "unconnected-(U2B-NC-PadC5)")
	(net 666 "unconnected-(U2B-NC-PadG1)")
	(net 667 "unconnected-(U2B-NC-PadM2)")
	(net 668 "unconnected-(U2B-NC-PadG12)")
	(net 669 "unconnected-(U2B-NC-PadE3)")
	(net 670 "unconnected-(U2B-NC-PadA13)")
	(net 671 "unconnected-(U2B-NC-PadB9)")
	(net 672 "unconnected-(U2B-NC-PadN1)")
	(net 673 "unconnected-(U2A-VSF-PadE10)")
	(net 674 "unconnected-(U2B-NC-PadE13)")
	(net 675 "unconnected-(U2B-NC-PadF3)")
	(net 676 "unconnected-(U2B-NC-PadH2)")
	(net 677 "unconnected-(U2B-NC-PadK1)")
	(net 678 "unconnected-(U2B-NC-PadD3)")
	(net 679 "unconnected-(U2B-NC-PadN11)")
	(net 680 "unconnected-(U2B-NC-PadH13)")
	(net 681 "unconnected-(U2B-NC-PadM11)")
	(net 682 "unconnected-(U2B-NC-PadM9)")
	(net 683 "unconnected-(U2B-NC-PadL14)")
	(net 684 "unconnected-(U2B-NC-PadB11)")
	(net 685 "unconnected-(U2B-NC-PadB7)")
	(net 686 "unconnected-(U2B-NC-PadK3)")
	(net 687 "unconnected-(U2B-NC-PadN7)")
	(net 688 "unconnected-(U2B-NC-PadB12)")
	(net 689 "unconnected-(U2B-NC-PadD12)")
	(net 690 "unconnected-(U2B-NC-PadA12)")
	(net 691 "unconnected-(U2B-NC-PadN6)")
	(net 692 "unconnected-(U2B-NC-PadB10)")
	(net 693 "unconnected-(U2B-NC-PadM13)")
	(net 694 "unconnected-(U2B-NC-PadF12)")
	(net 695 "unconnected-(U2A-RFU-PadG3)")
	(net 696 "unconnected-(U2B-NC-PadL3)")
	(net 697 "unconnected-(U2B-NC-PadP1)")
	(net 698 "unconnected-(U2B-NC-PadF2)")
	(net 699 "unconnected-(U2B-NC-PadA1)")
	(net 700 "unconnected-(U2B-NC-PadE2)")
	(net 701 "unconnected-(U2B-NC-PadD1)")
	(net 702 "unconnected-(U2B-NC-PadL2)")
	(net 703 "unconnected-(U2B-NC-PadM1)")
	(net 704 "unconnected-(U2B-NC-PadP9)")
	(net 705 "unconnected-(U2B-NC-PadB14)")
	(net 706 "unconnected-(U2B-NC-PadP8)")
	(net 707 "unconnected-(U2B-NC-PadM8)")
	(net 708 "unconnected-(U2B-NC-PadJ2)")
	(net 709 "unconnected-(U2A-RFU-PadA7)")
	(net 710 "unconnected-(U2B-NC-PadA10)")
	(net 711 "unconnected-(U2B-NC-PadG14)")
	(net 712 "unconnected-(U2A-RFU-PadK10)")
	(net 713 "unconnected-(U2B-NC-PadC1)")
	(net 714 "unconnected-(U2B-NC-PadG13)")
	(net 715 "unconnected-(U2B-NC-PadH1)")
	(net 716 "unconnected-(U2B-NC-PadA9)")
	(net 717 "unconnected-(U2B-NC-PadN13)")
	(net 718 "unconnected-(U2B-NC-PadJ14)")
	(net 719 "unconnected-(U2B-NC-PadH12)")
	(net 720 "unconnected-(U2B-NC-PadM3)")
	(net 721 "unconnected-(U2B-NC-PadN3)")
	(net 722 "unconnected-(U2B-NC-PadF14)")
	(net 723 "unconnected-(U2B-NC-PadD4)")
	(net 724 "unconnected-(U2B-NC-PadK14)")
	(net 725 "unconnected-(U2A-RFU-PadP7)")
	(net 726 "unconnected-(U2B-NC-PadL13)")
	(net 727 "unconnected-(U2B-NC-PadL1)")
	(net 728 "unconnected-(U2A-RFU-PadP10)")
	(net 729 "unconnected-(U2B-NC-PadC11)")
	(net 730 "unconnected-(U2B-NC-PadC10)")
	(net 731 "unconnected-(U2B-NC-PadH3)")
	(net 732 "unconnected-(U2B-NC-PadN14)")
	(net 733 "unconnected-(U2B-NC-PadE14)")
	(net 734 "unconnected-(U2B-NC-PadA14)")
	(net 735 "unconnected-(U2B-NC-PadN10)")
	(net 736 "unconnected-(U2A-RFU-PadG10)")
	(net 737 "unconnected-(U2B-NC-PadD13)")
	(net 738 "unconnected-(U2B-NC-PadC13)")
	(net 739 "unconnected-(U2B-NC-PadN8)")
	(net 740 "unconnected-(U2B-NC-PadN12)")
	(net 741 "unconnected-(U2B-NC-PadE1)")
	(net 742 "unconnected-(U2B-NC-PadA11)")
	(net 743 "unconnected-(U2A-RFU-PadE5)")
	(net 744 "unconnected-(U2B-NC-PadP11)")
	(net 745 "unconnected-(U2B-NC-PadE12)")
	(net 746 "unconnected-(U2B-NC-PadB1)")
	(net 747 "unconnected-(U2B-NC-PadP13)")
	(net 748 "unconnected-(U2A-RFU-PadK6)")
	(net 749 "unconnected-(U2B-NC-PadJ3)")
	(net 750 "unconnected-(U2B-NC-PadJ13)")
	(net 751 "unconnected-(U2B-NC-PadL12)")
	(net 752 "unconnected-(U2B-NC-PadP14)")
	(net 753 "unconnected-(U2A-VSF-PadF10)")
	(net 754 "unconnected-(U2B-NC-PadK13)")
	(net 755 "unconnected-(U2B-NC-PadM10)")
	(net 756 "unconnected-(U2B-NC-PadF1)")
	(net 757 "unconnected-(U2B-NC-PadJ1)")
	(net 758 "unconnected-(U2B-NC-PadA8)")
	(net 759 "unconnected-(U2B-NC-PadB13)")
	(net 760 "unconnected-(U2B-NC-PadM12)")
	(net 761 "unconnected-(U2B-NC-PadM14)")
	(net 762 "unconnected-(U2B-NC-PadC14)")
	(net 763 "unconnected-(U2B-NC-PadF13)")
	(net 764 "unconnected-(U2B-NC-PadJ12)")
	(net 765 "unconnected-(U2A-RFU-PadE8)")
	(net 766 "unconnected-(U2B-NC-PadD14)")
	(net 767 "unconnected-(U2B-NC-PadK12)")
	(net 768 "unconnected-(U2B-NC-PadH14)")
	(net 769 "unconnected-(U2B-NC-PadN9)")
	(net 770 "unconnected-(U2B-NC-PadC7)")
	(net 771 "unconnected-(U2B-NC-PadC9)")
	(footprint "antmicro-footprints:TP_SMD_0.75mm"
		(layer "F.Cu")
		(at 228.47 144.005)
		(property "Reference" "TP32"
			(at 9.76 0.755 180)
			(layer "F.SilkS")
			(hide yes)
			(effects
				(font
					(size 0.7 0.7)
					(thickness 0.15)
				)
				(justify left bottom)
			)
		)
		(property "Value" "TP_0.75mm_SMD"
			(at 0 1.2 0)
			(layer "F.Fab")
			(hide yes)
			(effects
				(font
					(size 0.7 0.7)
					(thickness 0.15)
				)
				(justify left bottom)
			)
		)
		(property "Description" "SMT test point"
			(at 0 0 0)
			(layer "F.Fab")
			(hide yes)
			(effects
				(font
					(size 1.27 1.27)
					(thickness 0.15)
				)
			)
		)
		(property "Author" "Antmicro"
			(at 0 0 0)
			(layer "F.Fab")
			(hide yes)
			(effects
				(font
					(size 1 1)
					(thickness 0.15)
				)
			)
		)
		(property "License" "Apache-2.0"
			(at 0 0 0)
			(layer "F.Fab")
			(hide yes)
			(effects
				(font
					(size 1 1)
					(thickness 0.15)
				)
			)
		)
		(property "MPN" ""
			(at 0 0 0)
			(layer "F.Fab")
			(hide yes)
			(effects
				(font
					(size 1 1)
					(thickness 0.15)
				)
			)
		)
		(property "Manufacturer" ""
			(at 0 0 0)
			(layer "F.Fab")
			(hide yes)
			(effects
				(font
					(size 1 1)
					(thickness 0.15)
				)
			)
		)
		(property "Public" "False"
			(at 0 0 0)
			(layer "F.Fab")
			(hide yes)
			(effects
				(font
					(size 1 1)
					(thickness 0.15)
				)
			)
		)
		(sheetname "/WiFi_Bluetooth/")
		(sheetfile "wifi_bt.kicad_sch")
		(attr exclude_from_pos_files exclude_from_bom)
		(fp_circle
			(center 0 0)
			(end 0.475 0)
			(stroke
				(width 0.05)
				(type default)
			)
			(fill no)
			(layer "F.CrtYd")
		)
		(fp_text user "${REFERENCE}"
			(at -0.4 2.7 0)
			(layer "F.Fab")
			(effects
				(font
					(size 0.7 0.7)
					(thickness 0.15)
				)
				(justify left bottom)
			)
		)
		(fp_text user "License: Apache-2.0"
			(at -0.4 5.101 0)
			(layer "F.Fab")
			(effects
				(font
					(size 0.7 0.7)
					(thickness 0.15)
				)
				(justify left bottom)
			)
		)
		(fp_text user "Author: Antmicro"
			(at -0.4 3.901 0)
			(layer "F.Fab")
			(effects
				(font
					(size 0.7 0.7)
					(thickness 0.15)
				)
				(justify left bottom)
			)
		)
		(pad "1" smd circle
			(at 0 0)
			(size 0.75 0.75)
			(layers "F.Cu" "F.Mask")
			(net 529 "Net-(U26A-BT_GPIO_5)")
			(pinfunction "1")
			(pintype "passive")
		)
	)
	(footprint "antmicro-footprints:C_0402_1005Metric"
		(layer "F.Cu")
		(at 192.15 120.95 90)
		(descr "Capacitor SMD 0402")
		(tags "capacitor SMD 0402")
		(property "Reference" "C132"
			(at -1.71 6.03 270)
			(layer "F.SilkS")
			(effects
				(font
					(size 0.7 0.7)
					(thickness 0.15)
				)
				(justify left bottom)
			)
		)
		(property "Value" "C_100n_0402"
			(at -1.022927 2.155213 90)
			(layer "F.Fab")
			(hide yes)
			(effects
				(font
					(size 0.7 0.7)
					(thickness 0.15)
				)
				(justify left bottom)
			)
		)
		(property "Datasheet" "https://www.murata.com/products/productdetail?partno=GRM155R61H104KE14%23"
			(at 0 0 90)
			(layer "F.Fab")
			(hide yes)
			(effects
				(font
					(size 1.27 1.27)
					(thickness 0.15)
				)
			)
		)
		(property "Description" "SMD Multilayer Ceramic Capacitor, 0.1 µF, 50 V, 0402 [1005 Metric], ± 10%, X5R, GRM Series"
			(at 0 0 90)
			(layer "F.Fab")
			(hide yes)
			(effects
				(font
					(size 1.27 1.27)
					(thickness 0.15)
				)
			)
		)
		(property "Author" "Antmicro"
			(at 313.1 -71.2 0)
			(layer "F.Fab")
			(hide yes)
			(effects
				(font
					(size 1 1)
					(thickness 0.15)
				)
			)
		)
		(property "Dielectric" "X5R"
			(at 313.1 -71.2 0)
			(layer "F.Fab")
			(hide yes)
			(effects
				(font
					(size 1 1)
					(thickness 0.15)
				)
			)
		)
		(property "License" "Apache-2.0"
			(at 313.1 -71.2 0)
			(layer "F.Fab")
			(hide yes)
			(effects
				(font
					(size 1 1)
					(thickness 0.15)
				)
			)
		)
		(property "MPN" "GRM155R61H104KE14D"
			(at 313.1 -71.2 0)
			(layer "F.Fab")
			(hide yes)
			(effects
				(font
					(size 1 1)
					(thickness 0.15)
				)
			)
		)
		(property "Manufacturer" "Murata"
			(at 313.1 -71.2 0)
			(layer "F.Fab")
			(hide yes)
			(effects
				(font
					(size 1 1)
					(thickness 0.15)
				)
			)
		)
		(property "Public" ""
			(at 313.1 -71.2 0)
			(layer "F.Fab")
			(hide yes)
			(effects
				(font
					(size 1 1)
					(thickness 0.15)
				)
			)
		)
		(property "Val" "100n"
			(at 313.1 -71.2 0)
			(layer "F.Fab")
			(hide yes)
			(effects
				(font
					(size 1 1)
					(thickness 0.15)
				)
			)
		)
		(property "Voltage" "50V"
			(at 313.1 -71.2 0)
			(layer "F.Fab")
			(hide yes)
			(effects
				(font
					(size 1 1)
					(thickness 0.15)
				)
			)
		)
		(sheetname "/FPGA GPIO/")
		(sheetfile "fpga-gpio.kicad_sch")
		(attr smd)
		(fp_rect
			(start -0.925 -0.47)
			(end 0.925 0.47)
			(stroke
				(width 0.05)
				(type default)
			)
			(fill no)
			(layer "F.CrtYd")
		)
		(fp_line
			(start 0.504 -0.25)
			(end 0.504 0.248)
			(stroke
				(width 0.15)
				(type solid)
			)
			(layer "F.Fab")
		)
		(fp_line
			(start -0.494 -0.25)
			(end 0.504 -0.25)
			(stroke
				(width 0.15)
				(type solid)
			)
			(layer "F.Fab")
		)
		(fp_line
			(start 0.504 0.248)
			(end -0.494 0.248)
			(stroke
				(width 0.15)
				(type solid)
			)
			(layer "F.Fab")
		)
		(fp_line
			(start -0.494 0.248)
			(end -0.494 -0.25)
			(stroke
				(width 0.15)
				(type solid)
			)
			(layer "F.Fab")
		)
		(fp_text user "Author: Antmicro"
			(at -0.939 3.399 90)
			(layer "F.Fab")
			(effects
				(font
					(size 0.7 0.7)
					(thickness 0.15)
				)
				(justify left bottom)
			)
		)
		(fp_text user "${REFERENCE}"
			(at -0.939 4.599 90)
			(layer "F.Fab")
			(effects
				(font
					(size 0.7 0.7)
					(thickness 0.15)
				)
				(justify left bottom)
			)
		)
		(fp_text user "License: Apache-2.0"
			(at -0.939 5.799 90)
			(layer "F.Fab")
			(effects
				(font
					(size 0.7 0.7)
					(thickness 0.15)
				)
				(justify left bottom)
			)
		)
		(pad "1" smd roundrect
			(at -0.48 0 90)
			(size 0.59 0.64)
			(layers "F.Cu" "F.Mask" "F.Paste")
			(roundrect_rratio 0.25)
			(net 649 "VDD")
			(pintype "passive")
		)
		(pad "2" smd roundrect
			(at 0.48 0 90)
			(size 0.59 0.64)
			(layers "F.Cu" "F.Mask" "F.Paste")
			(roundrect_rratio 0.25)
			(net 417 "GND")
			(pintype "passive")
		)
	)
	(footprint "antmicro-footprints:R_0402_1005Metric"
		(layer "F.Cu")
		(at 210.425 121.35 180)
		(descr "Resistor SMD 0402")
		(tags "resistor SMD 0402")
		(property "Reference" "R60"
			(at -1.215 -2.35 0)
			(layer "F.SilkS")
			(effects
				(font
					(size 0.7 0.7)
					(thickness 0.15)
				)
				(justify right bottom)
			)
		)
		(property "Value" "R_0R_0402"
			(at -1.011843 1.772047 0)
			(layer "F.Fab")
			(hide yes)
			(effects
				(font
					(size 0.7 0.7)
					(thickness 0.15)
				)
				(justify right bottom)
			)
		)
		(property "Datasheet" "https://industrial.panasonic.com/cdbs/www-data/pdf/RDA0000/AOA0000C301.pdf"
			(at 0 0 180)
			(layer "F.Fab")
			(hide yes)
			(effects
				(font
					(size 1.27 1.27)
					(thickness 0.15)
				)
			)
		)
		(property "Description" "SMD Chip Resistor, Jumper, 0 ohm, 100 mW, 0402 [1005 Metric], Thick Film, General Purpose"
			(at 0 0 180)
			(layer "F.Fab")
			(hide yes)
			(effects
				(font
					(size 1.27 1.27)
					(thickness 0.15)
				)
			)
		)
		(property "Author" "Antmicro"
			(at 420.85 242.7 0)
			(layer "F.Fab")
			(hide yes)
			(effects
				(font
					(size 1 1)
					(thickness 0.15)
				)
			)
		)
		(property "Current" "1A"
			(at 420.85 242.7 0)
			(layer "F.Fab")
			(hide yes)
			(effects
				(font
					(size 1 1)
					(thickness 0.15)
				)
			)
		)
		(property "License" "Apache-2.0"
			(at 420.85 242.7 0)
			(layer "F.Fab")
			(hide yes)
			(effects
				(font
					(size 1 1)
					(thickness 0.15)
				)
			)
		)
		(property "MPN" "ERJ2GE0R00X"
			(at 420.85 242.7 0)
			(layer "F.Fab")
			(hide yes)
			(effects
				(font
					(size 1 1)
					(thickness 0.15)
				)
			)
		)
		(property "Manufacturer" "Panasonic"
			(at 420.85 242.7 0)
			(layer "F.Fab")
			(hide yes)
			(effects
				(font
					(size 1 1)
					(thickness 0.15)
				)
			)
		)
		(property "Public" ""
			(at 420.85 242.7 0)
			(layer "F.Fab")
			(hide yes)
			(effects
				(font
					(size 1 1)
					(thickness 0.15)
				)
			)
		)
		(property "Tolerance" "~"
			(at 420.85 242.7 0)
			(layer "F.Fab")
			(hide yes)
			(effects
				(font
					(size 1 1)
					(thickness 0.15)
				)
			)
		)
		(property "Val" "0R"
			(at 420.85 242.7 0)
			(layer "F.Fab")
			(hide yes)
			(effects
				(font
					(size 1 1)
					(thickness 0.15)
				)
			)
		)
		(sheetname "/FPGA MSS/")
		(sheetfile "fpga-mss.kicad_sch")
		(attr smd)
		(fp_rect
			(start -0.925 -0.47)
			(end 0.925 0.47)
			(stroke
				(width 0.05)
				(type default)
			)
			(fill no)
			(layer "F.CrtYd")
		)
		(fp_rect
			(start -0.5 -0.25)
			(end 0.5 0.25)
			(stroke
				(width 0.15)
				(type solid)
			)
			(fill no)
			(layer "F.Fab")
		)
		(fp_text user "License: Apache-2.0"
			(at -0.95 5.169 180)
			(layer "F.Fab")
			(effects
				(font
					(size 0.7 0.7)
					(thickness 0.15)
				)
				(justify left bottom)
			)
		)
		(fp_text user "Author: Antmicro"
			(at -0.95 4.169 180)
			(layer "F.Fab")
			(effects
				(font
					(size 0.7 0.7)
					(thickness 0.15)
				)
				(justify left bottom)
			)
		)
		(fp_text user "${REFERENCE}"
			(at -0.95 3.168 180)
			(layer "F.Fab")
			(effects
				(font
					(size 0.7 0.7)
					(thickness 0.15)
				)
				(justify left bottom)
			)
		)
		(pad "1" smd roundrect
			(at -0.48 0 180)
			(size 0.59 0.64)
			(layers "F.Cu" "F.Mask" "F.Paste")
			(roundrect_rratio 0.25)
			(net 301 "/FPGA MSS/MSS_CLK_P")
			(pintype "passive")
		)
		(pad "2" smd roundrect
			(at 0.48 0 180)
			(size 0.59 0.64)
			(layers "F.Cu" "F.Mask" "F.Paste")
			(roundrect_rratio 0.25)
			(net 10 "MSS_REFCLK_P")
			(pintype "passive")
		)
	)
	(footprint "antmicro-footprints:C_0402_1005Metric"
		(layer "F.Cu")
		(at 183.734404 153.204531 180)
		(descr "Capacitor SMD 0402")
		(tags "capacitor SMD 0402")
		(property "Reference" "C89"
			(at -1.785596 1.764531 90)
			(layer "F.SilkS")
			(effects
				(font
					(size 0.7 0.7)
					(thickness 0.15)
				)
				(justify right bottom)
			)
		)
		(property "Value" "C_470n_0402"
			(at -1.022927 2.155213 0)
			(layer "F.Fab")
			(hide yes)
			(effects
				(font
					(size 0.7 0.7)
					(thickness 0.15)
				)
				(justify right bottom)
			)
		)
		(property "Datasheet" "https://product.tdk.com/en/search/capacitor/ceramic/mlcc/info?part_no=C1005X5R1E474M050BB"
			(at 0 0 180)
			(layer "F.Fab")
			(hide yes)
			(effects
				(font
					(size 1.27 1.27)
					(thickness 0.15)
				)
			)
		)
		(property "Description" "SMD Multilayer Ceramic Capacitor, 0.47 µF, 25 V, 0402 [1005 Metric], ± 20%, X5R, C"
			(at 0 0 180)
			(layer "F.Fab")
			(hide yes)
			(effects
				(font
					(size 1.27 1.27)
					(thickness 0.15)
				)
			)
		)
		(property "Author" "Antmicro"
			(at 367.468808 306.409062 0)
			(layer "F.Fab")
			(hide yes)
			(effects
				(font
					(size 1 1)
					(thickness 0.15)
				)
			)
		)
		(property "Dielectric" ""
			(at 367.468808 306.409062 0)
			(layer "F.Fab")
			(hide yes)
			(effects
				(font
					(size 1 1)
					(thickness 0.15)
				)
			)
		)
		(property "License" "Apache-2.0"
			(at 367.468808 306.409062 0)
			(layer "F.Fab")
			(hide yes)
			(effects
				(font
					(size 1 1)
					(thickness 0.15)
				)
			)
		)
		(property "MPN" "C1005X5R1E474M050BB"
			(at 367.468808 306.409062 0)
			(layer "F.Fab")
			(hide yes)
			(effects
				(font
					(size 1 1)
					(thickness 0.15)
				)
			)
		)
		(property "Manufacturer" "TDK"
			(at 367.468808 306.409062 0)
			(layer "F.Fab")
			(hide yes)
			(effects
				(font
					(size 1 1)
					(thickness 0.15)
				)
			)
		)
		(property "Public" ""
			(at 367.468808 306.409062 0)
			(layer "F.Fab")
			(hide yes)
			(effects
				(font
					(size 1 1)
					(thickness 0.15)
				)
			)
		)
		(property "Val" "470n"
			(at 367.468808 306.409062 0)
			(layer "F.Fab")
			(hide yes)
			(effects
				(font
					(size 1 1)
					(thickness 0.15)
				)
			)
		)
		(property "Voltage" ""
			(at 367.468808 306.409062 0)
			(layer "F.Fab")
			(hide yes)
			(effects
				(font
					(size 1 1)
					(thickness 0.15)
				)
			)
		)
		(sheetname "/Supply/")
		(sheetfile "supply.kicad_sch")
		(attr smd)
		(fp_rect
			(start -0.925 -0.47)
			(end 0.925 0.47)
			(stroke
				(width 0.05)
				(type default)
			)
			(fill no)
			(layer "F.CrtYd")
		)
		(fp_line
			(start 0.504 0.248)
			(end -0.494 0.248)
			(stroke
				(width 0.15)
				(type solid)
			)
			(layer "F.Fab")
		)
		(fp_line
			(start 0.504 -0.25)
			(end 0.504 0.248)
			(stroke
				(width 0.15)
				(type solid)
			)
			(layer "F.Fab")
		)
		(fp_line
			(start -0.494 0.248)
			(end -0.494 -0.25)
			(stroke
				(width 0.15)
				(type solid)
			)
			(layer "F.Fab")
		)
		(fp_line
			(start -0.494 -0.25)
			(end 0.504 -0.25)
			(stroke
				(width 0.15)
				(type solid)
			)
			(layer "F.Fab")
		)
		(fp_text user "Author: Antmicro"
			(at -0.939 3.399 180)
			(layer "F.Fab")
			(effects
				(font
					(size 0.7 0.7)
					(thickness 0.15)
				)
				(justify left bottom)
			)
		)
		(fp_text user "License: Apache-2.0"
			(at -0.939 5.799 180)
			(layer "F.Fab")
			(effects
				(font
					(size 0.7 0.7)
					(thickness 0.15)
				)
				(justify left bottom)
			)
		)
		(fp_text user "${REFERENCE}"
			(at -0.939 4.599 180)
			(layer "F.Fab")
			(effects
				(font
					(size 0.7 0.7)
					(thickness 0.15)
				)
				(justify left bottom)
			)
		)
		(pad "1" smd roundrect
			(at -0.48 0 180)
			(size 0.59 0.64)
			(layers "F.Cu" "F.Mask" "F.Paste")
			(roundrect_rratio 0.25)
			(net 417 "GND")
			(pintype "passive")
		)
		(pad "2" smd roundrect
			(at 0.48 0 180)
			(size 0.59 0.64)
			(layers "F.Cu" "F.Mask" "F.Paste")
			(roundrect_rratio 0.25)
			(net 148 "/Supply/1V05_VCC")
			(pintype "passive")
		)
	)
	(footprint "antmicro-footprints:C_Pol_EIA-B"
		(layer "F.Cu")
		(at 210.189 140.95 -90)
		(property "Reference" "C65"
			(at -2.15 1.789 90)
			(layer "F.SilkS")
			(effects
				(font
					(size 0.7 0.7)
					(thickness 0.15)
				)
				(justify right bottom)
			)
		)
		(property "Value" "C_Pol_330u_6.3V_KEMET-T520-B"
			(at 0 2.85 90)
			(layer "F.Fab")
			(hide yes)
			(effects
				(font
					(size 0.7 0.7)
					(thickness 0.15)
				)
				(justify right bottom)
			)
		)
		(property "Datasheet" "https://www.kemet.com/en/us/capacitors/product/T520B337M006ATE040.html"
			(at 0 0 90)
			(layer "F.Fab")
			(hide yes)
			(effects
				(font
					(size 1.27 1.27)
					(thickness 0.15)
				)
			)
		)
		(property "Description" "Tantalum Polymer Capacitor, KO-CAP®, 330 µF, ± 20%, 6.3 V, B, 0.04 ohm, 1411 [3528 Metric]"
			(at 0 0 90)
			(layer "F.Fab")
			(hide yes)
			(effects
				(font
					(size 1.27 1.27)
					(thickness 0.15)
				)
			)
		)
		(property "Author" "Antmicro"
			(at 69.239 351.139 0)
			(layer "F.Fab")
			(hide yes)
			(effects
				(font
					(size 1 1)
					(thickness 0.15)
				)
			)
		)
		(property "Capacitance" "330u"
			(at 69.239 351.139 0)
			(layer "F.Fab")
			(hide yes)
			(effects
				(font
					(size 1 1)
					(thickness 0.15)
				)
			)
		)
		(property "Dielectric" "template_dielectric"
			(at 69.239 351.139 0)
			(layer "F.Fab")
			(hide yes)
			(effects
				(font
					(size 1 1)
					(thickness 0.15)
				)
			)
		)
		(property "License" "Apache-2.0"
			(at 69.239 351.139 0)
			(layer "F.Fab")
			(hide yes)
			(effects
				(font
					(size 1 1)
					(thickness 0.15)
				)
			)
		)
		(property "MPN" "T520B337M006ATE040"
			(at 69.239 351.139 0)
			(layer "F.Fab")
			(hide yes)
			(effects
				(font
					(size 1 1)
					(thickness 0.15)
				)
			)
		)
		(property "Manufacturer" "KEMET"
			(at 69.239 351.139 0)
			(layer "F.Fab")
			(hide yes)
			(effects
				(font
					(size 1 1)
					(thickness 0.15)
				)
			)
		)
		(property "Public" ""
			(at 69.239 351.139 0)
			(layer "F.Fab")
			(hide yes)
			(effects
				(font
					(size 1 1)
					(thickness 0.15)
				)
			)
		)
		(property "Val" "330u"
			(at 69.239 351.139 0)
			(layer "F.Fab")
			(hide yes)
			(effects
				(font
					(size 1 1)
					(thickness 0.15)
				)
			)
		)
		(property "Voltage" "6.3V"
			(at 69.239 351.139 0)
			(layer "F.Fab")
			(hide yes)
			(effects
				(font
					(size 1 1)
					(thickness 0.15)
				)
			)
		)
		(sheetname "/FPGA Supply/")
		(sheetfile "fpga-supply.kicad_sch")
		(attr smd)
		(fp_line
			(start 1.8 1.6)
			(end -1.8 1.6)
			(stroke
				(width 0.15)
				(type solid)
			)
			(layer "F.SilkS")
		)
		(fp_line
			(start -1.8 1.3)
			(end -1.8 1.6)
			(stroke
				(width 0.15)
				(type solid)
			)
			(layer "F.SilkS")
		)
		(fp_line
			(start 1.8 1.3)
			(end 1.8 1.6)
			(stroke
				(width 0.15)
				(type solid)
			)
			(layer "F.SilkS")
		)
		(fp_line
			(start -1.8 -1.3)
			(end -1.8 -1.6)
			(stroke
				(width 0.15)
				(type solid)
			)
			(layer "F.SilkS")
		)
		(fp_line
			(start 1.8 -1.3)
			(end 1.8 -1.6)
			(stroke
				(width 0.15)
				(type solid)
			)
			(layer "F.SilkS")
		)
		(fp_line
			(start -2.325 -1.475)
			(end -2.325 -1.878)
			(stroke
				(width 0.15)
				(type solid)
			)
			(layer "F.SilkS")
		)
		(fp_line
			(start -1.8 -1.6)
			(end 1.8 -1.6)
			(stroke
				(width 0.15)
				(type solid)
			)
			(layer "F.SilkS")
		)
		(fp_line
			(start -2.521 -1.676)
			(end -2.123 -1.676)
			(stroke
				(width 0.15)
				(type solid)
			)
			(layer "F.SilkS")
		)
		(fp_line
			(start 1.96 1.75)
			(end -1.97 1.75)
			(stroke
				(width 0.05)
				(type solid)
			)
			(layer "F.CrtYd")
		)
		(fp_line
			(start -1.97 1.35)
			(end -1.97 1.75)
			(stroke
				(width 0.05)
				(type solid)
			)
			(layer "F.CrtYd")
		)
		(fp_line
			(start -1.97 1.35)
			(end -2.41 1.35)
			(stroke
				(width 0.05)
				(type solid)
			)
			(layer "F.CrtYd")
		)
		(fp_line
			(start 1.96 1.35)
			(end 1.96 1.75)
			(stroke
				(width 0.05)
				(type solid)
			)
			(layer "F.CrtYd")
		)
		(fp_line
			(start 2.4 1.35)
			(end 1.96 1.35)
			(stroke
				(width 0.05)
				(type solid)
			)
			(layer "F.CrtYd")
		)
		(fp_line
			(start -2.411 -1.35)
			(end -2.41 1.35)
			(stroke
				(width 0.05)
				(type solid)
			)
			(layer "F.CrtYd")
		)
		(fp_line
			(start -1.97 -1.35)
			(end -2.41 -1.35)
			(stroke
				(width 0.05)
				(type solid)
			)
			(layer "F.CrtYd")
		)
		(fp_line
			(start 2.399 -1.35)
			(end 2.4 1.35)
			(stroke
				(width 0.05)
				(type solid)
			)
			(layer "F.CrtYd")
		)
		(fp_line
			(start 2.399 -1.35)
			(end 1.959 -1.35)
			(stroke
				(width 0.05)
				(type solid)
			)
			(layer "F.CrtYd")
		)
		(fp_line
			(start -1.97 -1.75)
			(end -1.97 -1.35)
			(stroke
				(width 0.05)
				(type solid)
			)
			(layer "F.CrtYd")
		)
		(fp_line
			(start 1.959 -1.75)
			(end 1.959 -1.35)
			(stroke
				(width 0.05)
				(type solid)
			)
			(layer "F.CrtYd")
		)
		(fp_line
			(start 1.959 -1.75)
			(end -1.97 -1.75)
			(stroke
				(width 0.05)
				(type solid)
			)
			(layer "F.CrtYd")
		)
		(fp_line
			(start -1.7 1.324)
			(end -1.551 1.475)
			(stroke
				(width 0.15)
				(type solid)
			)
			(layer "F.Fab")
		)
		(fp_rect
			(start -1.72 -1.5)
			(end 1.719 1.499)
			(stroke
				(width 0.15)
				(type solid)
			)
			(fill no)
			(layer "F.Fab")
		)
		(fp_text user "${REFERENCE}"
			(at -2.665 4.45 270)
			(layer "F.Fab")
			(effects
				(font
					(size 0.7 0.7)
					(thickness 0.15)
				)
				(justify left bottom)
			)
		)
		(fp_text user "License: Apache-2.0"
			(at -2.665 5.65 270)
			(layer "F.Fab")
			(effects
				(font
					(size 0.7 0.7)
					(thickness 0.15)
				)
				(justify left bottom)
			)
		)
		(fp_text user "Author: Antmicro"
			(at -2.665 6.85 270)
			(layer "F.Fab")
			(effects
				(font
					(size 0.7 0.7)
					(thickness 0.15)
				)
				(justify left bottom)
			)
		)
		(pad "1" smd roundrect
			(at -1.551 0 270)
			(size 1.2 2.2)
			(layers "F.Cu" "F.Mask" "F.Paste")
			(roundrect_rratio 0.1)
			(net 47 "+1V05")
			(pintype "passive")
		)
		(pad "2" smd roundrect
			(at 1.55 0 270)
			(size 1.2 2.2)
			(layers "F.Cu" "F.Mask" "F.Paste")
			(roundrect_rratio 0.1)
			(net 417 "GND")
			(pintype "passive")
		)
	)
	(footprint "antmicro-footprints:TP_SMD_0.75mm"
		(layer "F.Cu")
		(at 206.3 142.85)
		(property "Reference" "TP12"
			(at 0 -0.6 0)
			(layer "F.SilkS")
			(hide yes)
			(effects
				(font
					(size 0.7 0.7)
					(thickness 0.15)
				)
				(justify left bottom)
			)
		)
		(property "Value" "TP_0.75mm_SMD"
			(at 0 1.2 0)
			(layer "F.Fab")
			(hide yes)
			(effects
				(font
					(size 0.7 0.7)
					(thickness 0.15)
				)
				(justify left bottom)
			)
		)
		(property "Description" "SMT test point"
			(at 0 0 0)
			(layer "F.Fab")
			(hide yes)
			(effects
				(font
					(size 1.27 1.27)
					(thickness 0.15)
				)
			)
		)
		(property "Author" "Antmicro"
			(at 0 0 0)
			(layer "F.Fab")
			(hide yes)
			(effects
				(font
					(size 1 1)
					(thickness 0.15)
				)
			)
		)
		(property "License" "Apache-2.0"
			(at 0 0 0)
			(layer "F.Fab")
			(hide yes)
			(effects
				(font
					(size 1 1)
					(thickness 0.15)
				)
			)
		)
		(property "MPN" ""
			(at 0 0 0)
			(layer "F.Fab")
			(hide yes)
			(effects
				(font
					(size 1 1)
					(thickness 0.15)
				)
			)
		)
		(property "Manufacturer" ""
			(at 0 0 0)
			(layer "F.Fab")
			(hide yes)
			(effects
				(font
					(size 1 1)
					(thickness 0.15)
				)
			)
		)
		(property "Public" "False"
			(at 0 0 0)
			(layer "F.Fab")
			(hide yes)
			(effects
				(font
					(size 1 1)
					(thickness 0.15)
				)
			)
		)
		(sheetname "/MIPI CrossLink/")
		(sheetfile "crosslink.kicad_sch")
		(attr exclude_from_pos_files exclude_from_bom)
		(fp_circle
			(center 0 0)
			(end 0.475 0)
			(stroke
				(width 0.05)
				(type default)
			)
			(fill no)
			(layer "F.CrtYd")
		)
		(fp_text user "License: Apache-2.0"
			(at -0.4 5.101 0)
			(layer "F.Fab")
			(effects
				(font
					(size 0.7 0.7)
					(thickness 0.15)
				)
				(justify left bottom)
			)
		)
		(fp_text user "${REFERENCE}"
			(at -0.4 2.7 0)
			(layer "F.Fab")
			(effects
				(font
					(size 0.7 0.7)
					(thickness 0.15)
				)
				(justify left bottom)
			)
		)
		(fp_text user "Author: Antmicro"
			(at -0.4 3.901 0)
			(layer "F.Fab")
			(effects
				(font
					(size 0.7 0.7)
					(thickness 0.15)
				)
				(justify left bottom)
			)
		)
		(pad "1" smd circle
			(at 0 0)
			(size 0.75 0.75)
			(layers "F.Cu" "F.Mask")
			(net 332 "Net-(U16-PB49{slash}PMU_WKUPN{slash}CDONE)")
			(pinfunction "1")
			(pintype "passive")
		)
	)
	(footprint "antmicro-footprints:TP_SMD_0.75mm"
		(layer "F.Cu")
		(at 227.2 144.64)
		(property "Reference" "TP31"
			(at 10.37 1.12 0)
			(layer "F.SilkS")
			(hide yes)
			(effects
				(font
					(size 0.7 0.7)
					(thickness 0.15)
				)
				(justify left bottom)
			)
		)
		(property "Value" "TP_0.75mm_SMD"
			(at 0 1.2 0)
			(layer "F.Fab")
			(hide yes)
			(effects
				(font
					(size 0.7 0.7)
					(thickness 0.15)
				)
				(justify left bottom)
			)
		)
		(property "Description" "SMT test point"
			(at 0 0 0)
			(layer "F.Fab")
			(hide yes)
			(effects
				(font
					(size 1.27 1.27)
					(thickness 0.15)
				)
			)
		)
		(property "Author" "Antmicro"
			(at 0 0 0)
			(layer "F.Fab")
			(hide yes)
			(effects
				(font
					(size 1 1)
					(thickness 0.15)
				)
			)
		)
		(property "License" "Apache-2.0"
			(at 0 0 0)
			(layer "F.Fab")
			(hide yes)
			(effects
				(font
					(size 1 1)
					(thickness 0.15)
				)
			)
		)
		(property "MPN" ""
			(at 0 0 0)
			(layer "F.Fab")
			(hide yes)
			(effects
				(font
					(size 1 1)
					(thickness 0.15)
				)
			)
		)
		(property "Manufacturer" ""
			(at 0 0 0)
			(layer "F.Fab")
			(hide yes)
			(effects
				(font
					(size 1 1)
					(thickness 0.15)
				)
			)
		)
		(property "Public" "False"
			(at 0 0 0)
			(layer "F.Fab")
			(hide yes)
			(effects
				(font
					(size 1 1)
					(thickness 0.15)
				)
			)
		)
		(sheetname "/WiFi_Bluetooth/")
		(sheetfile "wifi_bt.kicad_sch")
		(attr exclude_from_pos_files exclude_from_bom)
		(fp_circle
			(center 0 0)
			(end 0.475 0)
			(stroke
				(width 0.05)
				(type default)
			)
			(fill no)
			(layer "F.CrtYd")
		)
		(fp_text user "Author: Antmicro"
			(at -0.4 3.901 0)
			(layer "F.Fab")
			(effects
				(font
					(size 0.7 0.7)
					(thickness 0.15)
				)
				(justify left bottom)
			)
		)
		(fp_text user "License: Apache-2.0"
			(at -0.4 5.101 0)
			(layer "F.Fab")
			(effects
				(font
					(size 0.7 0.7)
					(thickness 0.15)
				)
				(justify left bottom)
			)
		)
		(fp_text user "${REFERENCE}"
			(at -0.4 2.7 0)
			(layer "F.Fab")
			(effects
				(font
					(size 0.7 0.7)
					(thickness 0.15)
				)
				(justify left bottom)
			)
		)
		(pad "1" smd circle
			(at 0 0)
			(size 0.75 0.75)
			(layers "F.Cu" "F.Mask")
			(net 528 "Net-(U26A-BT_GPIO_3)")
			(pinfunction "1")
			(pintype "passive")
		)
	)
	(footprint "antmicro-footprints:VQFN-48_7x7mm_P0.5mm_EP4.1x4.1mm"
		(layer "F.Cu")
		(at 216.8 120.4 180)
		(property "Reference" "U11"
			(at 4.2 -4.15 90)
			(unlocked yes)
			(layer "F.SilkS")
			(effects
				(font
					(size 0.7 0.7)
					(thickness 0.15)
				)
				(justify left bottom)
			)
		)
		(property "Value" "DP83867ISRGZR"
			(at 0 5.3 180)
			(unlocked yes)
			(layer "F.Fab")
			(hide yes)
			(effects
				(font
					(size 0.7 0.7)
					(thickness 0.15)
				)
				(justify left bottom)
			)
		)
		(property "Datasheet" "https://www.ti.com/lit/ds/symlink/dp83867is.pdf?HQS=dis-dk-null-digikeymode-dsf-pf-null-wwe&ts=1704962980288&ref_url=https%253A%252F%252Fwww.ti.com%252Fgeneral%252Fdocs%252Fsuppproductinfo.tsp%253FdistId%253D10%2526gotoUrl%253Dhttps%253A%252F%252Fwww.ti.com%252Flit%252Fgpn%252Fdp83867is"
			(at 0 0 180)
			(layer "F.Fab")
			(hide yes)
			(effects
				(font
					(size 1.27 1.27)
					(thickness 0.15)
				)
			)
		)
		(property "Description" "Robust, High Immunity, Small Form Factor 10/100/1000 Ethernet, Physical Layer Transceiver, SGMII/RGMII"
			(at 0 0 180)
			(layer "F.Fab")
			(hide yes)
			(effects
				(font
					(size 1.27 1.27)
					(thickness 0.15)
				)
			)
		)
		(property "Author" "Antmicro"
			(at 433.6 240.8 0)
			(layer "F.Fab")
			(hide yes)
			(effects
				(font
					(size 1 1)
					(thickness 0.15)
				)
			)
		)
		(property "License" "Apache-2.0"
			(at 433.6 240.8 0)
			(layer "F.Fab")
			(hide yes)
			(effects
				(font
					(size 1 1)
					(thickness 0.15)
				)
			)
		)
		(property "MPN" "DP83867ISRGZR"
			(at 433.6 240.8 0)
			(layer "F.Fab")
			(hide yes)
			(effects
				(font
					(size 1 1)
					(thickness 0.15)
				)
			)
		)
		(property "Manufacturer" "Texas Instruments"
			(at 433.6 240.8 0)
			(layer "F.Fab")
			(hide yes)
			(effects
				(font
					(size 1 1)
					(thickness 0.15)
				)
			)
		)
		(property ki_fp_filters "RGZ0048B RGZ0048B_NV")
		(sheetname "/Ethernet/")
		(sheetfile "ethernet.kicad_sch")
		(attr smd)
		(fp_line
			(start 3.956 3.956)
			(end 3.956 3.218)
			(stroke
				(width 0.15)
				(type solid)
			)
			(layer "F.SilkS")
		)
		(fp_line
			(start 3.956 3.956)
			(end 3.219 3.956)
			(stroke
				(width 0.15)
				(type solid)
			)
			(layer "F.SilkS")
		)
		(fp_line
			(start 3.956 -3.218)
			(end 3.956 -3.956)
			(stroke
				(width 0.15)
				(type solid)
			)
			(layer "F.SilkS")
		)
		(fp_line
			(start 3.956 -3.956)
			(end 3.219 -3.956)
			(stroke
				(width 0.15)
				(type solid)
			)
			(layer "F.SilkS")
		)
		(fp_line
			(start -3.219 3.956)
			(end -3.956 3.956)
			(stroke
				(width 0.15)
				(type solid)
			)
			(layer "F.SilkS")
		)
		(fp_line
			(start -3.219 -3.956)
			(end -3.956 -3.956)
			(stroke
				(width 0.15)
				(type solid)
			)
			(layer "F.SilkS")
		)
		(fp_line
			(start -3.956 3.956)
			(end -3.956 3.218)
			(stroke
				(width 0.15)
				(type solid)
			)
			(layer "F.SilkS")
		)
		(fp_line
			(start -3.956 -3.218)
			(end -3.956 -3.956)
			(stroke
				(width 0.15)
				(type solid)
			)
			(layer "F.SilkS")
		)
		(fp_circle
			(center -4.18 -3.05)
			(end -4.13 -3.05)
			(stroke
				(width 0.15)
				(type solid)
			)
			(fill yes)
			(layer "F.SilkS")
		)
		(fp_rect
			(start -4.3 -4.3)
			(end 4.3 4.3)
			(stroke
				(width 0.05)
				(type solid)
			)
			(fill no)
			(layer "F.CrtYd")
		)
		(fp_line
			(start 3.575 3.575)
			(end 3.575 -3.575)
			(stroke
				(width 0.15)
				(type solid)
			)
			(layer "B.Fab")
		)
		(fp_line
			(start 3.575 3.575)
			(end -3.575 3.575)
			(stroke
				(width 0.15)
				(type solid)
			)
			(layer "B.Fab")
		)
		(fp_line
			(start 3.575 -3.575)
			(end -3.575 -3.575)
			(stroke
				(width 0.15)
				(type solid)
			)
			(layer "B.Fab")
		)
		(fp_line
			(start -3.575 3.575)
			(end -3.575 -3.575)
			(stroke
				(width 0.15)
				(type solid)
			)
			(layer "B.Fab")
		)
		(fp_line
			(start -3.575 -2.305)
			(end -2.305 -3.575)
			(stroke
				(width 0.15)
				(type solid)
			)
			(layer "B.Fab")
		)
		(fp_text user "Author: Antmicro"
			(at -5.13 7.98 180)
			(layer "F.Fab")
			(effects
				(font
					(size 0.7 0.7)
					(thickness 0.15)
				)
				(justify left bottom)
			)
		)
		(fp_text user "License: Apache-2.0"
			(at -5.13 9.18 180)
			(layer "F.Fab")
			(effects
				(font
					(size 0.7 0.7)
					(thickness 0.15)
				)
				(justify left bottom)
			)
		)
		(fp_text user "${REFERENCE}"
			(at -5.13 6.78 180)
			(layer "F.Fab")
			(effects
				(font
					(size 0.7 0.7)
					(thickness 0.15)
				)
				(justify left bottom)
			)
		)
		(pad "1" smd roundrect
			(at -3.475 -2.75 90)
			(size 0.28 0.85)
			(layers "F.Cu" "F.Mask" "F.Paste")
			(roundrect_rratio 0.1785714286)
			(net 77 "/Ethernet/ETH.TXRX_A_P")
			(pinfunction "TD_P_A")
			(pintype "bidirectional")
		)
		(pad "2" smd roundrect
			(at -3.475 -2.25 90)
			(size 0.28 0.85)
			(layers "F.Cu" "F.Mask" "F.Paste")
			(roundrect_rratio 0.1785714286)
			(net 75 "/Ethernet/ETH.TXRX_A_N")
			(pinfunction "TD_M_A")
			(pintype "bidirectional")
		)
		(pad "3" smd roundrect
			(at -3.475 -1.75 90)
			(size 0.28 0.85)
			(layers "F.Cu" "F.Mask" "F.Paste")
			(roundrect_rratio 0.1785714286)
			(net 418 "+2V5")
			(pinfunction "VDDA2P5")
			(pintype "power_in")
		)
		(pad "4" smd roundrect
			(at -3.475 -1.25 90)
			(size 0.28 0.85)
			(layers "F.Cu" "F.Mask" "F.Paste")
			(roundrect_rratio 0.1785714286)
			(net 71 "/Ethernet/ETH.TXRX_B_P")
			(pinfunction "TD_P_B")
			(pintype "bidirectional")
		)
		(pad "5" smd roundrect
			(at -3.475 -0.75 90)
			(size 0.28 0.85)
			(layers "F.Cu" "F.Mask" "F.Paste")
			(roundrect_rratio 0.1785714286)
			(net 73 "/Ethernet/ETH.TXRX_B_N")
			(pinfunction "TD_M_B")
			(pintype "bidirectional")
		)
		(pad "6" smd roundrect
			(at -3.475 -0.25 90)
			(size 0.28 0.85)
			(layers "F.Cu" "F.Mask" "F.Paste")
			(roundrect_rratio 0.1785714286)
			(net 47 "+1V05")
			(pinfunction "VDD1P0")
			(pintype "passive")
		)
		(pad "7" smd roundrect
			(at -3.475 0.25 90)
			(size 0.28 0.85)
			(layers "F.Cu" "F.Mask" "F.Paste")
			(roundrect_rratio 0.1785714286)
			(net 76 "/Ethernet/ETH.TXRX_C_P")
			(pinfunction "TD_P_C")
			(pintype "bidirectional")
		)
		(pad "8" smd roundrect
			(at -3.475 0.75 90)
			(size 0.28 0.85)
			(layers "F.Cu" "F.Mask" "F.Paste")
			(roundrect_rratio 0.1785714286)
			(net 74 "/Ethernet/ETH.TXRX_C_N")
			(pinfunction "TD_M_C")
			(pintype "bidirectional")
		)
		(pad "9" smd roundrect
			(at -3.475 1.25 90)
			(size 0.28 0.85)
			(layers "F.Cu" "F.Mask" "F.Paste")
			(roundrect_rratio 0.1785714286)
			(net 418 "+2V5")
			(pinfunction "VDDA2P5")
			(pintype "passive")
		)
		(pad "10" smd roundrect
			(at -3.475 1.75 90)
			(size 0.28 0.85)
			(layers "F.Cu" "F.Mask" "F.Paste")
			(roundrect_rratio 0.1785714286)
			(net 70 "/Ethernet/ETH.TXRX_D_P")
			(pinfunction "TD_P_D")
			(pintype "bidirectional")
		)
		(pad "11" smd roundrect
			(at -3.475 2.25 90)
			(size 0.28 0.85)
			(layers "F.Cu" "F.Mask" "F.Paste")
			(roundrect_rratio 0.1785714286)
			(net 72 "/Ethernet/ETH.TXRX_D_N")
			(pinfunction "TD_M_D")
			(pintype "bidirectional")
		)
		(pad "12" smd roundrect
			(at -3.475 2.75 90)
			(size 0.28 0.85)
			(layers "F.Cu" "F.Mask" "F.Paste")
			(roundrect_rratio 0.1785714286)
			(net 222 "Net-(U11-RBIAS)")
			(pinfunction "RBIAS")
			(pintype "passive")
		)
		(pad "13" smd roundrect
			(at -2.75 3.475)
			(size 0.28 0.85)
			(layers "F.Cu" "F.Mask" "F.Paste")
			(roundrect_rratio 0.1785714286)
			(net 561 "unconnected-(U11-VDDA1P8-Pad13)")
			(pinfunction "VDDA1P8")
			(pintype "power_in+no_connect")
		)
		(pad "14" smd roundrect
			(at -2.25 3.475)
			(size 0.28 0.85)
			(layers "F.Cu" "F.Mask" "F.Paste")
			(roundrect_rratio 0.1785714286)
			(net 531 "unconnected-(U11-X_O-Pad14)")
			(pinfunction "X_O")
			(pintype "output+no_connect")
		)
		(pad "15" smd roundrect
			(at -1.75 3.475)
			(size 0.28 0.85)
			(layers "F.Cu" "F.Mask" "F.Paste")
			(roundrect_rratio 0.1785714286)
			(net 13 "/Ethernet/X_I")
			(pinfunction "X_I")
			(pintype "input")
		)
		(pad "16" smd roundrect
			(at -1.25 3.475)
			(size 0.28 0.85)
			(layers "F.Cu" "F.Mask" "F.Paste")
			(roundrect_rratio 0.1785714286)
			(net 618 "/Ethernet/ETH.MDC")
			(pinfunction "MDC")
			(pintype "input")
		)
		(pad "17" smd roundrect
			(at -0.75 3.475)
			(size 0.28 0.85)
			(layers "F.Cu" "F.Mask" "F.Paste")
			(roundrect_rratio 0.1785714286)
			(net 343 "/Ethernet/ETH.MDIO")
			(pinfunction "MDIO")
			(pintype "bidirectional")
		)
		(pad "18" smd roundrect
			(at -0.25 3.475)
			(size 0.28 0.85)
			(layers "F.Cu" "F.Mask" "F.Paste")
			(roundrect_rratio 0.1785714286)
			(net 532 "unconnected-(U11-CLK_OUT-Pad18)")
			(pinfunction "CLK_OUT")
			(pintype "output+no_connect")
		)
		(pad "19" smd roundrect
			(at 0.25 3.475)
			(size 0.28 0.85)
			(layers "F.Cu" "F.Mask" "F.Paste")
			(roundrect_rratio 0.1785714286)
			(net 50 "+3V3")
			(pinfunction "VDDIO")
			(pintype "power_in")
		)
		(pad "20" smd roundrect
			(at 0.75 3.475)
			(size 0.28 0.85)
			(layers "F.Cu" "F.Mask" "F.Paste")
			(roundrect_rratio 0.1785714286)
			(net 124 "JTAG_TCK")
			(pinfunction "JTAG_CLK")
			(pintype "input")
		)
		(pad "21" smd roundrect
			(at 1.25 3.475)
			(size 0.28 0.85)
			(layers "F.Cu" "F.Mask" "F.Paste")
			(roundrect_rratio 0.1785714286)
			(net 560 "Net-(U11-JTAG_TDO)")
			(pinfunction "JTAG_TDO")
			(pintype "output")
		)
		(pad "22" smd roundrect
			(at 1.75 3.475)
			(size 0.28 0.85)
			(layers "F.Cu" "F.Mask" "F.Paste")
			(roundrect_rratio 0.1785714286)
			(net 123 "JTAG_TMS")
			(pinfunction "JTAG_TMS")
			(pintype "input")
		)
		(pad "23" smd roundrect
			(at 2.25 3.475)
			(size 0.28 0.85)
			(layers "F.Cu" "F.Mask" "F.Paste")
			(roundrect_rratio 0.1785714286)
			(net 257 "WL_BT_TDO")
			(pinfunction "JTAG_TDI")
			(pintype "input")
		)
		(pad "24" smd roundrect
			(at 2.75 3.475)
			(size 0.28 0.85)
			(layers "F.Cu" "F.Mask" "F.Paste")
			(roundrect_rratio 0.1785714286)
			(net 47 "+1V05")
			(pinfunction "VDD1P0")
			(pintype "power_in")
		)
		(pad "25" smd roundrect
			(at 3.475 2.75 90)
			(size 0.28 0.85)
			(layers "F.Cu" "F.Mask" "F.Paste")
			(roundrect_rratio 0.1785714286)
			(net 227 "Net-(U11-GTX_CLK)")
			(pinfunction "TX_D3")
			(pintype "input")
		)
		(pad "26" smd roundrect
			(at 3.475 2.25 90)
			(size 0.28 0.85)
			(layers "F.Cu" "F.Mask" "F.Paste")
			(roundrect_rratio 0.1785714286)
			(net 227 "Net-(U11-GTX_CLK)")
			(pinfunction "TX_D2")
			(pintype "input")
		)
		(pad "27" smd roundrect
			(at 3.475 1.75 90)
			(size 0.28 0.85)
			(layers "F.Cu" "F.Mask" "F.Paste")
			(roundrect_rratio 0.1785714286)
			(net 164 "/Ethernet/SGMII_SI_P")
			(pinfunction "TX_D1/SGMII_SIP")
			(pintype "input")
		)
		(pad "28" smd roundrect
			(at 3.475 1.25 90)
			(size 0.28 0.85)
			(layers "F.Cu" "F.Mask" "F.Paste")
			(roundrect_rratio 0.1785714286)
			(net 167 "/Ethernet/SGMII_SI_N")
			(pinfunction "TX_D0/SGMII_SIN")
			(pintype "input")
		)
		(pad "29" smd roundrect
			(at 3.475 0.75 90)
			(size 0.28 0.85)
			(layers "F.Cu" "F.Mask" "F.Paste")
			(roundrect_rratio 0.1785714286)
			(net 227 "Net-(U11-GTX_CLK)")
			(pinfunction "GTX_CLK")
			(pintype "input")
		)
		(pad "30" smd roundrect
			(at 3.475 0.25 90)
			(size 0.28 0.85)
			(layers "F.Cu" "F.Mask" "F.Paste")
			(roundrect_rratio 0.1785714286)
			(net 50 "+3V3")
			(pinfunction "VDDIO")
			(pintype "passive")
		)
		(pad "31" smd roundrect
			(at 3.475 -0.25 90)
			(size 0.28 0.85)
			(layers "F.Cu" "F.Mask" "F.Paste")
			(roundrect_rratio 0.1785714286)
			(net 47 "+1V05")
			(pinfunction "VDD1P0")
			(pintype "passive")
		)
		(pad "32" smd roundrect
			(at 3.475 -0.75 90)
			(size 0.28 0.85)
			(layers "F.Cu" "F.Mask" "F.Paste")
			(roundrect_rratio 0.1785714286)
			(net 533 "unconnected-(U11-RX_CLK-Pad32)")
			(pinfunction "RX_CLK")
			(pintype "output+no_connect")
		)
		(pad "33" smd roundrect
			(at 3.475 -1.25 90)
			(size 0.28 0.85)
			(layers "F.Cu" "F.Mask" "F.Paste")
			(roundrect_rratio 0.1785714286)
			(net 169 "/Ethernet/SGMII_CO_P")
			(pinfunction "RX_D0/SGMII_COP")
			(pintype "output")
		)
		(pad "34" smd roundrect
			(at 3.475 -1.75 90)
			(size 0.28 0.85)
			(layers "F.Cu" "F.Mask" "F.Paste")
			(roundrect_rratio 0.1785714286)
			(net 165 "/Ethernet/SGMII_CO_N")
			(pinfunction "RX_D1/SGMII_CON")
			(pintype "output")
		)
		(pad "35" smd roundrect
			(at 3.475 -2.25 90)
			(size 0.28 0.85)
			(layers "F.Cu" "F.Mask" "F.Paste")
			(roundrect_rratio 0.1785714286)
			(net 170 "/Ethernet/SGMII_SO_P")
			(pinfunction "RX_D2/SGMII_SOP")
			(pintype "output")
		)
		(pad "36" smd roundrect
			(at 3.475 -2.75 90)
			(size 0.28 0.85)
			(layers "F.Cu" "F.Mask" "F.Paste")
			(roundrect_rratio 0.1785714286)
			(net 166 "/Ethernet/SGMII_SO_N")
			(pinfunction "RX_D3/SGMII_SON")
			(pintype "output")
		)
		(pad "37" smd roundrect
			(at 2.75 -3.475)
			(size 0.28 0.85)
			(layers "F.Cu" "F.Mask" "F.Paste")
			(roundrect_rratio 0.1785714286)
			(net 227 "Net-(U11-GTX_CLK)")
			(pinfunction "TX_CTRL")
			(pintype "input")
		)
		(pad "38" smd roundrect
			(at 2.25 -3.475)
			(size 0.28 0.85)
			(layers "F.Cu" "F.Mask" "F.Paste")
			(roundrect_rratio 0.1785714286)
			(net 282 "/Ethernet/ETH_RXCTRL")
			(pinfunction "RX_CTRL")
			(pintype "output")
		)
		(pad "39" smd roundrect
			(at 1.75 -3.475)
			(size 0.28 0.85)
			(layers "F.Cu" "F.Mask" "F.Paste")
			(roundrect_rratio 0.1785714286)
			(net 79 "/Ethernet/ETH.SYNC_IN")
			(pinfunction "GPIO_0")
			(pintype "output")
		)
		(pad "40" smd roundrect
			(at 1.25 -3.475)
			(size 0.28 0.85)
			(layers "F.Cu" "F.Mask" "F.Paste")
			(roundrect_rratio 0.1785714286)
			(net 81 "/Ethernet/ETH.SYNC_OUT")
			(pinfunction "GPIO_1")
			(pintype "output")
		)
		(pad "41" smd roundrect
			(at 0.75 -3.475)
			(size 0.28 0.85)
			(layers "F.Cu" "F.Mask" "F.Paste")
			(roundrect_rratio 0.1785714286)
			(net 50 "+3V3")
			(pinfunction "VDDIO")
			(pintype "passive")
		)
		(pad "42" smd roundrect
			(at 0.25 -3.475)
			(size 0.28 0.85)
			(layers "F.Cu" "F.Mask" "F.Paste")
			(roundrect_rratio 0.1785714286)
			(net 47 "+1V05")
			(pinfunction "VDD1P0")
			(pintype "passive")
		)
		(pad "43" smd roundrect
			(at -0.25 -3.475)
			(size 0.28 0.85)
			(layers "F.Cu" "F.Mask" "F.Paste")
			(roundrect_rratio 0.1785714286)
			(net 253 "ETH_RESET_n")
			(pinfunction "~{RESET}")
			(pintype "input")
		)
		(pad "44" smd roundrect
			(at -0.75 -3.475)
			(size 0.28 0.85)
			(layers "F.Cu" "F.Mask" "F.Paste")
			(roundrect_rratio 0.1785714286)
			(net 217 "ETH_PWDN_n")
			(pinfunction "~{INT}/~{PWDN}")
			(pintype "bidirectional")
		)
		(pad "45" smd roundrect
			(at -1.25 -3.475)
			(size 0.28 0.85)
			(layers "F.Cu" "F.Mask" "F.Paste")
			(roundrect_rratio 0.1785714286)
			(net 78 "/Ethernet/ETH.LED2")
			(pinfunction "LED_2")
			(pintype "bidirectional")
		)
		(pad "46" smd roundrect
			(at -1.75 -3.475)
			(size 0.28 0.85)
			(layers "F.Cu" "F.Mask" "F.Paste")
			(roundrect_rratio 0.1785714286)
			(net 80 "/Ethernet/ETH.LED1")
			(pinfunction "LED_1")
			(pintype "bidirectional")
		)
		(pad "47" smd roundrect
			(at -2.25 -3.475)
			(size 0.28 0.85)
			(layers "F.Cu" "F.Mask" "F.Paste")
			(roundrect_rratio 0.1785714286)
			(net 617 "/Ethernet/LED0")
			(pinfunction "LED_0")
			(pintype "bidirectional")
		)
		(pad "48" smd roundrect
			(at -2.75 -3.475)
			(size 0.28 0.85)
			(layers "F.Cu" "F.Mask" "F.Paste")
			(roundrect_rratio 0.1785714286)
			(net 652 "unconnected-(U11-VDDA1P8-Pad13)_1")
			(pinfunction "VDDA1P8")
			(pintype "passive+no_connect")
		)
		(pad "49" smd roundrect
			(at 0 0 180)
			(size 4.1 4.1)
			(layers "F.Cu" "F.Mask" "F.Paste")
			(roundrect_rratio 0.01219512195)
			(net 417 "GND")
			(pinfunction "GND")
			(pintype "power_in")
			(solder_paste_margin_ratio -0.1)
		)
	)
	(footprint "antmicro-footprints:R_Array_4x0201_Panasonic_EXB18V"
		(layer "F.Cu")
		(at 196.225 121.25 -90)
		(property "Reference" "R27"
			(at 1.75 1.185 180)
			(layer "F.SilkS")
			(effects
				(font
					(size 0.7 0.7)
					(thickness 0.15)
				)
				(justify left bottom)
			)
		)
		(property "Value" "R_4x0R_0201_array"
			(at -1.1 1.8 90)
			(layer "F.Fab")
			(hide yes)
			(effects
				(font
					(size 0.7 0.7)
					(thickness 0.15)
				)
				(justify right bottom)
			)
		)
		(property "Datasheet" "http://industrial.panasonic.com/cdbs/www-data/pdf/AOC0000/AOC0000C14.pdf"
			(at 0 0 270)
			(layer "F.Fab")
			(hide yes)
			(effects
				(font
					(size 1.27 1.27)
					(thickness 0.15)
				)
			)
		)
		(property "Description" "Zero Ohm Network Resistor, Jumper, 0201 [0603 Metric], Thick Film, Isolated, Flat, 4 Resistors"
			(at 0 0 270)
			(layer "F.Fab")
			(hide yes)
			(effects
				(font
					(size 1.27 1.27)
					(thickness 0.15)
				)
			)
		)
		(property "Author" "Antmicro"
			(at 74.975 317.475 0)
			(layer "F.Fab")
			(hide yes)
			(effects
				(font
					(size 1 1)
					(thickness 0.15)
				)
			)
		)
		(property "DNP" "DNP"
			(at 74.975 317.475 0)
			(layer "F.Fab")
			(hide yes)
			(effects
				(font
					(size 1 1)
					(thickness 0.15)
				)
			)
		)
		(property "License" "Apache-2.0"
			(at 74.975 317.475 0)
			(layer "F.Fab")
			(hide yes)
			(effects
				(font
					(size 1 1)
					(thickness 0.15)
				)
			)
		)
		(property "MPN" "EXB-18VR000X"
			(at 74.975 317.475 0)
			(layer "F.Fab")
			(hide yes)
			(effects
				(font
					(size 1 1)
					(thickness 0.15)
				)
			)
		)
		(property "Manufacturer" "Panasonic"
			(at 74.975 317.475 0)
			(layer "F.Fab")
			(hide yes)
			(effects
				(font
					(size 1 1)
					(thickness 0.15)
				)
			)
		)
		(property "Val" "4x0R_0201"
			(at 74.975 317.475 0)
			(layer "F.Fab")
			(hide yes)
			(effects
				(font
					(size 1 1)
					(thickness 0.15)
				)
			)
		)
		(sheetname "/FPGA MSSIO/")
		(sheetfile "fpga-mssio.kicad_sch")
		(attr smd dnp)
		(fp_line
			(start -0.8 -0.45)
			(end -0.8 0.45)
			(stroke
				(width 0.12)
				(type solid)
			)
			(layer "F.SilkS")
		)
		(fp_line
			(start 0.8 -0.45)
			(end 0.8 0.45)
			(stroke
				(width 0.12)
				(type solid)
			)
			(layer "F.SilkS")
		)
		(fp_rect
			(start -0.898 -0.66)
			(end 0.898 0.65)
			(stroke
				(width 0.05)
				(type solid)
			)
			(fill no)
			(layer "F.CrtYd")
		)
		(fp_text user "Author: Antmicro"
			(at -1.051 4.599 270)
			(layer "F.Fab")
			(effects
				(font
					(size 0.7 0.7)
					(thickness 0.15)
				)
				(justify left bottom)
			)
		)
		(fp_text user "License: Apache-2.0"
			(at -1.051 6 270)
			(layer "F.Fab")
			(effects
				(font
					(size 0.7 0.7)
					(thickness 0.15)
				)
				(justify left bottom)
			)
		)
		(fp_text user "${REFERENCE}"
			(at -1.051 3.2 270)
			(layer "F.Fab")
			(effects
				(font
					(size 0.7 0.7)
					(thickness 0.15)
				)
				(justify left bottom)
			)
		)
		(pad "1" smd roundrect
			(at -0.6 0.298 270)
			(size 0.2 0.4)
			(layers "F.Cu" "F.Mask" "F.Paste")
			(roundrect_rratio 0.25)
			(net 629 "unconnected-(R27-R1.1-Pad1)")
			(pinfunction "R1.1")
			(pintype "passive+no_connect")
		)
		(pad "2" smd roundrect
			(at -0.202 0.298 270)
			(size 0.2 0.4)
			(layers "F.Cu" "F.Mask" "F.Paste")
			(roundrect_rratio 0.25)
			(net 278 "/FPGA MSSIO/SD.CLK")
			(pinfunction "R2.1")
			(pintype "passive")
		)
		(pad "3" smd roundrect
			(at 0.2 0.298 270)
			(size 0.2 0.4)
			(layers "F.Cu" "F.Mask" "F.Paste")
			(roundrect_rratio 0.25)
			(net 388 "/FPGA MSSIO/SD.CMD")
			(pinfunction "R3.1")
			(pintype "passive")
		)
		(pad "4" smd roundrect
			(at 0.598 0.298 270)
			(size 0.2 0.4)
			(layers "F.Cu" "F.Mask" "F.Paste")
			(roundrect_rratio 0.25)
			(net 44 "SD_PWR_ON")
			(pinfunction "R4.1")
			(pintype "passive")
		)
		(pad "5" smd roundrect
			(at 0.598 -0.3 270)
			(size 0.2 0.4)
			(layers "F.Cu" "F.Mask" "F.Paste")
			(roundrect_rratio 0.25)
			(net 624 "/FPGA MSSIO/MEM.STRB")
			(pinfunction "R4.2")
			(pintype "passive")
		)
		(pad "6" smd roundrect
			(at 0.2 -0.3 270)
			(size 0.2 0.4)
			(layers "F.Cu" "F.Mask" "F.Paste")
			(roundrect_rratio 0.25)
			(net 625 "/FPGA MSSIO/MEM.CMD")
			(pinfunction "R3.2")
			(pintype "passive")
		)
		(pad "7" smd roundrect
			(at -0.202 -0.3 270)
			(size 0.2 0.4)
			(layers "F.Cu" "F.Mask" "F.Paste")
			(roundrect_rratio 0.25)
			(net 265 "/FPGA MSSIO/MEM.CLK")
			(pinfunction "R2.2")
			(pintype "passive")
		)
		(pad "8" smd roundrect
			(at -0.6 -0.3 270)
			(size 0.2 0.4)
			(layers "F.Cu" "F.Mask" "F.Paste")
			(roundrect_rratio 0.25)
			(net 628 "unconnected-(R27-R1.2-Pad8)")
			(pinfunction "R1.2")
			(pintype "passive+no_connect")
		)
	)
	(footprint "antmicro-footprints:TP_SMD_0.75mm"
		(layer "F.Cu")
		(at 228.47 147.815)
		(property "Reference" "TP9"
			(at 9.71 2.955 0)
			(layer "F.SilkS")
			(hide yes)
			(effects
				(font
					(size 0.7 0.7)
					(thickness 0.15)
				)
				(justify left bottom)
			)
		)
		(property "Value" "TP_0.75mm_SMD"
			(at 0 1.2 0)
			(layer "F.Fab")
			(hide yes)
			(effects
				(font
					(size 0.7 0.7)
					(thickness 0.15)
				)
				(justify left bottom)
			)
		)
		(property "Description" "SMT test point"
			(at 0 0 0)
			(layer "F.Fab")
			(hide yes)
			(effects
				(font
					(size 1.27 1.27)
					(thickness 0.15)
				)
			)
		)
		(property "Author" "Antmicro"
			(at 0 0 0)
			(layer "F.Fab")
			(hide yes)
			(effects
				(font
					(size 1 1)
					(thickness 0.15)
				)
			)
		)
		(property "License" "Apache-2.0"
			(at 0 0 0)
			(layer "F.Fab")
			(hide yes)
			(effects
				(font
					(size 1 1)
					(thickness 0.15)
				)
			)
		)
		(property "MPN" ""
			(at 0 0 0)
			(layer "F.Fab")
			(hide yes)
			(effects
				(font
					(size 1 1)
					(thickness 0.15)
				)
			)
		)
		(property "Manufacturer" ""
			(at 0 0 0)
			(layer "F.Fab")
			(hide yes)
			(effects
				(font
					(size 1 1)
					(thickness 0.15)
				)
			)
		)
		(property "Public" "False"
			(at 0 0 0)
			(layer "F.Fab")
			(hide yes)
			(effects
				(font
					(size 1 1)
					(thickness 0.15)
				)
			)
		)
		(sheetname "/WiFi_Bluetooth/")
		(sheetfile "wifi_bt.kicad_sch")
		(attr exclude_from_pos_files exclude_from_bom)
		(fp_circle
			(center 0 0)
			(end 0.475 0)
			(stroke
				(width 0.05)
				(type default)
			)
			(fill no)
			(layer "F.CrtYd")
		)
		(fp_text user "License: Apache-2.0"
			(at -0.4 5.101 0)
			(layer "F.Fab")
			(effects
				(font
					(size 0.7 0.7)
					(thickness 0.15)
				)
				(justify left bottom)
			)
		)
		(fp_text user "${REFERENCE}"
			(at -0.4 2.7 0)
			(layer "F.Fab")
			(effects
				(font
					(size 0.7 0.7)
					(thickness 0.15)
				)
				(justify left bottom)
			)
		)
		(fp_text user "Author: Antmicro"
			(at -0.4 3.901 0)
			(layer "F.Fab")
			(effects
				(font
					(size 0.7 0.7)
					(thickness 0.15)
				)
				(justify left bottom)
			)
		)
		(pad "1" smd circle
			(at 0 0)
			(size 0.75 0.75)
			(layers "F.Cu" "F.Mask")
			(net 506 "Net-(U26A-BT_UART_RTS_N)")
			(pinfunction "1")
			(pintype "passive")
		)
	)
	(footprint "antmicro-footprints:SOT-523"
		(layer "F.Cu")
		(at 190.52 119.9)
		(property "Reference" "Q2"
			(at -1.31 -0.98 0)
			(layer "F.SilkS")
			(effects
				(font
					(size 0.7 0.7)
					(thickness 0.15)
				)
				(justify left bottom)
			)
		)
		(property "Value" "DMG1012T-7"
			(at 0.1 1.824 0)
			(layer "F.Fab")
			(hide yes)
			(effects
				(font
					(size 0.7 0.7)
					(thickness 0.15)
				)
				(justify left bottom)
			)
		)
		(property "Datasheet" "https://www.diodes.com/assets/Datasheets/ds31783.pdf"
			(at 0 0 0)
			(layer "F.Fab")
			(hide yes)
			(effects
				(font
					(size 1.27 1.27)
					(thickness 0.15)
				)
			)
		)
		(property "Description" "Power MOSFET, N Channel, 20 V, 630 mA, 0.3 ohm, SOT-523, Surface Mount"
			(at 0 0 0)
			(layer "F.Fab")
			(hide yes)
			(effects
				(font
					(size 1.27 1.27)
					(thickness 0.15)
				)
			)
		)
		(property "Author" "Antmicro"
			(at 0 0 0)
			(layer "F.Fab")
			(hide yes)
			(effects
				(font
					(size 1 1)
					(thickness 0.15)
				)
			)
		)
		(property "License" "Apache-2.0"
			(at 0 0 0)
			(layer "F.Fab")
			(hide yes)
			(effects
				(font
					(size 1 1)
					(thickness 0.15)
				)
			)
		)
		(property "MPN" "DMG1012T-7"
			(at 0 0 0)
			(layer "F.Fab")
			(hide yes)
			(effects
				(font
					(size 1 1)
					(thickness 0.15)
				)
			)
		)
		(property "Manufacturer" "Diodes Incorporated"
			(at 0 0 0)
			(layer "F.Fab")
			(hide yes)
			(effects
				(font
					(size 1 1)
					(thickness 0.15)
				)
			)
		)
		(property "Public" ""
			(at 0 0 0)
			(layer "F.Fab")
			(hide yes)
			(effects
				(font
					(size 1 1)
					(thickness 0.15)
				)
			)
		)
		(sheetname "/Top Connector/")
		(sheetfile "top-connector.kicad_sch")
		(attr smd)
		(fp_line
			(start -0.927 -0.351)
			(end -0.725 -0.551)
			(stroke
				(width 0.15)
				(type solid)
			)
			(layer "F.SilkS")
		)
		(fp_line
			(start -0.927 -0.051)
			(end -0.927 -0.351)
			(stroke
				(width 0.15)
				(type solid)
			)
			(layer "F.SilkS")
		)
		(fp_line
			(start -0.725 -0.551)
			(end -0.277 -0.551)
			(stroke
				(width 0.15)
				(type solid)
			)
			(layer "F.SilkS")
		)
		(fp_line
			(start -0.277 -0.551)
			(end -0.277 -0.75)
			(stroke
				(width 0.15)
				(type solid)
			)
			(layer "F.SilkS")
		)
		(fp_circle
			(center -0.9652 0.9652)
			(end -0.9152 0.9652)
			(stroke
				(width 0.15)
				(type solid)
			)
			(fill yes)
			(layer "F.SilkS")
		)
		(fp_line
			(start -1.12 -1.16)
			(end -1.12 1.15)
			(stroke
				(width 0.05)
				(type solid)
			)
			(layer "F.CrtYd")
		)
		(fp_line
			(start -1.12 -1.16)
			(end 1.1 -1.16)
			(stroke
				(width 0.05)
				(type solid)
			)
			(layer "F.CrtYd")
		)
		(fp_line
			(start -1.12 1.15)
			(end 1.1 1.15)
			(stroke
				(width 0.05)
				(type solid)
			)
			(layer "F.CrtYd")
		)
		(fp_line
			(start 1.1 -1.16)
			(end 1.1 1.15)
			(stroke
				(width 0.05)
				(type solid)
			)
			(layer "F.CrtYd")
		)
		(fp_line
			(start -0.802 -0.276)
			(end -0.802 0.424)
			(stroke
				(width 0.15)
				(type solid)
			)
			(layer "F.Fab")
		)
		(fp_line
			(start -0.652 -0.425)
			(end -0.802 -0.276)
			(stroke
				(width 0.15)
				(type solid)
			)
			(layer "F.Fab")
		)
		(fp_line
			(start 0.8 -0.425)
			(end -0.652 -0.425)
			(stroke
				(width 0.15)
				(type solid)
			)
			(layer "F.Fab")
		)
		(fp_line
			(start 0.8 -0.425)
			(end 0.8 0.424)
			(stroke
				(width 0.15)
				(type solid)
			)
			(layer "F.Fab")
		)
		(fp_line
			(start 0.8 0.424)
			(end -0.802 0.424)
			(stroke
				(width 0.15)
				(type solid)
			)
			(layer "F.Fab")
		)
		(fp_circle
			(center -0.9652 0.9652)
			(end -0.9144 0.9652)
			(stroke
				(width 0.15)
				(type solid)
			)
			(fill no)
			(layer "F.Fab")
		)
		(fp_text user "License: Apache-2.0"
			(at -1.12 5.024 0)
			(layer "F.Fab")
			(effects
				(font
					(size 0.7 0.7)
					(thickness 0.15)
				)
				(justify left bottom)
			)
		)
		(fp_text user "Author: Antmicro"
			(at -1.12 6.224 0)
			(layer "F.Fab")
			(effects
				(font
					(size 0.7 0.7)
					(thickness 0.15)
				)
				(justify left bottom)
			)
		)
		(fp_text user "${REFERENCE}"
			(at -1.12 3.824 0)
			(layer "F.Fab")
			(effects
				(font
					(size 0.7 0.7)
					(thickness 0.15)
				)
				(justify left bottom)
			)
		)
		(pad "1" smd rect
			(at -0.5 0.65)
			(size 0.4 0.51)
			(layers "F.Cu" "F.Mask" "F.Paste")
			(net 649 "VDD")
			(pinfunction "G")
			(pintype "input")
		)
		(pad "2" smd rect
			(at 0.498 0.65)
			(size 0.4 0.51)
			(layers "F.Cu" "F.Mask" "F.Paste")
			(net 417 "GND")
			(pinfunction "S")
			(pintype "passive")
		)
		(pad "3" smd rect
			(at 0 -0.652)
			(size 0.4 0.51)
			(layers "F.Cu" "F.Mask" "F.Paste")
			(net 98 "/Top Connector/PI_LED_nPWR")
			(pinfunction "D")
			(pintype "passive")
		)
	)
	(footprint "antmicro-footprints:R_0402_1005Metric"
		(layer "F.Cu")
		(at 210.425 122.3406 180)
		(descr "Resistor SMD 0402")
		(tags "resistor SMD 0402")
		(property "Reference" "R87"
			(at -1.215 -2.3594 0)
			(layer "F.SilkS")
			(effects
				(font
					(size 0.7 0.7)
					(thickness 0.15)
				)
				(justify right bottom)
			)
		)
		(property "Value" "R_0R_0402"
			(at -1.011843 1.772047 0)
			(layer "F.Fab")
			(hide yes)
			(effects
				(font
					(size 0.7 0.7)
					(thickness 0.15)
				)
				(justify right bottom)
			)
		)
		(property "Datasheet" "https://industrial.panasonic.com/cdbs/www-data/pdf/RDA0000/AOA0000C301.pdf"
			(at 0 0 180)
			(layer "F.Fab")
			(hide yes)
			(effects
				(font
					(size 1.27 1.27)
					(thickness 0.15)
				)
			)
		)
		(property "Description" "SMD Chip Resistor, Jumper, 0 ohm, 100 mW, 0402 [1005 Metric], Thick Film, General Purpose"
			(at 0 0 180)
			(layer "F.Fab")
			(hide yes)
			(effects
				(font
					(size 1.27 1.27)
					(thickness 0.15)
				)
			)
		)
		(property "Author" "Antmicro"
			(at 420.85 244.6812 0)
			(layer "F.Fab")
			(hide yes)
			(effects
				(font
					(size 1 1)
					(thickness 0.15)
				)
			)
		)
		(property "Current" "1A"
			(at 420.85 244.6812 0)
			(layer "F.Fab")
			(hide yes)
			(effects
				(font
					(size 1 1)
					(thickness 0.15)
				)
			)
		)
		(property "License" "Apache-2.0"
			(at 420.85 244.6812 0)
			(layer "F.Fab")
			(hide yes)
			(effects
				(font
					(size 1 1)
					(thickness 0.15)
				)
			)
		)
		(property "MPN" "ERJ2GE0R00X"
			(at 420.85 244.6812 0)
			(layer "F.Fab")
			(hide yes)
			(effects
				(font
					(size 1 1)
					(thickness 0.15)
				)
			)
		)
		(property "Manufacturer" "Panasonic"
			(at 420.85 244.6812 0)
			(layer "F.Fab")
			(hide yes)
			(effects
				(font
					(size 1 1)
					(thickness 0.15)
				)
			)
		)
		(property "Public" ""
			(at 420.85 244.6812 0)
			(layer "F.Fab")
			(hide yes)
			(effects
				(font
					(size 1 1)
					(thickness 0.15)
				)
			)
		)
		(property "Tolerance" "~"
			(at 420.85 244.6812 0)
			(layer "F.Fab")
			(hide yes)
			(effects
				(font
					(size 1 1)
					(thickness 0.15)
				)
			)
		)
		(property "Val" "0R"
			(at 420.85 244.6812 0)
			(layer "F.Fab")
			(hide yes)
			(effects
				(font
					(size 1 1)
					(thickness 0.15)
				)
			)
		)
		(sheetname "/FPGA MSS/")
		(sheetfile "fpga-mss.kicad_sch")
		(attr smd)
		(fp_rect
			(start -0.925 -0.47)
			(end 0.925 0.47)
			(stroke
				(width 0.05)
				(type default)
			)
			(fill no)
			(layer "F.CrtYd")
		)
		(fp_rect
			(start -0.5 -0.25)
			(end 0.5 0.25)
			(stroke
				(width 0.15)
				(type solid)
			)
			(fill no)
			(layer "F.Fab")
		)
		(fp_text user "Author: Antmicro"
			(at -0.95 4.169 180)
			(layer "F.Fab")
			(effects
				(font
					(size 0.7 0.7)
					(thickness 0.15)
				)
				(justify left bottom)
			)
		)
		(fp_text user "License: Apache-2.0"
			(at -0.95 5.169 180)
			(layer "F.Fab")
			(effects
				(font
					(size 0.7 0.7)
					(thickness 0.15)
				)
				(justify left bottom)
			)
		)
		(fp_text user "${REFERENCE}"
			(at -0.95 3.168 180)
			(layer "F.Fab")
			(effects
				(font
					(size 0.7 0.7)
					(thickness 0.15)
				)
				(justify left bottom)
			)
		)
		(pad "1" smd roundrect
			(at -0.48 0 180)
			(size 0.59 0.64)
			(layers "F.Cu" "F.Mask" "F.Paste")
			(roundrect_rratio 0.25)
			(net 302 "/FPGA MSS/MSS_CLK_N")
			(pintype "passive")
		)
		(pad "2" smd roundrect
			(at 0.48 0 180)
			(size 0.59 0.64)
			(layers "F.Cu" "F.Mask" "F.Paste")
			(roundrect_rratio 0.25)
			(net 9 "MSS_REFCLK_N")
			(pintype "passive")
		)
	)
	(footprint "antmicro-footprints:C_0402_1005Metric"
		(layer "F.Cu")
		(at 208.07 151.68 180)
		(descr "Capacitor SMD 0402")
		(tags "capacitor SMD 0402")
		(property "Reference" "C211"
			(at -1.76 -2.47 180)
			(layer "F.SilkS")
			(effects
				(font
					(size 0.7 0.7)
					(thickness 0.15)
				)
				(justify right bottom)
			)
		)
		(property "Value" "C_100n_0402"
			(at -1.022927 2.155213 0)
			(layer "F.Fab")
			(hide yes)
			(effects
				(font
					(size 0.7 0.7)
					(thickness 0.15)
				)
				(justify right bottom)
			)
		)
		(property "Datasheet" "https://www.murata.com/products/productdetail?partno=GRM155R61H104KE14%23"
			(at 0 0 180)
			(layer "F.Fab")
			(hide yes)
			(effects
				(font
					(size 1.27 1.27)
					(thickness 0.15)
				)
			)
		)
		(property "Description" "SMD Multilayer Ceramic Capacitor, 0.1 µF, 50 V, 0402 [1005 Metric], ± 10%, X5R, GRM Series"
			(at 0 0 180)
			(layer "F.Fab")
			(hide yes)
			(effects
				(font
					(size 1.27 1.27)
					(thickness 0.15)
				)
			)
		)
		(property "Author" "Antmicro"
			(at 416.14 303.36 0)
			(layer "F.Fab")
			(hide yes)
			(effects
				(font
					(size 1 1)
					(thickness 0.15)
				)
			)
		)
		(property "Dielectric" "X5R"
			(at 416.14 303.36 0)
			(layer "F.Fab")
			(hide yes)
			(effects
				(font
					(size 1 1)
					(thickness 0.15)
				)
			)
		)
		(property "License" "Apache-2.0"
			(at 416.14 303.36 0)
			(layer "F.Fab")
			(hide yes)
			(effects
				(font
					(size 1 1)
					(thickness 0.15)
				)
			)
		)
		(property "MPN" "GRM155R61H104KE14D"
			(at 416.14 303.36 0)
			(layer "F.Fab")
			(hide yes)
			(effects
				(font
					(size 1 1)
					(thickness 0.15)
				)
			)
		)
		(property "Manufacturer" "Murata"
			(at 416.14 303.36 0)
			(layer "F.Fab")
			(hide yes)
			(effects
				(font
					(size 1 1)
					(thickness 0.15)
				)
			)
		)
		(property "Public" ""
			(at 416.14 303.36 0)
			(layer "F.Fab")
			(hide yes)
			(effects
				(font
					(size 1 1)
					(thickness 0.15)
				)
			)
		)
		(property "Val" "100n"
			(at 416.14 303.36 0)
			(layer "F.Fab")
			(hide yes)
			(effects
				(font
					(size 1 1)
					(thickness 0.15)
				)
			)
		)
		(property "Voltage" "50V"
			(at 416.14 303.36 0)
			(layer "F.Fab")
			(hide yes)
			(effects
				(font
					(size 1 1)
					(thickness 0.15)
				)
			)
		)
		(sheetname "/MIPI CrossLink/")
		(sheetfile "crosslink.kicad_sch")
		(attr smd)
		(fp_rect
			(start -0.925 -0.47)
			(end 0.925 0.47)
			(stroke
				(width 0.05)
				(type default)
			)
			(fill no)
			(layer "F.CrtYd")
		)
		(fp_line
			(start 0.504 0.248)
			(end -0.494 0.248)
			(stroke
				(width 0.15)
				(type solid)
			)
			(layer "F.Fab")
		)
		(fp_line
			(start 0.504 -0.25)
			(end 0.504 0.248)
			(stroke
				(width 0.15)
				(type solid)
			)
			(layer "F.Fab")
		)
		(fp_line
			(start -0.494 0.248)
			(end -0.494 -0.25)
			(stroke
				(width 0.15)
				(type solid)
			)
			(layer "F.Fab")
		)
		(fp_line
			(start -0.494 -0.25)
			(end 0.504 -0.25)
			(stroke
				(width 0.15)
				(type solid)
			)
			(layer "F.Fab")
		)
		(fp_text user "Author: Antmicro"
			(at -0.939 3.399 180)
			(layer "F.Fab")
			(effects
				(font
					(size 0.7 0.7)
					(thickness 0.15)
				)
				(justify left bottom)
			)
		)
		(fp_text user "${REFERENCE}"
			(at -0.939 4.599 180)
			(layer "F.Fab")
			(effects
				(font
					(size 0.7 0.7)
					(thickness 0.15)
				)
				(justify left bottom)
			)
		)
		(fp_text user "License: Apache-2.0"
			(at -0.939 5.799 180)
			(layer "F.Fab")
			(effects
				(font
					(size 0.7 0.7)
					(thickness 0.15)
				)
				(justify left bottom)
			)
		)
		(pad "1" smd roundrect
			(at -0.48 0 180)
			(size 0.59 0.64)
			(layers "F.Cu" "F.Mask" "F.Paste")
			(roundrect_rratio 0.25)
			(net 417 "GND")
			(pintype "passive")
		)
		(pad "2" smd roundrect
			(at 0.48 0 180)
			(size 0.59 0.64)
			(layers "F.Cu" "F.Mask" "F.Paste")
			(roundrect_rratio 0.25)
			(net 203 "/MIPI CrossLink/CL_VCCA_DPHY0")
			(pintype "passive")
		)
	)
	(footprint "antmicro-footprints:R_Array_4x0201_Panasonic_EXB18V"
		(layer "F.Cu")
		(at 205.593002 121.25 -90)
		(property "Reference" "R25"
			(at 1.75 1.193002 180)
			(layer "F.SilkS")
			(effects
				(font
					(size 0.7 0.7)
					(thickness 0.15)
				)
				(justify left bottom)
			)
		)
		(property "Value" "R_4x0R_0201_array"
			(at -1.1 1.8 90)
			(layer "F.Fab")
			(hide yes)
			(effects
				(font
					(size 0.7 0.7)
					(thickness 0.15)
				)
				(justify right bottom)
			)
		)
		(property "Datasheet" "http://industrial.panasonic.com/cdbs/www-data/pdf/AOC0000/AOC0000C14.pdf"
			(at 0 0 270)
			(layer "F.Fab")
			(hide yes)
			(effects
				(font
					(size 1.27 1.27)
					(thickness 0.15)
				)
			)
		)
		(property "Description" "Zero Ohm Network Resistor, Jumper, 0201 [0603 Metric], Thick Film, Isolated, Flat, 4 Resistors"
			(at 0 0 270)
			(layer "F.Fab")
			(hide yes)
			(effects
				(font
					(size 1.27 1.27)
					(thickness 0.15)
				)
			)
		)
		(property "Author" "Antmicro"
			(at 84.343002 326.843002 0)
			(layer "F.Fab")
			(hide yes)
			(effects
				(font
					(size 1 1)
					(thickness 0.15)
				)
			)
		)
		(property "DNP" "DNP"
			(at 84.343002 326.843002 0)
			(layer "F.Fab")
			(hide yes)
			(effects
				(font
					(size 1 1)
					(thickness 0.15)
				)
			)
		)
		(property "License" "Apache-2.0"
			(at 84.343002 326.843002 0)
			(layer "F.Fab")
			(hide yes)
			(effects
				(font
					(size 1 1)
					(thickness 0.15)
				)
			)
		)
		(property "MPN" "EXB-18VR000X"
			(at 84.343002 326.843002 0)
			(layer "F.Fab")
			(hide yes)
			(effects
				(font
					(size 1 1)
					(thickness 0.15)
				)
			)
		)
		(property "Manufacturer" "Panasonic"
			(at 84.343002 326.843002 0)
			(layer "F.Fab")
			(hide yes)
			(effects
				(font
					(size 1 1)
					(thickness 0.15)
				)
			)
		)
		(property "Val" "4x0R_0201"
			(at 84.343002 326.843002 0)
			(layer "F.Fab")
			(hide yes)
			(effects
				(font
					(size 1 1)
					(thickness 0.15)
				)
			)
		)
		(sheetname "/FPGA MSSIO/")
		(sheetfile "fpga-mssio.kicad_sch")
		(attr smd dnp)
		(fp_line
			(start -0.8 -0.45)
			(end -0.8 0.45)
			(stroke
				(width 0.12)
				(type solid)
			)
			(layer "F.SilkS")
		)
		(fp_line
			(start 0.8 -0.45)
			(end 0.8 0.45)
			(stroke
				(width 0.12)
				(type solid)
			)
			(layer "F.SilkS")
		)
		(fp_rect
			(start -0.898 -0.66)
			(end 0.898 0.65)
			(stroke
				(width 0.05)
				(type solid)
			)
			(fill no)
			(layer "F.CrtYd")
		)
		(fp_text user "License: Apache-2.0"
			(at -1.051 6 270)
			(layer "F.Fab")
			(effects
				(font
					(size 0.7 0.7)
					(thickness 0.15)
				)
				(justify left bottom)
			)
		)
		(fp_text user "Author: Antmicro"
			(at -1.051 4.599 270)
			(layer "F.Fab")
			(effects
				(font
					(size 0.7 0.7)
					(thickness 0.15)
				)
				(justify left bottom)
			)
		)
		(fp_text user "${REFERENCE}"
			(at -1.051 3.2 270)
			(layer "F.Fab")
			(effects
				(font
					(size 0.7 0.7)
					(thickness 0.15)
				)
				(justify left bottom)
			)
		)
		(pad "1" smd roundrect
			(at -0.6 0.298 270)
			(size 0.2 0.4)
			(layers "F.Cu" "F.Mask" "F.Paste")
			(roundrect_rratio 0.25)
			(net 266 "/FPGA MSSIO/SD.DAT3")
			(pinfunction "R1.1")
			(pintype "passive")
		)
		(pad "2" smd roundrect
			(at -0.202 0.298 270)
			(size 0.2 0.4)
			(layers "F.Cu" "F.Mask" "F.Paste")
			(roundrect_rratio 0.25)
			(net 267 "/FPGA MSSIO/SD.DAT0")
			(pinfunction "R2.1")
			(pintype "passive")
		)
		(pad "3" smd roundrect
			(at 0.2 0.298 270)
			(size 0.2 0.4)
			(layers "F.Cu" "F.Mask" "F.Paste")
			(roundrect_rratio 0.25)
			(net 268 "/FPGA MSSIO/SD.DAT5")
			(pinfunction "R3.1")
			(pintype "passive")
		)
		(pad "4" smd roundrect
			(at 0.598 0.298 270)
			(size 0.2 0.4)
			(layers "F.Cu" "F.Mask" "F.Paste")
			(roundrect_rratio 0.25)
			(net 269 "/FPGA MSSIO/SD.DAT7")
			(pinfunction "R4.1")
			(pintype "passive")
		)
		(pad "5" smd roundrect
			(at 0.598 -0.3 270)
			(size 0.2 0.4)
			(layers "F.Cu" "F.Mask" "F.Paste")
			(roundrect_rratio 0.25)
			(net 215 "/FPGA MSSIO/MEM.DAT7")
			(pinfunction "R4.2")
			(pintype "passive")
		)
		(pad "6" smd roundrect
			(at 0.2 -0.3 270)
			(size 0.2 0.4)
			(layers "F.Cu" "F.Mask" "F.Paste")
			(roundrect_rratio 0.25)
			(net 216 "/FPGA MSSIO/MEM.DAT5")
			(pinfunction "R3.2")
			(pintype "passive")
		)
		(pad "7" smd roundrect
			(at -0.202 -0.3 270)
			(size 0.2 0.4)
			(layers "F.Cu" "F.Mask" "F.Paste")
			(roundrect_rratio 0.25)
			(net 235 "/FPGA MSSIO/MEM.DAT0")
			(pinfunction "R2.2")
			(pintype "passive")
		)
		(pad "8" smd roundrect
			(at -0.6 -0.3 270)
			(size 0.2 0.4)
			(layers "F.Cu" "F.Mask" "F.Paste")
			(roundrect_rratio 0.25)
			(net 236 "/FPGA MSSIO/MEM.DAT3")
			(pinfunction "R1.2")
			(pintype "passive")
		)
	)
	(footprint "antmicro-footprints:TP_SMD_0.75mm"
		(layer "F.Cu")
		(at 217.4 145 90)
		(property "Reference" "TP10"
			(at 0 -0.6 90)
			(layer "F.SilkS")
			(hide yes)
			(effects
				(font
					(size 0.7 0.7)
					(thickness 0.15)
				)
				(justify left bottom)
			)
		)
		(property "Value" "TP_0.75mm_SMD"
			(at 0 1.2 90)
			(layer "F.Fab")
			(hide yes)
			(effects
				(font
					(size 0.7 0.7)
					(thickness 0.15)
				)
				(justify left bottom)
			)
		)
		(property "Description" "SMT test point"
			(at 0 0 90)
			(layer "F.Fab")
			(hide yes)
			(effects
				(font
					(size 1.27 1.27)
					(thickness 0.15)
				)
			)
		)
		(property "Author" "Antmicro"
			(at 362.4 -72.4 0)
			(layer "F.Fab")
			(hide yes)
			(effects
				(font
					(size 1 1)
					(thickness 0.15)
				)
			)
		)
		(property "License" "Apache-2.0"
			(at 362.4 -72.4 0)
			(layer "F.Fab")
			(hide yes)
			(effects
				(font
					(size 1 1)
					(thickness 0.15)
				)
			)
		)
		(property "MPN" ""
			(at 362.4 -72.4 0)
			(layer "F.Fab")
			(hide yes)
			(effects
				(font
					(size 1 1)
					(thickness 0.15)
				)
			)
		)
		(property "Manufacturer" ""
			(at 362.4 -72.4 0)
			(layer "F.Fab")
			(hide yes)
			(effects
				(font
					(size 1 1)
					(thickness 0.15)
				)
			)
		)
		(property "Public" "False"
			(at 362.4 -72.4 0)
			(layer "F.Fab")
			(hide yes)
			(effects
				(font
					(size 1 1)
					(thickness 0.15)
				)
			)
		)
		(sheetname "/USB/")
		(sheetfile "usb.kicad_sch")
		(attr exclude_from_pos_files exclude_from_bom)
		(fp_circle
			(center 0 0)
			(end 0.475 0)
			(stroke
				(width 0.05)
				(type default)
			)
			(fill no)
			(layer "F.CrtYd")
		)
		(fp_text user "${REFERENCE}"
			(at -0.4 2.7 90)
			(layer "F.Fab")
			(effects
				(font
					(size 0.7 0.7)
					(thickness 0.15)
				)
				(justify left bottom)
			)
		)
		(fp_text user "License: Apache-2.0"
			(at -0.4 5.101 90)
			(layer "F.Fab")
			(effects
				(font
					(size 0.7 0.7)
					(thickness 0.15)
				)
				(justify left bottom)
			)
		)
		(fp_text user "Author: Antmicro"
			(at -0.4 3.901 90)
			(layer "F.Fab")
			(effects
				(font
					(size 0.7 0.7)
					(thickness 0.15)
				)
				(justify left bottom)
			)
		)
		(pad "1" smd circle
			(at 0 0 90)
			(size 0.75 0.75)
			(layers "F.Cu" "F.Mask")
			(net 330 "Net-(U13-CPEN)")
			(pinfunction "1")
			(pintype "passive")
		)
	)
	(footprint "antmicro-footprints:C_0402_1005Metric"
		(layer "F.Cu")
		(at 178.5 138.3175 -90)
		(descr "Capacitor SMD 0402")
		(tags "capacitor SMD 0402")
		(property "Reference" "C92"
			(at -4.1175 -8.99 0)
			(layer "F.SilkS")
			(effects
				(font
					(size 0.7 0.7)
					(thickness 0.15)
				)
				(justify right bottom)
			)
		)
		(property "Value" "C_100n_0402"
			(at -1.022927 2.155213 90)
			(layer "F.Fab")
			(hide yes)
			(effects
				(font
					(size 0.7 0.7)
					(thickness 0.15)
				)
				(justify right bottom)
			)
		)
		(property "Datasheet" "https://www.murata.com/products/productdetail?partno=GRM155R61H104KE14%23"
			(at 0 0 270)
			(layer "F.Fab")
			(hide yes)
			(effects
				(font
					(size 1.27 1.27)
					(thickness 0.15)
				)
			)
		)
		(property "Description" "SMD Multilayer Ceramic Capacitor, 0.1 µF, 50 V, 0402 [1005 Metric], ± 10%, X5R, GRM Series"
			(at 0 0 270)
			(layer "F.Fab")
			(hide yes)
			(effects
				(font
					(size 1.27 1.27)
					(thickness 0.15)
				)
			)
		)
		(property "Author" "Antmicro"
			(at 40.1825 316.8175 0)
			(layer "F.Fab")
			(hide yes)
			(effects
				(font
					(size 1 1)
					(thickness 0.15)
				)
			)
		)
		(property "Dielectric" "X5R"
			(at 40.1825 316.8175 0)
			(layer "F.Fab")
			(hide yes)
			(effects
				(font
					(size 1 1)
					(thickness 0.15)
				)
			)
		)
		(property "License" "Apache-2.0"
			(at 40.1825 316.8175 0)
			(layer "F.Fab")
			(hide yes)
			(effects
				(font
					(size 1 1)
					(thickness 0.15)
				)
			)
		)
		(property "MPN" "GRM155R61H104KE14D"
			(at 40.1825 316.8175 0)
			(layer "F.Fab")
			(hide yes)
			(effects
				(font
					(size 1 1)
					(thickness 0.15)
				)
			)
		)
		(property "Manufacturer" "Murata"
			(at 40.1825 316.8175 0)
			(layer "F.Fab")
			(hide yes)
			(effects
				(font
					(size 1 1)
					(thickness 0.15)
				)
			)
		)
		(property "Public" ""
			(at 40.1825 316.8175 0)
			(layer "F.Fab")
			(hide yes)
			(effects
				(font
					(size 1 1)
					(thickness 0.15)
				)
			)
		)
		(property "Val" "100n"
			(at 40.1825 316.8175 0)
			(layer "F.Fab")
			(hide yes)
			(effects
				(font
					(size 1 1)
					(thickness 0.15)
				)
			)
		)
		(property "Voltage" "50V"
			(at 40.1825 316.8175 0)
			(layer "F.Fab")
			(hide yes)
			(effects
				(font
					(size 1 1)
					(thickness 0.15)
				)
			)
		)
		(sheetname "/Supply/")
		(sheetfile "supply.kicad_sch")
		(attr smd)
		(fp_rect
			(start -0.925 -0.47)
			(end 0.925 0.47)
			(stroke
				(width 0.05)
				(type default)
			)
			(fill no)
			(layer "F.CrtYd")
		)
		(fp_line
			(start -0.494 0.248)
			(end -0.494 -0.25)
			(stroke
				(width 0.15)
				(type solid)
			)
			(layer "F.Fab")
		)
		(fp_line
			(start 0.504 0.248)
			(end -0.494 0.248)
			(stroke
				(width 0.15)
				(type solid)
			)
			(layer "F.Fab")
		)
		(fp_line
			(start -0.494 -0.25)
			(end 0.504 -0.25)
			(stroke
				(width 0.15)
				(type solid)
			)
			(layer "F.Fab")
		)
		(fp_line
			(start 0.504 -0.25)
			(end 0.504 0.248)
			(stroke
				(width 0.15)
				(type solid)
			)
			(layer "F.Fab")
		)
		(fp_text user "Author: Antmicro"
			(at -0.939 3.399 270)
			(layer "F.Fab")
			(effects
				(font
					(size 0.7 0.7)
					(thickness 0.15)
				)
				(justify left bottom)
			)
		)
		(fp_text user "${REFERENCE}"
			(at -0.939 4.599 270)
			(layer "F.Fab")
			(effects
				(font
					(size 0.7 0.7)
					(thickness 0.15)
				)
				(justify left bottom)
			)
		)
		(fp_text user "License: Apache-2.0"
			(at -0.939 5.799 270)
			(layer "F.Fab")
			(effects
				(font
					(size 0.7 0.7)
					(thickness 0.15)
				)
				(justify left bottom)
			)
		)
		(pad "1" smd roundrect
			(at -0.48 0 270)
			(size 0.59 0.64)
			(layers "F.Cu" "F.Mask" "F.Paste")
			(roundrect_rratio 0.25)
			(net 417 "GND")
			(pintype "passive")
		)
		(pad "2" smd roundrect
			(at 0.48 0 270)
			(size 0.59 0.64)
			(layers "F.Cu" "F.Mask" "F.Paste")
			(roundrect_rratio 0.25)
			(net 3 "Net-(U7-AVIN)")
			(pintype "passive")
		)
	)
	(footprint "antmicro-footprints:L_0806_2016Metric"
		(layer "F.Cu")
		(at 183.374 144.003695 -90)
		(property "Reference" "L5"
			(at 2.656305 -0.726 180)
			(layer "F.SilkS")
			(effects
				(font
					(size 0.7 0.7)
					(thickness 0.15)
				)
				(justify right bottom)
			)
		)
		(property "Value" "L_1u5_2.8A_0806"
			(at 0 2 90)
			(layer "F.Fab")
			(hide yes)
			(effects
				(font
					(size 0.7 0.7)
					(thickness 0.15)
				)
				(justify right bottom)
			)
		)
		(property "Datasheet" "https://abracon.com/datasheets/AOTA-B201610S.pdf"
			(at 0 0 270)
			(layer "F.Fab")
			(hide yes)
			(effects
				(font
					(size 1.27 1.27)
					(thickness 0.15)
				)
			)
		)
		(property "Description" "Power Inductor (SMT), 1.5 µH, 0.074 ohm, 2.8 A, AOTA-B201610S"
			(at 0 0 270)
			(layer "F.Fab")
			(hide yes)
			(effects
				(font
					(size 1.27 1.27)
					(thickness 0.15)
				)
			)
		)
		(property "Author" "Antmicro"
			(at 39.370305 327.377695 0)
			(layer "F.Fab")
			(hide yes)
			(effects
				(font
					(size 1 1)
					(thickness 0.15)
				)
			)
		)
		(property "IMax" "2.8 A"
			(at 39.370305 327.377695 0)
			(layer "F.Fab")
			(hide yes)
			(effects
				(font
					(size 1 1)
					(thickness 0.15)
				)
			)
		)
		(property "ISat" "3.5 A"
			(at 39.370305 327.377695 0)
			(layer "F.Fab")
			(hide yes)
			(effects
				(font
					(size 1 1)
					(thickness 0.15)
				)
			)
		)
		(property "License" "Apache-2.0"
			(at 39.370305 327.377695 0)
			(layer "F.Fab")
			(hide yes)
			(effects
				(font
					(size 1 1)
					(thickness 0.15)
				)
			)
		)
		(property "MPN" "AOTA-B201610S1R5MT"
			(at 39.370305 327.377695 0)
			(layer "F.Fab")
			(hide yes)
			(effects
				(font
					(size 1 1)
					(thickness 0.15)
				)
			)
		)
		(property "Manufacturer" "Abracon"
			(at 39.370305 327.377695 0)
			(layer "F.Fab")
			(hide yes)
			(effects
				(font
					(size 1 1)
					(thickness 0.15)
				)
			)
		)
		(property "Public" ""
			(at 39.370305 327.377695 0)
			(layer "F.Fab")
			(hide yes)
			(effects
				(font
					(size 1 1)
					(thickness 0.15)
				)
			)
		)
		(property "Size" "2.0x1.6"
			(at 39.370305 327.377695 0)
			(layer "F.Fab")
			(hide yes)
			(effects
				(font
					(size 1 1)
					(thickness 0.15)
				)
			)
		)
		(property "Val" "1.5u/2.8A"
			(at 39.370305 327.377695 0)
			(layer "F.Fab")
			(hide yes)
			(effects
				(font
					(size 1 1)
					(thickness 0.15)
				)
			)
		)
		(sheetname "/Supply/")
		(sheetfile "supply.kicad_sch")
		(attr smd)
		(fp_line
			(start -0.301 0.9)
			(end 0.299 0.9)
			(stroke
				(width 0.15)
				(type solid)
			)
			(layer "F.SilkS")
		)
		(fp_line
			(start -0.3 -0.9)
			(end 0.298 -0.9)
			(stroke
				(width 0.15)
				(type solid)
			)
			(layer "F.SilkS")
		)
		(fp_rect
			(start -1.75 -1.05)
			(end 1.75 1.05)
			(stroke
				(width 0.05)
				(type solid)
			)
			(fill no)
			(layer "F.CrtYd")
		)
		(fp_rect
			(start -0.951 -0.882)
			(end 0.949 0.875)
			(stroke
				(width 0.15)
				(type solid)
			)
			(fill no)
			(layer "F.Fab")
		)
		(fp_text user "${REFERENCE}"
			(at -1.9 3.1 270)
			(layer "F.Fab")
			(effects
				(font
					(size 0.7 0.7)
					(thickness 0.15)
				)
				(justify left bottom)
			)
		)
		(fp_text user "Author: Antmicro"
			(at -1.9 4.4 270)
			(layer "F.Fab")
			(effects
				(font
					(size 0.7 0.7)
					(thickness 0.15)
				)
				(justify left bottom)
			)
		)
		(fp_text user "License: Apache-2.0"
			(at -1.9 5.75 270)
			(layer "F.Fab")
			(effects
				(font
					(size 0.7 0.7)
					(thickness 0.15)
				)
				(justify left bottom)
			)
		)
		(pad "1" smd roundrect
			(at -1.1 -0.001 270)
			(size 1 1.8)
			(layers "F.Cu" "F.Mask" "F.Paste")
			(roundrect_rratio 0.15)
			(net 184 "Net-(U7-SW4)")
			(pintype "passive")
		)
		(pad "2" smd roundrect
			(at 1.1 -0.001 270)
			(size 1 1.8)
			(layers "F.Cu" "F.Mask" "F.Paste")
			(roundrect_rratio 0.15)
			(net 409 "/Supply/SENSE4_P")
			(pintype "passive")
		)
	)
	(footprint "antmicro-footprints:MP_NPTH_Drill2.7mm"
		(locked yes)
		(layer "F.Cu")
		(at 226.017 119.336)
		(property "Reference" "MP4"
			(at 0 -1.8 0)
			(layer "F.SilkS")
			(hide yes)
			(effects
				(font
					(size 0.7 0.7)
					(thickness 0.15)
				)
				(justify left bottom)
			)
		)
		(property "Value" "MP_NPTH_Drill2.7mm"
			(at 0 2.3 0)
			(layer "F.Fab")
			(hide yes)
			(effects
				(font
					(size 0.7 0.7)
					(thickness 0.15)
				)
				(justify left bottom)
			)
		)
		(property "Description" "Mechanical part"
			(at 0 0 0)
			(layer "F.Fab")
			(hide yes)
			(effects
				(font
					(size 1.27 1.27)
					(thickness 0.15)
				)
			)
		)
		(property "Author" "Antmicro"
			(at 0 0 0)
			(layer "F.Fab")
			(hide yes)
			(effects
				(font
					(size 1 1)
					(thickness 0.15)
				)
			)
		)
		(property "License" "Apache-2.0"
			(at 0 0 0)
			(layer "F.Fab")
			(hide yes)
			(effects
				(font
					(size 1 1)
					(thickness 0.15)
				)
			)
		)
		(property "exclude_from_bom" ""
			(at 0 0 0)
			(layer "F.Fab")
			(hide yes)
			(effects
				(font
					(size 1 1)
					(thickness 0.15)
				)
			)
		)
		(sheetfile "polarfire-som.kicad_sch")
		(attr board_only exclude_from_pos_files exclude_from_bom)
		(fp_circle
			(center 0 0)
			(end 1.45 0)
			(stroke
				(width 0.05)
				(type default)
			)
			(fill no)
			(layer "F.CrtYd")
		)
		(fp_text user "Author: Antmicro"
			(at 0 5.95 0)
			(layer "F.Fab")
			(effects
				(font
					(size 0.7 0.7)
					(thickness 0.15)
				)
				(justify left bottom)
			)
		)
		(fp_text user "${REFERENCE}"
			(at 0 4.749 0)
			(layer "F.Fab")
			(effects
				(font
					(size 0.7 0.7)
					(thickness 0.15)
				)
				(justify left bottom)
			)
		)
		(fp_text user "License: Apache-2.0"
			(at 0 7.15 0)
			(layer "F.Fab")
			(effects
				(font
					(size 0.7 0.7)
					(thickness 0.15)
				)
				(justify left bottom)
			)
		)
		(pad "" np_thru_hole circle
			(at 0 0)
			(size 2.7 2.7)
			(drill 2.7)
			(layers "F&B.Cu" "*.Mask")
		)
	)
	(footprint "antmicro-footprints:WiFi_Bluetooth_Module_LBEE5PK2AE"
		(layer "F.Cu")
		(at 222.1015 144.442)
		(property "Reference" "U26"
			(at 2.1485 5.028 0)
			(layer "F.SilkS")
			(effects
				(font
					(size 0.7 0.7)
					(thickness 0.15)
				)
				(justify left bottom)
			)
		)
		(property "Value" "WiFi_Bluetooth_LBEE5PK2AE"
			(at 0 5.1 0)
			(layer "F.Fab")
			(hide yes)
			(effects
				(font
					(size 0.7 0.7)
					(thickness 0.15)
				)
				(justify left bottom)
			)
		)
		(property "Datasheet" "https://www.murata.com/products/productdata/8816428220446/type2ae.pdf"
			(at 0 0 0)
			(layer "F.Fab")
			(hide yes)
			(effects
				(font
					(size 1.27 1.27)
					(thickness 0.15)
				)
			)
		)
		(property "Description" "WiFi and Bluetooth Module"
			(at 0 0 0)
			(layer "F.Fab")
			(hide yes)
			(effects
				(font
					(size 1.27 1.27)
					(thickness 0.15)
				)
			)
		)
		(property "Author" "Antmicro"
			(at 0 0 0)
			(layer "F.Fab")
			(hide yes)
			(effects
				(font
					(size 1 1)
					(thickness 0.15)
				)
			)
		)
		(property "License" "Apache-2.0"
			(at 0 0 0)
			(layer "F.Fab")
			(hide yes)
			(effects
				(font
					(size 1 1)
					(thickness 0.15)
				)
			)
		)
		(property "MPN" "LBEE5PK2AE"
			(at 0 0 0)
			(layer "F.Fab")
			(hide yes)
			(effects
				(font
					(size 1 1)
					(thickness 0.15)
				)
			)
		)
		(property "Manufacturer" "Murata"
			(at 0 0 0)
			(layer "F.Fab")
			(hide yes)
			(effects
				(font
					(size 1 1)
					(thickness 0.15)
				)
			)
		)
		(sheetname "/WiFi_Bluetooth/")
		(sheetfile "wifi_bt.kicad_sch")
		(attr smd)
		(fp_rect
			(start -4 -3.9)
			(end 4 3.9)
			(stroke
				(width 0.15)
				(type solid)
			)
			(fill no)
			(layer "F.SilkS")
		)
		(fp_circle
			(center -3.3 4.1)
			(end -3.25 4.1)
			(stroke
				(width 0.15)
				(type solid)
			)
			(fill yes)
			(layer "F.SilkS")
		)
		(fp_rect
			(start -4.3 -4.2)
			(end 4.3 4.2)
			(stroke
				(width 0.05)
				(type solid)
			)
			(fill no)
			(layer "F.CrtYd")
		)
		(fp_text user "License: Apache-2.0"
			(at -4.25 8.7 0)
			(layer "F.Fab")
			(effects
				(font
					(size 0.7 0.7)
					(thickness 0.15)
				)
				(justify left bottom)
			)
		)
		(fp_text user "Author: Antmicro"
			(at -4.25 6.3 0)
			(layer "F.Fab")
			(effects
				(font
					(size 0.7 0.7)
					(thickness 0.15)
				)
				(justify left bottom)
			)
		)
		(fp_text user "${REFERENCE}"
			(at -4.25 7.5 0)
			(layer "F.Fab")
			(effects
				(font
					(size 0.7 0.7)
					(thickness 0.15)
				)
				(justify left bottom)
			)
		)
		(pad "1" smd roundrect
			(at -3.3 3.375 180)
			(size 0.3 0.45)
			(layers "F.Cu" "F.Mask" "F.Paste")
			(roundrect_rratio 0.18)
			(net 417 "GND")
			(pinfunction "GND")
			(pintype "power_in")
		)
		(pad "2" smd roundrect
			(at -2.7 3.375 180)
			(size 0.3 0.45)
			(layers "F.Cu" "F.Mask" "F.Paste")
			(roundrect_rratio 0.18)
			(net 220 "Net-(U26A-SR_VLX)")
			(pinfunction "SR_VLX")
			(pintype "power_out")
		)
		(pad "3" smd roundrect
			(at -2.1 3.375 180)
			(size 0.3 0.45)
			(layers "F.Cu" "F.Mask" "F.Paste")
			(roundrect_rratio 0.18)
			(net 50 "+3V3")
			(pinfunction "VBAT")
			(pintype "power_in")
		)
		(pad "4" smd roundrect
			(at -1.5 3.375 180)
			(size 0.3 0.45)
			(layers "F.Cu" "F.Mask" "F.Paste")
			(roundrect_rratio 0.18)
			(net 171 "WL_REG_ON")
			(pinfunction "WL_REG_EN")
			(pintype "input")
		)
		(pad "5" smd roundrect
			(at -0.9 3.375 180)
			(size 0.3 0.45)
			(layers "F.Cu" "F.Mask" "F.Paste")
			(roundrect_rratio 0.18)
			(net 430 "/WiFi_Bluetooth/LPO_IN")
			(pinfunction "LPO_IN")
			(pintype "input")
		)
		(pad "6" smd roundrect
			(at -0.3 3.375 180)
			(size 0.3 0.45)
			(layers "F.Cu" "F.Mask" "F.Paste")
			(roundrect_rratio 0.18)
			(net 507 "Net-(U26A-BT_PCM_IN)")
			(pinfunction "BT_PCM_IN")
			(pintype "input")
		)
		(pad "7" smd roundrect
			(at 0.3 3.375 180)
			(size 0.3 0.45)
			(layers "F.Cu" "F.Mask" "F.Paste")
			(roundrect_rratio 0.18)
			(net 508 "Net-(U26A-BT_PCM_CLK)")
			(pinfunction "BT_PCM_CLK")
			(pintype "bidirectional")
		)
		(pad "8" smd roundrect
			(at 0.9 3.375 180)
			(size 0.3 0.45)
			(layers "F.Cu" "F.Mask" "F.Paste")
			(roundrect_rratio 0.18)
			(net 520 "Net-(U26A-BT_PCM_SYNC)")
			(pinfunction "BT_PCM_SYNC")
			(pintype "bidirectional")
		)
		(pad "9" smd roundrect
			(at 1.5 3.375 180)
			(size 0.3 0.45)
			(layers "F.Cu" "F.Mask" "F.Paste")
			(roundrect_rratio 0.18)
			(net 521 "Net-(U26A-BT_PCM_OUT)")
			(pinfunction "BT_PCM_OUT")
			(pintype "output")
		)
		(pad "10" smd roundrect
			(at 2.1 3.375 180)
			(size 0.3 0.45)
			(layers "F.Cu" "F.Mask" "F.Paste")
			(roundrect_rratio 0.18)
			(net 85 "/FPGA MSSIO/PF_BT.TX")
			(pinfunction "BT_UART_TXD")
			(pintype "output")
		)
		(pad "11" smd roundrect
			(at 2.7 3.375 180)
			(size 0.3 0.45)
			(layers "F.Cu" "F.Mask" "F.Paste")
			(roundrect_rratio 0.18)
			(net 297 "Net-(U26A-BT_UART_CTS_N)")
			(pinfunction "BT_UART_CTS_N")
			(pintype "input")
		)
		(pad "12" smd roundrect
			(at 3.3 3.375 180)
			(size 0.3 0.45)
			(layers "F.Cu" "F.Mask" "F.Paste")
			(roundrect_rratio 0.18)
			(net 117 "/FPGA MSSIO/PF_BT.RX")
			(pinfunction "BT_UART_RXD")
			(pintype "input")
		)
		(pad "13" smd roundrect
			(at 3.475 2.7 90)
			(size 0.3 0.45)
			(layers "F.Cu" "F.Mask" "F.Paste")
			(roundrect_rratio 0.18)
			(net 506 "Net-(U26A-BT_UART_RTS_N)")
			(pinfunction "BT_UART_RTS_N")
			(pintype "output")
		)
		(pad "14" smd roundrect
			(at 3.475 2.1 90)
			(size 0.3 0.45)
			(layers "F.Cu" "F.Mask" "F.Paste")
			(roundrect_rratio 0.18)
			(net 417 "GND")
			(pinfunction "GND")
			(pintype "passive")
		)
		(pad "15" smd roundrect
			(at 3.475 1.5 90)
			(size 0.3 0.45)
			(layers "F.Cu" "F.Mask" "F.Paste")
			(roundrect_rratio 0.18)
		)
		(pad "16" smd roundrect
			(at 3.475 0.9 90)
			(size 0.3 0.45)
			(layers "F.Cu" "F.Mask" "F.Paste")
			(roundrect_rratio 0.18)
			(net 417 "GND")
			(pinfunction "GND")
			(pintype "passive")
		)
		(pad "17" smd roundrect
			(at 3.475 0.3 90)
			(size 0.3 0.45)
			(layers "F.Cu" "F.Mask" "F.Paste")
			(roundrect_rratio 0.18)
			(net 526 "Net-(U26A-BT_HOST_WAKE)")
			(pinfunction "BT_HOST_WAKE")
			(pintype "bidirectional")
		)
		(pad "18" smd roundrect
			(at 3.475 -0.3 90)
			(size 0.3 0.45)
			(layers "F.Cu" "F.Mask" "F.Paste")
			(roundrect_rratio 0.18)
			(net 527 "Net-(U26A-BT_GPIO_2)")
			(pinfunction "BT_GPIO_2")
			(pintype "bidirectional")
		)
		(pad "19" smd roundrect
			(at 3.475 -0.9 90)
			(size 0.3 0.45)
			(layers "F.Cu" "F.Mask" "F.Paste")
			(roundrect_rratio 0.18)
			(net 528 "Net-(U26A-BT_GPIO_3)")
			(pinfunction "BT_GPIO_3")
			(pintype "bidirectional")
		)
		(pad "20" smd roundrect
			(at 3.475 -1.5 90)
			(size 0.3 0.45)
			(layers "F.Cu" "F.Mask" "F.Paste")
			(roundrect_rratio 0.18)
			(net 529 "Net-(U26A-BT_GPIO_5)")
			(pinfunction "BT_GPIO_5")
			(pintype "bidirectional")
		)
		(pad "21" smd roundrect
			(at 3.475 -2.1 90)
			(size 0.3 0.45)
			(layers "F.Cu" "F.Mask" "F.Paste")
			(roundrect_rratio 0.18)
			(net 417 "GND")
			(pinfunction "GND")
			(pintype "passive")
		)
		(pad "22" smd roundrect
			(at 3.475 -2.7 90)
			(size 0.3 0.45)
			(layers "F.Cu" "F.Mask" "F.Paste")
			(roundrect_rratio 0.18)
			(net 232 "Net-(U26A-WL_ANT)")
			(pinfunction "WL_ANT")
			(pintype "bidirectional")
		)
		(pad "23" smd roundrect
			(at 3.3 -3.375 180)
			(size 0.3 0.45)
			(layers "F.Cu" "F.Mask" "F.Paste")
			(roundrect_rratio 0.18)
			(net 417 "GND")
			(pinfunction "GND")
			(pintype "passive")
		)
		(pad "24" smd roundrect
			(at 2.7 -3.375 180)
			(size 0.3 0.45)
			(layers "F.Cu" "F.Mask" "F.Paste")
			(roundrect_rratio 0.18)
			(net 417 "GND")
			(pinfunction "GND")
			(pintype "passive")
		)
		(pad "25" smd roundrect
			(at 2.1 -3.375 180)
			(size 0.3 0.45)
			(layers "F.Cu" "F.Mask" "F.Paste")
			(roundrect_rratio 0.18)
			(net 621 "Net-(U26A-RF_SW_CTRL_5)")
			(pinfunction "RF_SW_CTRL_5")
			(pintype "output")
		)
		(pad "26" smd roundrect
			(at 1.5 -3.375 180)
			(size 0.3 0.45)
			(layers "F.Cu" "F.Mask" "F.Paste")
			(roundrect_rratio 0.18)
			(net 620 "Net-(U26A-RF_SW_CTRL_0)")
			(pinfunction "RF_SW_CTRL_0")
			(pintype "output")
		)
		(pad "27" smd roundrect
			(at 0.9 -3.375 180)
			(size 0.3 0.45)
			(layers "F.Cu" "F.Mask" "F.Paste")
			(roundrect_rratio 0.18)
			(net 417 "GND")
			(pinfunction "GND")
			(pintype "passive")
		)
		(pad "28" smd roundrect
			(at 0.3 -3.375 180)
			(size 0.3 0.45)
			(layers "F.Cu" "F.Mask" "F.Paste")
			(roundrect_rratio 0.18)
			(net 231 "/FPGA GPIO/WiFi.CMD")
			(pinfunction "SDIO_CMD")
			(pintype "bidirectional")
		)
		(pad "29" smd roundrect
			(at -0.3 -3.375 180)
			(size 0.3 0.45)
			(layers "F.Cu" "F.Mask" "F.Paste")
			(roundrect_rratio 0.18)
			(net 226 "/FPGA GPIO/WiFi.DAT1")
			(pinfunction "SDIO_DATA_1")
			(pintype "bidirectional")
		)
		(pad "30" smd roundrect
			(at -0.9 -3.375 180)
			(size 0.3 0.45)
			(layers "F.Cu" "F.Mask" "F.Paste")
			(roundrect_rratio 0.18)
			(net 240 "/FPGA GPIO/WiFi.DAT0")
			(pinfunction "SDIO_DATA_0")
			(pintype "bidirectional")
		)
		(pad "31" smd roundrect
			(at -1.5 -3.375 180)
			(size 0.3 0.45)
			(layers "F.Cu" "F.Mask" "F.Paste")
			(roundrect_rratio 0.18)
			(net 128 "/FPGA GPIO/WiFi.DAT3")
			(pinfunction "SDIO_DATA_3")
			(pintype "bidirectional")
		)
		(pad "32" smd roundrect
			(at -2.1 -3.375 180)
			(size 0.3 0.45)
			(layers "F.Cu" "F.Mask" "F.Paste")
			(roundrect_rratio 0.18)
			(net 225 "/FPGA GPIO/WiFi.DAT2")
			(pinfunction "SDIO_DATA_2")
			(pintype "bidirectional")
		)
		(pad "33" smd roundrect
			(at -2.7 -3.375 180)
			(size 0.3 0.45)
			(layers "F.Cu" "F.Mask" "F.Paste")
			(roundrect_rratio 0.18)
			(net 129 "/FPGA GPIO/WiFi.CLK")
			(pinfunction "SDIO_CLK")
			(pintype "input")
		)
		(pad "34" smd roundrect
			(at -3.3 -3.375 180)
			(size 0.3 0.45)
			(layers "F.Cu" "F.Mask" "F.Paste")
			(roundrect_rratio 0.18)
			(net 417 "GND")
			(pinfunction "GND")
			(pintype "passive")
		)
		(pad "35" smd roundrect
			(at -3.475 -2.7 90)
			(size 0.3 0.45)
			(layers "F.Cu" "F.Mask" "F.Paste")
			(roundrect_rratio 0.18)
		)
		(pad "36" smd roundrect
			(at -3.475 -2.1 90)
			(size 0.3 0.45)
			(layers "F.Cu" "F.Mask" "F.Paste")
			(roundrect_rratio 0.18)
		)
		(pad "37" smd roundrect
			(at -3.475 -1.5 90)
			(size 0.3 0.45)
			(layers "F.Cu" "F.Mask" "F.Paste")
			(roundrect_rratio 0.18)
		)
		(pad "38" smd roundrect
			(at -3.475 -0.9 90)
			(size 0.3 0.45)
			(layers "F.Cu" "F.Mask" "F.Paste")
			(roundrect_rratio 0.18)
		)
		(pad "39" smd roundrect
			(at -3.475 -0.3 90)
			(size 0.3 0.45)
			(layers "F.Cu" "F.Mask" "F.Paste")
			(roundrect_rratio 0.18)
		)
		(pad "40" smd roundrect
			(at -3.475 0.3 90)
			(size 0.3 0.45)
			(layers "F.Cu" "F.Mask" "F.Paste")
			(roundrect_rratio 0.18)
		)
		(pad "41" smd roundrect
			(at -3.475 0.9 90)
			(size 0.3 0.45)
			(layers "F.Cu" "F.Mask" "F.Paste")
			(roundrect_rratio 0.18)
			(net 417 "GND")
			(pinfunction "GND")
			(pintype "passive")
		)
		(pad "42" smd roundrect
			(at -3.475 1.5 90)
			(size 0.3 0.45)
			(layers "F.Cu" "F.Mask" "F.Paste")
			(roundrect_rratio 0.18)
			(net 50 "+3V3")
			(pinfunction "VDDIO")
			(pintype "power_in")
		)
		(pad "43" smd roundrect
			(at -3.475 2.1 90)
			(size 0.3 0.45)
			(layers "F.Cu" "F.Mask" "F.Paste")
			(roundrect_rratio 0.18)
			(net 151 "Net-(U26A-VIN_LDO)")
			(pinfunction "VIN_LDO")
			(pintype "power_in")
		)
		(pad "44" smd roundrect
			(at -3.475 2.7 90)
			(size 0.3 0.45)
			(layers "F.Cu" "F.Mask" "F.Paste")
			(roundrect_rratio 0.18)
		)
		(pad "45" smd roundrect
			(at -1.5 2.175 180)
			(size 0.3 0.45)
			(layers "F.Cu" "F.Mask" "F.Paste")
			(roundrect_rratio 0.18)
			(net 530 "Net-(U26A-GPIO_1)")
			(pinfunction "GPIO_1")
			(pintype "bidirectional")
		)
		(pad "46" smd roundrect
			(at -0.9 2.175 180)
			(size 0.3 0.45)
			(layers "F.Cu" "F.Mask" "F.Paste")
			(roundrect_rratio 0.18)
			(net 122 "/USB/WL_BT.D_N")
			(pinfunction "USB2_DM")
			(pintype "bidirectional")
		)
		(pad "47" smd roundrect
			(at -0.3 2.175 180)
			(size 0.3 0.45)
			(layers "F.Cu" "F.Mask" "F.Paste")
			(roundrect_rratio 0.18)
			(net 190 "/USB/WL_BT.D_P")
			(pinfunction "USB2_DP")
			(pintype "bidirectional")
		)
		(pad "48" smd roundrect
			(at 0.3 2.175 180)
			(size 0.3 0.45)
			(layers "F.Cu" "F.Mask" "F.Paste")
			(roundrect_rratio 0.18)
			(net 534 "unconnected-(U26A-USB2_MONCDR-Pad48)")
			(pinfunction "USB2_MONCDR")
			(pintype "output+no_connect")
		)
		(pad "49" smd roundrect
			(at 0.9 2.175 180)
			(size 0.3 0.45)
			(layers "F.Cu" "F.Mask" "F.Paste")
			(roundrect_rratio 0.18)
			(net 50 "+3V3")
			(pinfunction "USB2_AVDD33")
			(pintype "power_in")
		)
		(pad "50" smd roundrect
			(at 1.5 2.175 180)
			(size 0.3 0.45)
			(layers "F.Cu" "F.Mask" "F.Paste")
			(roundrect_rratio 0.18)
			(net 281 "Net-(U26A-USB2_RREF)")
			(pinfunction "USB2_RREF")
			(pintype "bidirectional")
		)
		(pad "51" smd roundrect
			(at 2.275 1.5 90)
			(size 0.3 0.45)
			(layers "F.Cu" "F.Mask" "F.Paste")
			(roundrect_rratio 0.18)
			(net 524 "Net-(U26A-BT_DEV_WAKE)")
			(pinfunction "BT_DEV_WAKE")
			(pintype "input")
		)
		(pad "52" smd roundrect
			(at 2.275 0.9 90)
			(size 0.3 0.45)
			(layers "F.Cu" "F.Mask" "F.Paste")
			(roundrect_rratio 0.18)
			(net 525 "Net-(U26A-WL_HOST_WAKE)")
			(pinfunction "WL_HOST_WAKE")
			(pintype "output")
		)
		(pad "53" smd roundrect
			(at 2.275 0.3 90)
			(size 0.3 0.45)
			(layers "F.Cu" "F.Mask" "F.Paste")
			(roundrect_rratio 0.18)
			(net 424 "/WiFi_Bluetooth/JTAG_SEL")
			(pinfunction "JTAG_SEL")
			(pintype "input")
		)
		(pad "54" smd roundrect
			(at 2.275 -0.3 90)
			(size 0.3 0.45)
			(layers "F.Cu" "F.Mask" "F.Paste")
			(roundrect_rratio 0.18)
			(net 422 "/WiFi_Bluetooth/STRAP_1")
			(pinfunction "STRAP_1")
			(pintype "input")
		)
		(pad "55" smd roundrect
			(at 2.275 -0.9 90)
			(size 0.3 0.45)
			(layers "F.Cu" "F.Mask" "F.Paste")
			(roundrect_rratio 0.18)
			(net 423 "/WiFi_Bluetooth/STRAP_2")
			(pinfunction "STRAP_2")
			(pintype "input")
		)
		(pad "56" smd roundrect
			(at 2.275 -1.5 90)
			(size 0.3 0.45)
			(layers "F.Cu" "F.Mask" "F.Paste")
			(roundrect_rratio 0.18)
			(net 421 "/WiFi_Bluetooth/STRAP_0")
			(pinfunction "STRAP_0")
			(pintype "input")
		)
		(pad "57" smd roundrect
			(at 1.5 -2.175 180)
			(size 0.3 0.45)
			(layers "F.Cu" "F.Mask" "F.Paste")
			(roundrect_rratio 0.18)
			(net 417 "GND")
			(pinfunction "GND")
			(pintype "passive")
		)
		(pad "58" smd roundrect
			(at 0.9 -2.175 180)
			(size 0.3 0.45)
			(layers "F.Cu" "F.Mask" "F.Paste")
			(roundrect_rratio 0.18)
		)
		(pad "59" smd roundrect
			(at 0.3 -2.175 180)
			(size 0.3 0.45)
			(layers "F.Cu" "F.Mask" "F.Paste")
			(roundrect_rratio 0.18)
		)
		(pad "60" smd roundrect
			(at -0.3 -2.175 180)
			(size 0.3 0.45)
			(layers "F.Cu" "F.Mask" "F.Paste")
			(roundrect_rratio 0.18)
		)
		(pad "61" smd roundrect
			(at -0.9 -2.175 180)
			(size 0.3 0.45)
			(layers "F.Cu" "F.Mask" "F.Paste")
			(roundrect_rratio 0.18)
		)
		(pad "62" smd roundrect
			(at -1.5 -2.175 180)
			(size 0.3 0.45)
			(layers "F.Cu" "F.Mask" "F.Paste")
			(roundrect_rratio 0.18)
		)
		(pad "63" smd roundrect
			(at -2.275 -1.5 90)
			(size 0.3 0.45)
			(layers "F.Cu" "F.Mask" "F.Paste")
			(roundrect_rratio 0.18)
			(net 127 "JTAG_RESET_n")
			(pinfunction "TRST_L")
			(pintype "bidirectional")
		)
		(pad "64" smd roundrect
			(at -2.275 -0.9 90)
			(size 0.3 0.45)
			(layers "F.Cu" "F.Mask" "F.Paste")
			(roundrect_rratio 0.18)
			(net 192 "PF_TDO")
			(pinfunction "JTAG_TDI")
			(pintype "bidirectional")
		)
		(pad "65" smd roundrect
			(at -2.275 -0.3 90)
			(size 0.3 0.45)
			(layers "F.Cu" "F.Mask" "F.Paste")
			(roundrect_rratio 0.18)
			(net 257 "WL_BT_TDO")
			(pinfunction "JTAG_TDO")
			(pintype "bidirectional")
		)
		(pad "66" smd roundrect
			(at -2.275 0.3 90)
			(size 0.3 0.45)
			(layers "F.Cu" "F.Mask" "F.Paste")
			(roundrect_rratio 0.18)
			(net 124 "JTAG_TCK")
			(pinfunction "JTAG_TCK/SWCLK")
			(pintype "bidirectional")
		)
		(pad "67" smd roundrect
			(at -2.275 0.9 90)
			(size 0.3 0.45)
			(layers "F.Cu" "F.Mask" "F.Paste")
			(roundrect_rratio 0.18)
			(net 123 "JTAG_TMS")
			(pinfunction "JTAG_TMS/SWDIO")
			(pintype "bidirectional")
		)
		(pad "68" smd roundrect
			(at -2.275 1.5 90)
			(size 0.3 0.45)
			(layers "F.Cu" "F.Mask" "F.Paste")
			(roundrect_rratio 0.18)
			(net 172 "BT_REG_ON")
			(pinfunction "BT_REG_EN")
			(pintype "input")
		)
		(pad "69" smd roundrect
			(at -1 1 180)
			(size 0.3 0.45)
			(layers "F.Cu" "F.Mask" "F.Paste")
			(roundrect_rratio 0.18)
			(net 417 "GND")
			(pinfunction "GND")
			(pintype "passive")
		)
		(pad "70" smd roundrect
			(at 0 1 180)
			(size 0.3 0.45)
			(layers "F.Cu" "F.Mask" "F.Paste")
			(roundrect_rratio 0.18)
			(net 417 "GND")
			(pinfunction "GND")
			(pintype "passive")
		)
		(pad "71" smd roundrect
			(at 1 1 180)
			(size 0.3 0.45)
			(layers "F.Cu" "F.Mask" "F.Paste")
			(roundrect_rratio 0.18)
			(net 417 "GND")
			(pinfunction "GND")
			(pintype "passive")
		)
		(pad "72" smd roundrect
			(at 1 0 180)
			(size 0.3 0.45)
			(layers "F.Cu" "F.Mask" "F.Paste")
			(roundrect_rratio 0.18)
			(net 417 "GND")
			(pinfunction "GND")
			(pintype "passive")
		)
		(pad "73" smd roundrect
			(at 1 -1 180)
			(size 0.3 0.45)
			(layers "F.Cu" "F.Mask" "F.Paste")
			(roundrect_rratio 0.18)
			(net 417 "GND")
			(pinfunction "GND")
			(pintype "passive")
		)
		(pad "74" smd roundrect
			(at 0 -1 180)
			(size 0.3 0.45)
			(layers "F.Cu" "F.Mask" "F.Paste")
			(roundrect_rratio 0.18)
			(net 417 "GND")
			(pinfunction "GND")
			(pintype "passive")
		)
		(pad "75" smd roundrect
			(at -1 -1 180)
			(size 0.3 0.45)
			(layers "F.Cu" "F.Mask" "F.Paste")
			(roundrect_rratio 0.18)
			(net 417 "GND")
			(pinfunction "GND")
			(pintype "passive")
		)
		(pad "76" smd roundrect
			(at -1 0 180)
			(size 0.3 0.45)
			(layers "F.Cu" "F.Mask" "F.Paste")
			(roundrect_rratio 0.18)
			(net 417 "GND")
			(pinfunction "GND")
			(pintype "passive")
		)
		(pad "77" smd roundrect
			(at 0 0 180)
			(size 0.3 0.45)
			(layers "F.Cu" "F.Mask" "F.Paste")
			(roundrect_rratio 0.18)
			(net 417 "GND")
			(pinfunction "GND")
			(pintype "passive")
		)
	)
	(footprint "antmicro-footprints:C_0402_1005Metric"
		(layer "F.Cu")
		(at 180.7 138.3175 -90)
		(descr "Capacitor SMD 0402")
		(tags "capacitor SMD 0402")
		(property "Reference" "C93"
			(at -2.2275 -6.79 180)
			(layer "F.SilkS")
			(effects
				(font
					(size 0.7 0.7)
					(thickness 0.15)
				)
				(justify right bottom)
			)
		)
		(property "Value" "C_10u_10V_0402"
			(at -1.022927 2.155213 90)
			(layer "F.Fab")
			(hide yes)
			(effects
				(font
					(size 0.7 0.7)
					(thickness 0.15)
				)
				(justify right bottom)
			)
		)
		(property "Datasheet" "https://www.murata.com/products/productdetail?partno=GRM155R61A106ME11%23"
			(at 0 0 270)
			(layer "F.Fab")
			(hide yes)
			(effects
				(font
					(size 1.27 1.27)
					(thickness 0.15)
				)
			)
		)
		(property "Description" "Multilayer Ceramic Capacitors MLCC - SMD/SMT 10 uF 10 VDC 20% 0402 X5R"
			(at 0 0 270)
			(layer "F.Fab")
			(hide yes)
			(effects
				(font
					(size 1.27 1.27)
					(thickness 0.15)
				)
			)
		)
		(property "Author" "Antmicro"
			(at 42.3825 319.0175 0)
			(layer "F.Fab")
			(hide yes)
			(effects
				(font
					(size 1 1)
					(thickness 0.15)
				)
			)
		)
		(property "Dielectric" "X5R"
			(at 42.3825 319.0175 0)
			(layer "F.Fab")
			(hide yes)
			(effects
				(font
					(size 1 1)
					(thickness 0.15)
				)
			)
		)
		(property "License" "Apache-2.0"
			(at 42.3825 319.0175 0)
			(layer "F.Fab")
			(hide yes)
			(effects
				(font
					(size 1 1)
					(thickness 0.15)
				)
			)
		)
		(property "MPN" "GRM155R61A106ME11D"
			(at 42.3825 319.0175 0)
			(layer "F.Fab")
			(hide yes)
			(effects
				(font
					(size 1 1)
					(thickness 0.15)
				)
			)
		)
		(property "Manufacturer" "Murata"
			(at 42.3825 319.0175 0)
			(layer "F.Fab")
			(hide yes)
			(effects
				(font
					(size 1 1)
					(thickness 0.15)
				)
			)
		)
		(property "Public" ""
			(at 42.3825 319.0175 0)
			(layer "F.Fab")
			(hide yes)
			(effects
				(font
					(size 1 1)
					(thickness 0.15)
				)
			)
		)
		(property "Val" "10u"
			(at 42.3825 319.0175 0)
			(layer "F.Fab")
			(hide yes)
			(effects
				(font
					(size 1 1)
					(thickness 0.15)
				)
			)
		)
		(property "Voltage" "10V"
			(at 42.3825 319.0175 0)
			(layer "F.Fab")
			(hide yes)
			(effects
				(font
					(size 1 1)
					(thickness 0.15)
				)
			)
		)
		(sheetname "/Supply/")
		(sheetfile "supply.kicad_sch")
		(attr smd)
		(fp_rect
			(start -0.925 -0.47)
			(end 0.925 0.47)
			(stroke
				(width 0.05)
				(type default)
			)
			(fill no)
			(layer "F.CrtYd")
		)
		(fp_line
			(start -0.494 0.248)
			(end -0.494 -0.25)
			(stroke
				(width 0.15)
				(type solid)
			)
			(layer "F.Fab")
		)
		(fp_line
			(start 0.504 0.248)
			(end -0.494 0.248)
			(stroke
				(width 0.15)
				(type solid)
			)
			(layer "F.Fab")
		)
		(fp_line
			(start -0.494 -0.25)
			(end 0.504 -0.25)
			(stroke
				(width 0.15)
				(type solid)
			)
			(layer "F.Fab")
		)
		(fp_line
			(start 0.504 -0.25)
			(end 0.504 0.248)
			(stroke
				(width 0.15)
				(type solid)
			)
			(layer "F.Fab")
		)
		(fp_text user "${REFERENCE}"
			(at -0.939 4.599 270)
			(layer "F.Fab")
			(effects
				(font
					(size 0.7 0.7)
					(thickness 0.15)
				)
				(justify left bottom)
			)
		)
		(fp_text user "Author: Antmicro"
			(at -0.939 3.399 270)
			(layer "F.Fab")
			(effects
				(font
					(size 0.7 0.7)
					(thickness 0.15)
				)
				(justify left bottom)
			)
		)
		(fp_text user "License: Apache-2.0"
			(at -0.939 5.799 270)
			(layer "F.Fab")
			(effects
				(font
					(size 0.7 0.7)
					(thickness 0.15)
				)
				(justify left bottom)
			)
		)
		(pad "1" smd roundrect
			(at -0.48 0 270)
			(size 0.59 0.64)
			(layers "F.Cu" "F.Mask" "F.Paste")
			(roundrect_rratio 0.25)
			(net 417 "GND")
			(pintype "passive")
		)
		(pad "2" smd roundrect
			(at 0.48 0 270)
			(size 0.59 0.64)
			(layers "F.Cu" "F.Mask" "F.Paste")
			(roundrect_rratio 0.25)
			(net 90 "+5V")
			(pintype "passive")
		)
	)
	(footprint "antmicro-footprints:TP_SMD_0.75mm"
		(layer "F.Cu")
		(at 222.68 139.72)
		(property "Reference" "TP2"
			(at 0 -0.6 0)
			(layer "F.SilkS")
			(hide yes)
			(effects
				(font
					(size 0.7 0.7)
					(thickness 0.15)
				)
				(justify left bottom)
			)
		)
		(property "Value" "TP_0.75mm_SMD"
			(at 0 1.2 0)
			(layer "F.Fab")
			(hide yes)
			(effects
				(font
					(size 0.7 0.7)
					(thickness 0.15)
				)
				(justify left bottom)
			)
		)
		(property "Description" "SMT test point"
			(at 0 0 0)
			(layer "F.Fab")
			(hide yes)
			(effects
				(font
					(size 1.27 1.27)
					(thickness 0.15)
				)
			)
		)
		(property "Author" "Antmicro"
			(at 0 0 0)
			(layer "F.Fab")
			(hide yes)
			(effects
				(font
					(size 1 1)
					(thickness 0.15)
				)
			)
		)
		(property "License" "Apache-2.0"
			(at 0 0 0)
			(layer "F.Fab")
			(hide yes)
			(effects
				(font
					(size 1 1)
					(thickness 0.15)
				)
			)
		)
		(property "MPN" ""
			(at 0 0 0)
			(layer "F.Fab")
			(hide yes)
			(effects
				(font
					(size 1 1)
					(thickness 0.15)
				)
			)
		)
		(property "Manufacturer" ""
			(at 0 0 0)
			(layer "F.Fab")
			(hide yes)
			(effects
				(font
					(size 1 1)
					(thickness 0.15)
				)
			)
		)
		(property "Public" "False"
			(at 0 0 0)
			(layer "F.Fab")
			(hide yes)
			(effects
				(font
					(size 1 1)
					(thickness 0.15)
				)
			)
		)
		(sheetname "/WiFi_Bluetooth/")
		(sheetfile "wifi_bt.kicad_sch")
		(attr exclude_from_pos_files exclude_from_bom)
		(fp_circle
			(center 0 0)
			(end 0.475 0)
			(stroke
				(width 0.05)
				(type default)
			)
			(fill no)
			(layer "F.CrtYd")
		)
		(fp_text user "License: Apache-2.0"
			(at -0.4 5.101 0)
			(layer "F.Fab")
			(effects
				(font
					(size 0.7 0.7)
					(thickness 0.15)
				)
				(justify left bottom)
			)
		)
		(fp_text user "Author: Antmicro"
			(at -0.4 3.901 0)
			(layer "F.Fab")
			(effects
				(font
					(size 0.7 0.7)
					(thickness 0.15)
				)
				(justify left bottom)
			)
		)
		(fp_text user "${REFERENCE}"
			(at -0.4 2.7 0)
			(layer "F.Fab")
			(effects
				(font
					(size 0.7 0.7)
					(thickness 0.15)
				)
				(justify left bottom)
			)
		)
		(pad "1" smd circle
			(at 0 0)
			(size 0.75 0.75)
			(layers "F.Cu" "F.Mask")
			(net 620 "Net-(U26A-RF_SW_CTRL_0)")
			(pinfunction "1")
			(pintype "passive")
		)
	)
	(footprint "antmicro-footprints:C_0402_1005Metric"
		(layer "F.Cu")
		(at 198.3 145.43 180)
		(descr "Capacitor SMD 0402")
		(tags "capacitor SMD 0402")
		(property "Reference" "C2"
			(at -1.31 -0.27 270)
			(layer "F.SilkS")
			(effects
				(font
					(size 0.7 0.7)
					(thickness 0.15)
				)
				(justify right bottom)
			)
		)
		(property "Value" "C_100n_0402"
			(at -1.022927 2.155213 0)
			(layer "F.Fab")
			(hide yes)
			(effects
				(font
					(size 0.7 0.7)
					(thickness 0.15)
				)
				(justify right bottom)
			)
		)
		(property "Datasheet" "https://www.murata.com/products/productdetail?partno=GRM155R61H104KE14%23"
			(at 0 0 180)
			(layer "F.Fab")
			(hide yes)
			(effects
				(font
					(size 1.27 1.27)
					(thickness 0.15)
				)
			)
		)
		(property "Description" "SMD Multilayer Ceramic Capacitor, 0.1 µF, 50 V, 0402 [1005 Metric], ± 10%, X5R, GRM Series"
			(at 0 0 180)
			(layer "F.Fab")
			(hide yes)
			(effects
				(font
					(size 1.27 1.27)
					(thickness 0.15)
				)
			)
		)
		(property "Author" "Antmicro"
			(at 396.6 290.86 0)
			(layer "F.Fab")
			(hide yes)
			(effects
				(font
					(size 1 1)
					(thickness 0.15)
				)
			)
		)
		(property "Dielectric" "X5R"
			(at 396.6 290.86 0)
			(layer "F.Fab")
			(hide yes)
			(effects
				(font
					(size 1 1)
					(thickness 0.15)
				)
			)
		)
		(property "License" "Apache-2.0"
			(at 396.6 290.86 0)
			(layer "F.Fab")
			(hide yes)
			(effects
				(font
					(size 1 1)
					(thickness 0.15)
				)
			)
		)
		(property "MPN" "GRM155R61H104KE14D"
			(at 396.6 290.86 0)
			(layer "F.Fab")
			(hide yes)
			(effects
				(font
					(size 1 1)
					(thickness 0.15)
				)
			)
		)
		(property "Manufacturer" "Murata"
			(at 396.6 290.86 0)
			(layer "F.Fab")
			(hide yes)
			(effects
				(font
					(size 1 1)
					(thickness 0.15)
				)
			)
		)
		(property "Public" ""
			(at 396.6 290.86 0)
			(layer "F.Fab")
			(hide yes)
			(effects
				(font
					(size 1 1)
					(thickness 0.15)
				)
			)
		)
		(property "Val" "100n"
			(at 396.6 290.86 0)
			(layer "F.Fab")
			(hide yes)
			(effects
				(font
					(size 1 1)
					(thickness 0.15)
				)
			)
		)
		(property "Voltage" "50V"
			(at 396.6 290.86 0)
			(layer "F.Fab")
			(hide yes)
			(effects
				(font
					(size 1 1)
					(thickness 0.15)
				)
			)
		)
		(sheetname "/FPGA HSIO/")
		(sheetfile "fpga-hsio.kicad_sch")
		(attr smd)
		(fp_rect
			(start -0.925 -0.47)
			(end 0.925 0.47)
			(stroke
				(width 0.05)
				(type default)
			)
			(fill no)
			(layer "F.CrtYd")
		)
		(fp_line
			(start 0.504 0.248)
			(end -0.494 0.248)
			(stroke
				(width 0.15)
				(type solid)
			)
			(layer "F.Fab")
		)
		(fp_line
			(start 0.504 -0.25)
			(end 0.504 0.248)
			(stroke
				(width 0.15)
				(type solid)
			)
			(layer "F.Fab")
		)
		(fp_line
			(start -0.494 0.248)
			(end -0.494 -0.25)
			(stroke
				(width 0.15)
				(type solid)
			)
			(layer "F.Fab")
		)
		(fp_line
			(start -0.494 -0.25)
			(end 0.504 -0.25)
			(stroke
				(width 0.15)
				(type solid)
			)
			(layer "F.Fab")
		)
		(fp_text user "${REFERENCE}"
			(at -0.939 4.599 180)
			(layer "F.Fab")
			(effects
				(font
					(size 0.7 0.7)
					(thickness 0.15)
				)
				(justify left bottom)
			)
		)
		(fp_text user "License: Apache-2.0"
			(at -0.939 5.799 180)
			(layer "F.Fab")
			(effects
				(font
					(size 0.7 0.7)
					(thickness 0.15)
				)
				(justify left bottom)
			)
		)
		(fp_text user "Author: Antmicro"
			(at -0.939 3.399 180)
			(layer "F.Fab")
			(effects
				(font
					(size 0.7 0.7)
					(thickness 0.15)
				)
				(justify left bottom)
			)
		)
		(pad "1" smd roundrect
			(at -0.48 0 180)
			(size 0.59 0.64)
			(layers "F.Cu" "F.Mask" "F.Paste")
			(roundrect_rratio 0.25)
			(net 417 "GND")
			(pintype "passive")
		)
		(pad "2" smd roundrect
			(at 0.48 0 180)
			(size 0.59 0.64)
			(layers "F.Cu" "F.Mask" "F.Paste")
			(roundrect_rratio 0.25)
			(net 48 "+1V8")
			(pintype "passive")
		)
	)
	(footprint "antmicro-footprints:MP_NPTH_Drill2.7mm"
		(locked yes)
		(layer "F.Cu")
		(at 226.01377 152.33277)
		(property "Reference" "MP3"
			(at 0 -1.8 0)
			(layer "F.SilkS")
			(hide yes)
			(effects
				(font
					(size 0.7 0.7)
					(thickness 0.15)
				)
				(justify left bottom)
			)
		)
		(property "Value" "MP_NPTH_Drill2.7mm"
			(at 0 2.3 0)
			(layer "F.Fab")
			(hide yes)
			(effects
				(font
					(size 0.7 0.7)
					(thickness 0.15)
				)
				(justify left bottom)
			)
		)
		(property "Description" "Mechanical part"
			(at 0 0 0)
			(layer "F.Fab")
			(hide yes)
			(effects
				(font
					(size 1.27 1.27)
					(thickness 0.15)
				)
			)
		)
		(property "Author" "Antmicro"
			(at 0 0 0)
			(layer "F.Fab")
			(hide yes)
			(effects
				(font
					(size 1 1)
					(thickness 0.15)
				)
			)
		)
		(property "License" "Apache-2.0"
			(at 0 0 0)
			(layer "F.Fab")
			(hide yes)
			(effects
				(font
					(size 1 1)
					(thickness 0.15)
				)
			)
		)
		(property "exclude_from_bom" ""
			(at 0 0 0)
			(layer "F.Fab")
			(hide yes)
			(effects
				(font
					(size 1 1)
					(thickness 0.15)
				)
			)
		)
		(sheetfile "polarfire-som.kicad_sch")
		(attr board_only exclude_from_pos_files exclude_from_bom)
		(fp_circle
			(center 0 0)
			(end 1.45 0)
			(stroke
				(width 0.05)
				(type default)
			)
			(fill no)
			(layer "F.CrtYd")
		)
		(fp_text user "Author: Antmicro"
			(at 0 5.95 0)
			(layer "F.Fab")
			(effects
				(font
					(size 0.7 0.7)
					(thickness 0.15)
				)
				(justify left bottom)
			)
		)
		(fp_text user "${REFERENCE}"
			(at 0 4.749 0)
			(layer "F.Fab")
			(effects
				(font
					(size 0.7 0.7)
					(thickness 0.15)
				)
				(justify left bottom)
			)
		)
		(fp_text user "License: Apache-2.0"
			(at 0 7.15 0)
			(layer "F.Fab")
			(effects
				(font
					(size 0.7 0.7)
					(thickness 0.15)
				)
				(justify left bottom)
			)
		)
		(pad "" np_thru_hole circle
			(at 0 0)
			(size 2.7 2.7)
			(drill 2.7)
			(layers "F&B.Cu" "*.Mask")
		)
	)
	(footprint "antmicro-footprints:C_0402_1005Metric"
		(layer "F.Cu")
		(at 185.684904 147.897281 -90)
		(descr "Capacitor SMD 0402")
		(tags "capacitor SMD 0402")
		(property "Reference" "C97"
			(at 5.06272 -7.315096 180)
			(layer "F.SilkS")
			(effects
				(font
					(size 0.7 0.7)
					(thickness 0.15)
				)
				(justify right bottom)
			)
		)
		(property "Value" "C_22u_0402"
			(at -1.022927 2.155213 90)
			(layer "F.Fab")
			(hide yes)
			(effects
				(font
					(size 0.7 0.7)
					(thickness 0.15)
				)
				(justify right bottom)
			)
		)
		(property "Datasheet" "https://www.murata.com/products/productdetail?partno=GRM158R60J226ME01%23"
			(at 0 0 270)
			(layer "F.Fab")
			(hide yes)
			(effects
				(font
					(size 1.27 1.27)
					(thickness 0.15)
				)
			)
		)
		(property "Description" "SMD Multilayer Ceramic Capacitor, 22 uF, 4 V, 0402 [1005 Metric], X6S"
			(at 0 0 270)
			(layer "F.Fab")
			(hide yes)
			(effects
				(font
					(size 1.27 1.27)
					(thickness 0.15)
				)
			)
		)
		(property "Author" "Antmicro"
			(at 37.787623 333.582185 0)
			(layer "F.Fab")
			(hide yes)
			(effects
				(font
					(size 1 1)
					(thickness 0.15)
				)
			)
		)
		(property "Dielectric" ""
			(at 37.787623 333.582185 0)
			(layer "F.Fab")
			(hide yes)
			(effects
				(font
					(size 1 1)
					(thickness 0.15)
				)
			)
		)
		(property "License" "Apache-2.0"
			(at 37.787623 333.582185 0)
			(layer "F.Fab")
			(hide yes)
			(effects
				(font
					(size 1 1)
					(thickness 0.15)
				)
			)
		)
		(property "MPN" "GRM158R60J226ME01D"
			(at 37.787623 333.582185 0)
			(layer "F.Fab")
			(hide yes)
			(effects
				(font
					(size 1 1)
					(thickness 0.15)
				)
			)
		)
		(property "Manufacturer" "Murata"
			(at 37.787623 333.582185 0)
			(layer "F.Fab")
			(hide yes)
			(effects
				(font
					(size 1 1)
					(thickness 0.15)
				)
			)
		)
		(property "Public" ""
			(at 37.787623 333.582185 0)
			(layer "F.Fab")
			(hide yes)
			(effects
				(font
					(size 1 1)
					(thickness 0.15)
				)
			)
		)
		(property "Val" "22u"
			(at 37.787623 333.582185 0)
			(layer "F.Fab")
			(hide yes)
			(effects
				(font
					(size 1 1)
					(thickness 0.15)
				)
			)
		)
		(property "Voltage" ""
			(at 37.787623 333.582185 0)
			(layer "F.Fab")
			(hide yes)
			(effects
				(font
					(size 1 1)
					(thickness 0.15)
				)
			)
		)
		(sheetname "/Supply/")
		(sheetfile "supply.kicad_sch")
		(attr smd)
		(fp_rect
			(start -0.925 -0.47)
			(end 0.925 0.47)
			(stroke
				(width 0.05)
				(type default)
			)
			(fill no)
			(layer "F.CrtYd")
		)
		(fp_line
			(start -0.494 0.248)
			(end -0.494 -0.25)
			(stroke
				(width 0.15)
				(type solid)
			)
			(layer "F.Fab")
		)
		(fp_line
			(start 0.504 0.248)
			(end -0.494 0.248)
			(stroke
				(width 0.15)
				(type solid)
			)
			(layer "F.Fab")
		)
		(fp_line
			(start -0.494 -0.25)
			(end 0.504 -0.25)
			(stroke
				(width 0.15)
				(type solid)
			)
			(layer "F.Fab")
		)
		(fp_line
			(start 0.504 -0.25)
			(end 0.504 0.248)
			(stroke
				(width 0.15)
				(type solid)
			)
			(layer "F.Fab")
		)
		(fp_text user "License: Apache-2.0"
			(at -0.939 5.799 270)
			(layer "F.Fab")
			(effects
				(font
					(size 0.7 0.7)
					(thickness 0.15)
				)
				(justify left bottom)
			)
		)
		(fp_text user "Author: Antmicro"
			(at -0.939 3.399 270)
			(layer "F.Fab")
			(effects
				(font
					(size 0.7 0.7)
					(thickness 0.15)
				)
				(justify left bottom)
			)
		)
		(fp_text user "${REFERENCE}"
			(at -0.939 4.599 270)
			(layer "F.Fab")
			(effects
				(font
					(size 0.7 0.7)
					(thickness 0.15)
				)
				(justify left bottom)
			)
		)
		(pad "1" smd roundrect
			(at -0.48 0 270)
			(size 0.59 0.64)
			(layers "F.Cu" "F.Mask" "F.Paste")
			(roundrect_rratio 0.25)
			(net 417 "GND")
			(pintype "passive")
		)
		(pad "2" smd roundrect
			(at 0.48 0 270)
			(size 0.59 0.64)
			(layers "F.Cu" "F.Mask" "F.Paste")
			(roundrect_rratio 0.25)
			(net 522 "/Supply/1V05_REG")
			(pintype "passive")
		)
	)
	(footprint "antmicro-footprints:TP_SMD_0.75mm"
		(layer "F.Cu")
		(at 179.45 145.3375 90)
		(property "Reference" "TP26"
			(at 0 -0.6 90)
			(layer "F.SilkS")
			(hide yes)
			(effects
				(font
					(size 0.7 0.7)
					(thickness 0.15)
				)
				(justify left bottom)
			)
		)
		(property "Value" "TP_0.75mm_SMD"
			(at 0 1.2 90)
			(layer "F.Fab")
			(hide yes)
			(effects
				(font
					(size 0.7 0.7)
					(thickness 0.15)
				)
				(justify left bottom)
			)
		)
		(property "Description" "SMT test point"
			(at 0 0 90)
			(layer "F.Fab")
			(hide yes)
			(effects
				(font
					(size 1.27 1.27)
					(thickness 0.15)
				)
			)
		)
		(property "Author" "Antmicro"
			(at 324.7875 -34.1125 0)
			(layer "F.Fab")
			(hide yes)
			(effects
				(font
					(size 1 1)
					(thickness 0.15)
				)
			)
		)
		(property "License" "Apache-2.0"
			(at 324.7875 -34.1125 0)
			(layer "F.Fab")
			(hide yes)
			(effects
				(font
					(size 1 1)
					(thickness 0.15)
				)
			)
		)
		(property "MPN" ""
			(at 324.7875 -34.1125 0)
			(layer "F.Fab")
			(hide yes)
			(effects
				(font
					(size 1 1)
					(thickness 0.15)
				)
			)
		)
		(property "Manufacturer" ""
			(at 324.7875 -34.1125 0)
			(layer "F.Fab")
			(hide yes)
			(effects
				(font
					(size 1 1)
					(thickness 0.15)
				)
			)
		)
		(property "Public" "False"
			(at 324.7875 -34.1125 0)
			(layer "F.Fab")
			(hide yes)
			(effects
				(font
					(size 1 1)
					(thickness 0.15)
				)
			)
		)
		(sheetname "/Supply/")
		(sheetfile "supply.kicad_sch")
		(attr exclude_from_pos_files exclude_from_bom)
		(fp_circle
			(center 0 0)
			(end 0.475 0)
			(stroke
				(width 0.05)
				(type default)
			)
			(fill no)
			(layer "F.CrtYd")
		)
		(fp_text user "License: Apache-2.0"
			(at -0.4 5.101 90)
			(layer "F.Fab")
			(effects
				(font
					(size 0.7 0.7)
					(thickness 0.15)
				)
				(justify left bottom)
			)
		)
		(fp_text user "${REFERENCE}"
			(at -0.4 2.7 90)
			(layer "F.Fab")
			(effects
				(font
					(size 0.7 0.7)
					(thickness 0.15)
				)
				(justify left bottom)
			)
		)
		(fp_text user "Author: Antmicro"
			(at -0.4 3.901 90)
			(layer "F.Fab")
			(effects
				(font
					(size 0.7 0.7)
					(thickness 0.15)
				)
				(justify left bottom)
			)
		)
		(pad "1" smd circle
			(at 0 0 90)
			(size 0.75 0.75)
			(layers "F.Cu" "F.Mask")
			(net 92 "/FPGA MSSIO/SUPPLY.SCL")
			(pinfunction "1")
			(pintype "passive")
		)
	)
	(footprint "antmicro-footprints:R_0402_1005Metric"
		(layer "F.Cu")
		(at 199.85 120.95 90)
		(descr "Resistor SMD 0402")
		(tags "resistor SMD 0402")
		(property "Reference" "R1"
			(at -0.27 1.33 90)
			(layer "F.SilkS")
			(effects
				(font
					(size 0.7 0.7)
					(thickness 0.15)
				)
				(justify left bottom)
			)
		)
		(property "Value" "R_100k_0402"
			(at -1.011843 1.772047 90)
			(layer "F.Fab")
			(hide yes)
			(effects
				(font
					(size 0.7 0.7)
					(thickness 0.15)
				)
				(justify left bottom)
			)
		)
		(property "Datasheet" "https://www.bourns.com/docs/product-datasheets/cr.pdf"
			(at 0 0 90)
			(layer "F.Fab")
			(hide yes)
			(effects
				(font
					(size 1.27 1.27)
					(thickness 0.15)
				)
			)
		)
		(property "Description" "SMD Chip Resistor, 100 kohm, ± 1%, 62.5 mW, 0402 [1005 Metric], Thick Film, General Purpose"
			(at 0 0 90)
			(layer "F.Fab")
			(hide yes)
			(effects
				(font
					(size 1.27 1.27)
					(thickness 0.15)
				)
			)
		)
		(property "Author" "Antmicro"
			(at 320.8 -78.9 0)
			(layer "F.Fab")
			(hide yes)
			(effects
				(font
					(size 1 1)
					(thickness 0.15)
				)
			)
		)
		(property "License" "Apache-2.0"
			(at 320.8 -78.9 0)
			(layer "F.Fab")
			(hide yes)
			(effects
				(font
					(size 1 1)
					(thickness 0.15)
				)
			)
		)
		(property "MPN" "CR0402-FX-1003GLF"
			(at 320.8 -78.9 0)
			(layer "F.Fab")
			(hide yes)
			(effects
				(font
					(size 1 1)
					(thickness 0.15)
				)
			)
		)
		(property "Manufacturer" "Bourns"
			(at 320.8 -78.9 0)
			(layer "F.Fab")
			(hide yes)
			(effects
				(font
					(size 1 1)
					(thickness 0.15)
				)
			)
		)
		(property "Public" ""
			(at 320.8 -78.9 0)
			(layer "F.Fab")
			(hide yes)
			(effects
				(font
					(size 1 1)
					(thickness 0.15)
				)
			)
		)
		(property "Tolerance" "1%"
			(at 320.8 -78.9 0)
			(layer "F.Fab")
			(hide yes)
			(effects
				(font
					(size 1 1)
					(thickness 0.15)
				)
			)
		)
		(property "Val" "100k"
			(at 320.8 -78.9 0)
			(layer "F.Fab")
			(hide yes)
			(effects
				(font
					(size 1 1)
					(thickness 0.15)
				)
			)
		)
		(sheetname "/Top Connector/")
		(sheetfile "top-connector.kicad_sch")
		(attr smd)
		(fp_rect
			(start -0.925 -0.47)
			(end 0.925 0.47)
			(stroke
				(width 0.05)
				(type default)
			)
			(fill no)
			(layer "F.CrtYd")
		)
		(fp_rect
			(start -0.5 -0.25)
			(end 0.5 0.25)
			(stroke
				(width 0.15)
				(type solid)
			)
			(fill no)
			(layer "F.Fab")
		)
		(fp_text user "Author: Antmicro"
			(at -0.95 4.169 90)
			(layer "F.Fab")
			(effects
				(font
					(size 0.7 0.7)
					(thickness 0.15)
				)
				(justify left bottom)
			)
		)
		(fp_text user "License: Apache-2.0"
			(at -0.95 5.169 90)
			(layer "F.Fab")
			(effects
				(font
					(size 0.7 0.7)
					(thickness 0.15)
				)
				(justify left bottom)
			)
		)
		(fp_text user "${REFERENCE}"
			(at -0.95 3.168 90)
			(layer "F.Fab")
			(effects
				(font
					(size 0.7 0.7)
					(thickness 0.15)
				)
				(justify left bottom)
			)
		)
		(pad "1" smd roundrect
			(at -0.48 0 90)
			(size 0.59 0.64)
			(layers "F.Cu" "F.Mask" "F.Paste")
			(roundrect_rratio 0.25)
			(net 50 "+3V3")
			(pintype "passive")
		)
		(pad "2" smd roundrect
			(at 0.48 0 90)
			(size 0.59 0.64)
			(layers "F.Cu" "F.Mask" "F.Paste")
			(roundrect_rratio 0.25)
			(net 34 "Net-(J1-Pad43)")
			(pintype "passive")
		)
	)
	(footprint "antmicro-footprints:TP_SMD_0.75mm"
		(layer "F.Cu")
		(at 221.73 150.5)
		(property "Reference" "TP33"
			(at 12.08 5.61 90)
			(layer "F.SilkS")
			(hide yes)
			(effects
				(font
					(size 0.7 0.7)
					(thickness 0.15)
				)
				(justify left bottom)
			)
		)
		(property "Value" "TP_0.75mm_SMD"
			(at 0 1.2 0)
			(layer "F.Fab")
			(hide yes)
			(effects
				(font
					(size 0.7 0.7)
					(thickness 0.15)
				)
				(justify left bottom)
			)
		)
		(property "Description" "SMT test point"
			(at 0 0 0)
			(layer "F.Fab")
			(hide yes)
			(effects
				(font
					(size 1.27 1.27)
					(thickness 0.15)
				)
			)
		)
		(property "Author" "Antmicro"
			(at 0 0 0)
			(layer "F.Fab")
			(hide yes)
			(effects
				(font
					(size 1 1)
					(thickness 0.15)
				)
			)
		)
		(property "License" "Apache-2.0"
			(at 0 0 0)
			(layer "F.Fab")
			(hide yes)
			(effects
				(font
					(size 1 1)
					(thickness 0.15)
				)
			)
		)
		(property "MPN" ""
			(at 0 0 0)
			(layer "F.Fab")
			(hide yes)
			(effects
				(font
					(size 1 1)
					(thickness 0.15)
				)
			)
		)
		(property "Manufacturer" ""
			(at 0 0 0)
			(layer "F.Fab")
			(hide yes)
			(effects
				(font
					(size 1 1)
					(thickness 0.15)
				)
			)
		)
		(property "Public" "False"
			(at 0 0 0)
			(layer "F.Fab")
			(hide yes)
			(effects
				(font
					(size 1 1)
					(thickness 0.15)
				)
			)
		)
		(sheetname "/WiFi_Bluetooth/")
		(sheetfile "wifi_bt.kicad_sch")
		(attr exclude_from_pos_files exclude_from_bom)
		(fp_circle
			(center 0 0)
			(end 0.475 0)
			(stroke
				(width 0.05)
				(type default)
			)
			(fill no)
			(layer "F.CrtYd")
		)
		(fp_text user "License: Apache-2.0"
			(at -0.4 5.101 0)
			(layer "F.Fab")
			(effects
				(font
					(size 0.7 0.7)
					(thickness 0.15)
				)
				(justify left bottom)
			)
		)
		(fp_text user "${REFERENCE}"
			(at -0.4 2.7 0)
			(layer "F.Fab")
			(effects
				(font
					(size 0.7 0.7)
					(thickness 0.15)
				)
				(justify left bottom)
			)
		)
		(fp_text user "Author: Antmicro"
			(at -0.4 3.901 0)
			(layer "F.Fab")
			(effects
				(font
					(size 0.7 0.7)
					(thickness 0.15)
				)
				(justify left bottom)
			)
		)
		(pad "1" smd circle
			(at 0 0)
			(size 0.75 0.75)
			(layers "F.Cu" "F.Mask")
			(net 530 "Net-(U26A-GPIO_1)")
			(pinfunction "1")
			(pintype "passive")
		)
	)
	(footprint "antmicro-footprints:Oscillator_SMD_Microchip_DSC1103DI2_2.5x2x0.85mm"
		(layer "F.Cu")
		(at 222.8 122.9 180)
		(tags "DSC1123DI2-125.0000 ")
		(property "Reference" "Y3"
			(at -2.12 -0.04 90)
			(unlocked yes)
			(layer "F.SilkS")
			(effects
				(font
					(size 0.7 0.7)
					(thickness 0.15)
				)
				(justify left bottom)
			)
		)
		(property "Value" "Oscillator_125MHz_DSC1103DI2"
			(at 2.75 1.75 180)
			(unlocked yes)
			(layer "F.Fab")
			(hide yes)
			(effects
				(font
					(size 0.7 0.7)
					(thickness 0.15)
				)
				(justify left bottom)
			)
		)
		(property "Datasheet" "https://ww1.microchip.com/downloads/aemDocuments/documents/TCG/ProductDocuments/DataSheets/DSC1103-23-Low-Jitter-Precision-LVDS-Oscillator-DS20005745C.pdf"
			(at 0 0 180)
			(layer "F.Fab")
			(hide yes)
			(effects
				(font
					(size 1.27 1.27)
					(thickness 0.15)
				)
			)
		)
		(property "Description" "125 MHz XO (Standard) LVDS Oscillator 3.3V Enable/Disable 6-SMD, No Lead"
			(at 0 0 180)
			(layer "F.Fab")
			(hide yes)
			(effects
				(font
					(size 1.27 1.27)
					(thickness 0.15)
				)
			)
		)
		(property "Author" "Antmicro"
			(at 445.6 245.8 0)
			(layer "F.Fab")
			(hide yes)
			(effects
				(font
					(size 1 1)
					(thickness 0.15)
				)
			)
		)
		(property "License" "Apache-2.0"
			(at 445.6 245.8 0)
			(layer "F.Fab")
			(hide yes)
			(effects
				(font
					(size 1 1)
					(thickness 0.15)
				)
			)
		)
		(property "MPN" "DSC1103DI2-125.0000"
			(at 445.6 245.8 0)
			(layer "F.Fab")
			(hide yes)
			(effects
				(font
					(size 1 1)
					(thickness 0.15)
				)
			)
		)
		(property "Manufacturer" "Microchip Technology"
			(at 445.6 245.8 0)
			(layer "F.Fab")
			(hide yes)
			(effects
				(font
					(size 1 1)
					(thickness 0.15)
				)
			)
		)
		(property "Public" ""
			(at 445.6 245.8 0)
			(layer "F.Fab")
			(hide yes)
			(effects
				(font
					(size 1 1)
					(thickness 0.15)
				)
			)
		)
		(property "Val" "125 MHz"
			(at 445.6 245.8 0)
			(layer "F.Fab")
			(hide yes)
			(effects
				(font
					(size 1 1)
					(thickness 0.15)
				)
			)
		)
		(sheetname "/FPGA MSS/")
		(sheetfile "fpga-mss.kicad_sch")
		(attr smd)
		(fp_circle
			(center -1.7 -0.825)
			(end -1.65 -0.825)
			(stroke
				(width 0.15)
				(type solid)
			)
			(fill yes)
			(layer "F.SilkS")
		)
		(fp_rect
			(start -1.25 -1.35)
			(end 1.25 1.35)
			(stroke
				(width 0.05)
				(type solid)
			)
			(fill no)
			(layer "F.CrtYd")
		)
		(fp_line
			(start 1 1.25)
			(end 1 -1.25)
			(stroke
				(width 0.15)
				(type solid)
			)
			(layer "F.Fab")
		)
		(fp_line
			(start 1 -1.25)
			(end -1 -1.25)
			(stroke
				(width 0.15)
				(type solid)
			)
			(layer "F.Fab")
		)
		(fp_line
			(start -1 1.25)
			(end 1 1.25)
			(stroke
				(width 0.15)
				(type solid)
			)
			(layer "F.Fab")
		)
		(fp_line
			(start -1 -1.25)
			(end -1 1.25)
			(stroke
				(width 0.15)
				(type solid)
			)
			(layer "F.Fab")
		)
		(fp_arc
			(start 0.305 -1.25)
			(mid 0 -0.945)
			(end -0.305 -1.25)
			(stroke
				(width 0.15)
				(type solid)
			)
			(layer "F.Fab")
		)
		(fp_circle
			(center -0.3 -0.825)
			(end -0.3 -0.825)
			(stroke
				(width 0.15)
				(type solid)
			)
			(fill no)
			(layer "F.Fab")
		)
		(fp_text user "Author: Antmicro"
			(at -1.75 4.95 180)
			(layer "F.Fab")
			(effects
				(font
					(size 0.7 0.7)
					(thickness 0.15)
				)
				(justify left bottom)
			)
		)
		(fp_text user "License: Apache-2.0"
			(at -1.75 6.15 180)
			(layer "F.Fab")
			(effects
				(font
					(size 0.7 0.7)
					(thickness 0.15)
				)
				(justify left bottom)
			)
		)
		(fp_text user "${REFERENCE}"
			(at -1.75 3.75 180)
			(unlocked yes)
			(layer "F.Fab")
			(effects
				(font
					(size 0.7 0.7)
					(thickness 0.15)
				)
				(justify left bottom)
			)
		)
		(pad "1" smd rect
			(at -0.725 -0.825 180)
			(size 0.85 0.65)
			(layers "F.Cu" "F.Mask" "F.Paste")
			(net 50 "+3V3")
			(pinfunction "EN")
			(pintype "input")
		)
		(pad "2" smd oval
			(at -0.725 0 180)
			(size 0.85 0.25)
			(layers "F.Cu" "F.Mask" "F.Paste")
			(net 575 "unconnected-(Y3-NC-Pad2)")
			(pinfunction "NC")
			(pintype "no_connect")
		)
		(pad "3" smd rect
			(at -0.725 0.825 180)
			(size 0.85 0.65)
			(layers "F.Cu" "F.Mask" "F.Paste")
			(net 417 "GND")
			(pinfunction "GND")
			(pintype "power_in")
		)
		(pad "4" smd rect
			(at 0.725 0.825 180)
			(size 0.85 0.65)
			(layers "F.Cu" "F.Mask" "F.Paste")
			(net 301 "/FPGA MSS/MSS_CLK_P")
			(pinfunction "OUT+")
			(pintype "output")
		)
		(pad "5" smd oval
			(at 0.725 0 180)
			(size 0.85 0.25)
			(layers "F.Cu" "F.Mask" "F.Paste")
			(net 302 "/FPGA MSS/MSS_CLK_N")
			(pinfunction "OUT-")
			(pintype "output")
		)
		(pad "6" smd rect
			(at 0.725 -0.825 180)
			(size 0.85 0.65)
			(layers "F.Cu" "F.Mask" "F.Paste")
			(net 50 "+3V3")
			(pinfunction "VCC")
			(pintype "power_in")
		)
	)
	(footprint "antmicro-footprints:FB_0402_1005Metric"
		(layer "F.Cu")
		(at 208.085 147.775)
		(descr "Ferrite Bead SMD 0402")
		(tags "ferrite bead SMD 0402")
		(property "Reference" "FB9"
			(at -4.16 6.54 90)
			(layer "F.SilkS")
			(effects
				(font
					(size 0.7 0.7)
					(thickness 0.15)
				)
				(justify left bottom)
			)
		)
		(property "Value" "FB_120Z_1.2A_TDK-MPZ_0402"
			(at 0 1.4 0)
			(layer "F.Fab")
			(hide yes)
			(effects
				(font
					(size 0.7 0.7)
					(thickness 0.15)
				)
				(justify left bottom)
			)
		)
		(property "Datasheet" "https://product.tdk.com/en/search/emc/emc/beads/info?part_no=MPZ1005S121CT000"
			(at 0 0 0)
			(layer "F.Fab")
			(hide yes)
			(effects
				(font
					(size 1.27 1.27)
					(thickness 0.15)
				)
			)
		)
		(property "Description" "Ferrite Bead, 0402 [1005 Metric], 120 ohm, 1.2A, MPZ, 0.06 ohm, ± 25%, DC Power line"
			(at 0 0 0)
			(layer "F.Fab")
			(hide yes)
			(effects
				(font
					(size 1.27 1.27)
					(thickness 0.15)
				)
			)
		)
		(property "Author" "Antmicro"
			(at 0 0 0)
			(layer "F.Fab")
			(hide yes)
			(effects
				(font
					(size 1 1)
					(thickness 0.15)
				)
			)
		)
		(property "Current" ""
			(at 0 0 0)
			(layer "F.Fab")
			(hide yes)
			(effects
				(font
					(size 1 1)
					(thickness 0.15)
				)
			)
		)
		(property "License" "Apache-2.0"
			(at 0 0 0)
			(layer "F.Fab")
			(hide yes)
			(effects
				(font
					(size 1 1)
					(thickness 0.15)
				)
			)
		)
		(property "MPN" "MPZ1005S121CT000"
			(at 0 0 0)
			(layer "F.Fab")
			(hide yes)
			(effects
				(font
					(size 1 1)
					(thickness 0.15)
				)
			)
		)
		(property "Manufacturer" "TDK"
			(at 0 0 0)
			(layer "F.Fab")
			(hide yes)
			(effects
				(font
					(size 1 1)
					(thickness 0.15)
				)
			)
		)
		(property "Public" ""
			(at 0 0 0)
			(layer "F.Fab")
			(hide yes)
			(effects
				(font
					(size 1 1)
					(thickness 0.15)
				)
			)
		)
		(property "Val" "120Z/1.2A"
			(at 0 0 0)
			(layer "F.Fab")
			(hide yes)
			(effects
				(font
					(size 1 1)
					(thickness 0.15)
				)
			)
		)
		(sheetname "/MIPI CrossLink/")
		(sheetfile "crosslink.kicad_sch")
		(attr smd)
		(fp_rect
			(start -0.925 -0.47)
			(end 0.925 0.47)
			(stroke
				(width 0.05)
				(type default)
			)
			(fill no)
			(layer "F.CrtYd")
		)
		(fp_rect
			(start -0.5 -0.25)
			(end 0.5 0.25)
			(stroke
				(width 0.15)
				(type solid)
			)
			(fill no)
			(layer "F.Fab")
		)
		(fp_text user "Author: Antmicro"
			(at -0.95 4.169 0)
			(layer "F.Fab")
			(effects
				(font
					(size 0.7 0.7)
					(thickness 0.15)
				)
				(justify left bottom)
			)
		)
		(fp_text user "License: Apache-2.0"
			(at -0.95 5.169 0)
			(layer "F.Fab")
			(effects
				(font
					(size 0.7 0.7)
					(thickness 0.15)
				)
				(justify left bottom)
			)
		)
		(fp_text user "${REFERENCE}"
			(at -0.95 3.168 0)
			(layer "F.Fab")
			(effects
				(font
					(size 0.7 0.7)
					(thickness 0.15)
				)
				(justify left bottom)
			)
		)
		(pad "1" smd roundrect
			(at -0.48 0)
			(size 0.59 0.64)
			(layers "F.Cu" "F.Mask" "F.Paste")
			(roundrect_rratio 0.25)
			(net 176 "/MIPI CrossLink/CL_VCC")
			(pintype "passive")
		)
		(pad "2" smd roundrect
			(at 0.48 0)
			(size 0.59 0.64)
			(layers "F.Cu" "F.Mask" "F.Paste")
			(roundrect_rratio 0.25)
			(net 96 "+1V2")
			(pintype "passive")
		)
	)
	(footprint "antmicro-footprints:TP_SMD_0.75mm"
		(layer "F.Cu")
		(at 223.635 149.23)
		(property "Reference" "TP15"
			(at 13.305 5.98 90)
			(layer "F.SilkS")
			(hide yes)
			(effects
				(font
					(size 0.7 0.7)
					(thickness 0.15)
				)
				(justify left bottom)
			)
		)
		(property "Value" "TP_0.75mm_SMD"
			(at 0 1.2 0)
			(layer "F.Fab")
			(hide yes)
			(effects
				(font
					(size 0.7 0.7)
					(thickness 0.15)
				)
				(justify left bottom)
			)
		)
		(property "Description" "SMT test point"
			(at 0 0 0)
			(layer "F.Fab")
			(hide yes)
			(effects
				(font
					(size 1.27 1.27)
					(thickness 0.15)
				)
			)
		)
		(property "Author" "Antmicro"
			(at 0 0 0)
			(layer "F.Fab")
			(hide yes)
			(effects
				(font
					(size 1 1)
					(thickness 0.15)
				)
			)
		)
		(property "License" "Apache-2.0"
			(at 0 0 0)
			(layer "F.Fab")
			(hide yes)
			(effects
				(font
					(size 1 1)
					(thickness 0.15)
				)
			)
		)
		(property "MPN" ""
			(at 0 0 0)
			(layer "F.Fab")
			(hide yes)
			(effects
				(font
					(size 1 1)
					(thickness 0.15)
				)
			)
		)
		(property "Manufacturer" ""
			(at 0 0 0)
			(layer "F.Fab")
			(hide yes)
			(effects
				(font
					(size 1 1)
					(thickness 0.15)
				)
			)
		)
		(property "Public" "False"
			(at 0 0 0)
			(layer "F.Fab")
			(hide yes)
			(effects
				(font
					(size 1 1)
					(thickness 0.15)
				)
			)
		)
		(sheetname "/WiFi_Bluetooth/")
		(sheetfile "wifi_bt.kicad_sch")
		(attr exclude_from_pos_files exclude_from_bom)
		(fp_circle
			(center 0 0)
			(end 0.475 0)
			(stroke
				(width 0.05)
				(type default)
			)
			(fill no)
			(layer "F.CrtYd")
		)
		(fp_text user "${REFERENCE}"
			(at -0.4 2.7 0)
			(layer "F.Fab")
			(effects
				(font
					(size 0.7 0.7)
					(thickness 0.15)
				)
				(justify left bottom)
			)
		)
		(fp_text user "Author: Antmicro"
			(at -0.4 3.901 0)
			(layer "F.Fab")
			(effects
				(font
					(size 0.7 0.7)
					(thickness 0.15)
				)
				(justify left bottom)
			)
		)
		(fp_text user "License: Apache-2.0"
			(at -0.4 5.101 0)
			(layer "F.Fab")
			(effects
				(font
					(size 0.7 0.7)
					(thickness 0.15)
				)
				(justify left bottom)
			)
		)
		(pad "1" smd circle
			(at 0 0)
			(size 0.75 0.75)
			(layers "F.Cu" "F.Mask")
			(net 520 "Net-(U26A-BT_PCM_SYNC)")
			(pinfunction "1")
			(pintype "passive")
		)
	)
	(footprint "antmicro-footprints:C_0402_1005Metric"
		(layer "F.Cu")
		(at 179.718763 148.663922 180)
		(descr "Capacitor SMD 0402")
		(tags "capacitor SMD 0402")
		(property "Reference" "C88"
			(at -1.341237 -1.286078 0)
			(layer "F.SilkS")
			(effects
				(font
					(size 0.7 0.7)
					(thickness 0.15)
				)
				(justify right bottom)
			)
		)
		(property "Value" "C_22u_0402"
			(at -1.022927 2.155213 0)
			(layer "F.Fab")
			(hide yes)
			(effects
				(font
					(size 0.7 0.7)
					(thickness 0.15)
				)
				(justify right bottom)
			)
		)
		(property "Datasheet" "https://www.murata.com/products/productdetail?partno=GRM158R60J226ME01%23"
			(at 0 0 180)
			(layer "F.Fab")
			(hide yes)
			(effects
				(font
					(size 1.27 1.27)
					(thickness 0.15)
				)
			)
		)
		(property "Description" "SMD Multilayer Ceramic Capacitor, 22 uF, 4 V, 0402 [1005 Metric], X6S"
			(at 0 0 180)
			(layer "F.Fab")
			(hide yes)
			(effects
				(font
					(size 1.27 1.27)
					(thickness 0.15)
				)
			)
		)
		(property "Author" "Antmicro"
			(at 359.437526 297.327844 0)
			(layer "F.Fab")
			(hide yes)
			(effects
				(font
					(size 1 1)
					(thickness 0.15)
				)
			)
		)
		(property "Dielectric" ""
			(at 359.437526 297.327844 0)
			(layer "F.Fab")
			(hide yes)
			(effects
				(font
					(size 1 1)
					(thickness 0.15)
				)
			)
		)
		(property "License" "Apache-2.0"
			(at 359.437526 297.327844 0)
			(layer "F.Fab")
			(hide yes)
			(effects
				(font
					(size 1 1)
					(thickness 0.15)
				)
			)
		)
		(property "MPN" "GRM158R60J226ME01D"
			(at 359.437526 297.327844 0)
			(layer "F.Fab")
			(hide yes)
			(effects
				(font
					(size 1 1)
					(thickness 0.15)
				)
			)
		)
		(property "Manufacturer" "Murata"
			(at 359.437526 297.327844 0)
			(layer "F.Fab")
			(hide yes)
			(effects
				(font
					(size 1 1)
					(thickness 0.15)
				)
			)
		)
		(property "Public" ""
			(at 359.437526 297.327844 0)
			(layer "F.Fab")
			(hide yes)
			(effects
				(font
					(size 1 1)
					(thickness 0.15)
				)
			)
		)
		(property "Val" "22u"
			(at 359.437526 297.327844 0)
			(layer "F.Fab")
			(hide yes)
			(effects
				(font
					(size 1 1)
					(thickness 0.15)
				)
			)
		)
		(property "Voltage" ""
			(at 359.437526 297.327844 0)
			(layer "F.Fab")
			(hide yes)
			(effects
				(font
					(size 1 1)
					(thickness 0.15)
				)
			)
		)
		(sheetname "/Supply/")
		(sheetfile "supply.kicad_sch")
		(attr smd)
		(fp_rect
			(start -0.925 -0.47)
			(end 0.925 0.47)
			(stroke
				(width 0.05)
				(type default)
			)
			(fill no)
			(layer "F.CrtYd")
		)
		(fp_line
			(start 0.504 0.248)
			(end -0.494 0.248)
			(stroke
				(width 0.15)
				(type solid)
			)
			(layer "F.Fab")
		)
		(fp_line
			(start 0.504 -0.25)
			(end 0.504 0.248)
			(stroke
				(width 0.15)
				(type solid)
			)
			(layer "F.Fab")
		)
		(fp_line
			(start -0.494 0.248)
			(end -0.494 -0.25)
			(stroke
				(width 0.15)
				(type solid)
			)
			(layer "F.Fab")
		)
		(fp_line
			(start -0.494 -0.25)
			(end 0.504 -0.25)
			(stroke
				(width 0.15)
				(type solid)
			)
			(layer "F.Fab")
		)
		(fp_text user "Author: Antmicro"
			(at -0.939 3.399 180)
			(layer "F.Fab")
			(effects
				(font
					(size 0.7 0.7)
					(thickness 0.15)
				)
				(justify left bottom)
			)
		)
		(fp_text user "${REFERENCE}"
			(at -0.939 4.599 180)
			(layer "F.Fab")
			(effects
				(font
					(size 0.7 0.7)
					(thickness 0.15)
				)
				(justify left bottom)
			)
		)
		(fp_text user "License: Apache-2.0"
			(at -0.939 5.799 180)
			(layer "F.Fab")
			(effects
				(font
					(size 0.7 0.7)
					(thickness 0.15)
				)
				(justify left bottom)
			)
		)
		(pad "1" smd roundrect
			(at -0.48 0 180)
			(size 0.59 0.64)
			(layers "F.Cu" "F.Mask" "F.Paste")
			(roundrect_rratio 0.25)
			(net 417 "GND")
			(pintype "passive")
		)
		(pad "2" smd roundrect
			(at 0.48 0 180)
			(size 0.59 0.64)
			(layers "F.Cu" "F.Mask" "F.Paste")
			(roundrect_rratio 0.25)
			(net 90 "+5V")
			(pintype "passive")
		)
	)
	(footprint "antmicro-footprints:Fiducial_1mm_Mask2mm"
		(layer "F.Cu")
		(at 228.7 150.5)
		(descr "Circular Fiducial, 1mm bare copper, 3mm soldermask opening")
		(tags "fiducial")
		(property "Reference" "FD5"
			(at 0 -1.4 0)
			(layer "F.SilkS")
			(hide yes)
			(effects
				(font
					(size 0.7 0.7)
					(thickness 0.15)
				)
				(justify left bottom)
			)
		)
		(property "Value" "Fiducial_1mm_Mask2mm"
			(at 0 2.2 0)
			(layer "F.Fab")
			(hide yes)
			(effects
				(font
					(size 0.7 0.7)
					(thickness 0.15)
				)
				(justify left bottom)
			)
		)
		(property "Description" "Fiducial mask "
			(at 0 0 0)
			(layer "F.Fab")
			(hide yes)
			(effects
				(font
					(size 1.27 1.27)
					(thickness 0.15)
				)
			)
		)
		(property "Author" "Antmicro"
			(at 0 0 0)
			(layer "F.Fab")
			(hide yes)
			(effects
				(font
					(size 1 1)
					(thickness 0.15)
				)
			)
		)
		(property "License" "Apache-2.0"
			(at 0 0 0)
			(layer "F.Fab")
			(hide yes)
			(effects
				(font
					(size 1 1)
					(thickness 0.15)
				)
			)
		)
		(property "exclude_from_bom" ""
			(at 0 0 0)
			(layer "F.Fab")
			(hide yes)
			(effects
				(font
					(size 1 1)
					(thickness 0.15)
				)
			)
		)
		(sheetfile "polarfire-som.kicad_sch")
		(attr board_only exclude_from_pos_files exclude_from_bom)
		(fp_circle
			(center 0 0)
			(end 1.24 0)
			(stroke
				(width 0.05)
				(type solid)
			)
			(fill no)
			(layer "F.CrtYd")
		)
		(fp_circle
			(center 0 0)
			(end 0.999 0)
			(stroke
				(width 0.15)
				(type solid)
			)
			(fill no)
			(layer "F.Fab")
		)
		(fp_text user "${REFERENCE}"
			(at -1.25 4.603 0)
			(layer "F.Fab")
			(effects
				(font
					(size 0.7 0.7)
					(thickness 0.15)
				)
				(justify left bottom)
			)
		)
		(fp_text user "Author: Antmicro"
			(at -1.25 5.803 0)
			(layer "F.Fab")
			(effects
				(font
					(size 0.7 0.7)
					(thickness 0.15)
				)
				(justify left bottom)
			)
		)
		(fp_text user "License: Apache-2.0"
			(at -1.25 7.003 0)
			(layer "F.Fab")
			(effects
				(font
					(size 0.7 0.7)
					(thickness 0.15)
				)
				(justify left bottom)
			)
		)
		(pad "" smd circle
			(at 0 0)
			(size 1 1)
			(layers "F.Cu" "F.Mask")
			(solder_mask_margin 0.5)
			(clearance 0.5)
		)
	)
	(footprint "antmicro-footprints:4x0R_0402_array_EXB28V"
		(layer "F.Cu")
		(at 195.61 144.45 180)
		(property "Reference" "R107"
			(at -1.515 1.95 0)
			(layer "F.SilkS")
			(effects
				(font
					(size 0.7 0.7)
					(thickness 0.15)
				)
				(justify right top)
			)
		)
		(property "Value" "4x0R_0402_array"
			(at 0.6604 2.8194 0)
			(layer "F.Fab")
			(hide yes)
			(effects
				(font
					(size 0.7 0.7)
					(thickness 0.15)
				)
				(justify right top)
			)
		)
		(property "Datasheet" "https://industrial.panasonic.com/cdbs/www-data/pdf/AOC0000/AOC0000C14.pdf"
			(at 0 0 0)
			(layer "F.Fab")
			(hide yes)
			(effects
				(font
					(size 1.27 1.27)
					(thickness 0.15)
				)
			)
		)
		(property "Description" "Zero Ohm Network Resistor, Jumper, 0402 [1005 Metric], Thick Film, Isolated, Convex, 4 Resistors"
			(at 0 0 0)
			(layer "F.Fab")
			(hide yes)
			(effects
				(font
					(size 1.27 1.27)
					(thickness 0.15)
				)
			)
		)
		(property "MPN" "EXB28VR000X"
			(at 0 0 180)
			(unlocked yes)
			(layer "F.Fab")
			(hide yes)
			(effects
				(font
					(size 1 1)
					(thickness 0.15)
				)
			)
		)
		(property "Manufacturer" "Panasonic"
			(at 0 0 180)
			(unlocked yes)
			(layer "F.Fab")
			(hide yes)
			(effects
				(font
					(size 1 1)
					(thickness 0.15)
				)
			)
		)
		(property "Author" "Antmicro"
			(at 0 0 180)
			(unlocked yes)
			(layer "F.Fab")
			(hide yes)
			(effects
				(font
					(size 1 1)
					(thickness 0.15)
				)
			)
		)
		(property "License" "Apache-2.0"
			(at 0 0 180)
			(unlocked yes)
			(layer "F.Fab")
			(hide yes)
			(effects
				(font
					(size 1 1)
					(thickness 0.15)
				)
			)
		)
		(property "Val" "4x0R_0402"
			(at 0 0 180)
			(unlocked yes)
			(layer "F.Fab")
			(hide yes)
			(effects
				(font
					(size 1 1)
					(thickness 0.15)
				)
			)
		)
		(sheetname "/HDMI/")
		(sheetfile "hdmi.kicad_sch")
		(attr smd)
		(fp_line
			(start 1.15 0.15)
			(end 1.15 -0.15)
			(stroke
				(width 0.15)
				(type solid)
			)
			(layer "F.SilkS")
		)
		(fp_line
			(start -1.15 -0.15)
			(end -1.15 0.15)
			(stroke
				(width 0.15)
				(type solid)
			)
			(layer "F.SilkS")
		)
		(fp_circle
			(center -0.9652 0.9144)
			(end -0.9144 0.9144)
			(stroke
				(width 0.15)
				(type solid)
			)
			(fill no)
			(layer "F.SilkS")
		)
		(fp_line
			(start 1.25 0.8)
			(end 1.25 -0.8)
			(stroke
				(width 0.05)
				(type solid)
			)
			(layer "F.CrtYd")
		)
		(fp_line
			(start 1.25 -0.8)
			(end -1.25 -0.8)
			(stroke
				(width 0.05)
				(type solid)
			)
			(layer "F.CrtYd")
		)
		(fp_line
			(start -1.25 0.8)
			(end 1.25 0.8)
			(stroke
				(width 0.05)
				(type solid)
			)
			(layer "F.CrtYd")
		)
		(fp_line
			(start -1.25 -0.8)
			(end -1.25 0.8)
			(stroke
				(width 0.05)
				(type solid)
			)
			(layer "F.CrtYd")
		)
		(fp_line
			(start 1 0.5)
			(end -1 0.5)
			(stroke
				(width 0.15)
				(type solid)
			)
			(layer "F.Fab")
		)
		(fp_line
			(start 1 -0.5)
			(end 1 0.5)
			(stroke
				(width 0.15)
				(type solid)
			)
			(layer "F.Fab")
		)
		(fp_line
			(start -1 0.5)
			(end -1 -0.5)
			(stroke
				(width 0.15)
				(type solid)
			)
			(layer "F.Fab")
		)
		(fp_line
			(start -1 0)
			(end -0.508 0.5)
			(stroke
				(width 0.15)
				(type solid)
			)
			(layer "F.Fab")
		)
		(fp_line
			(start -1 -0.5)
			(end 1 -0.5)
			(stroke
				(width 0.15)
				(type solid)
			)
			(layer "F.Fab")
		)
		(fp_circle
			(center -0.9652 0.9144)
			(end -0.9144 0.9144)
			(stroke
				(width 0.15)
				(type solid)
			)
			(fill no)
			(layer "F.Fab")
		)
		(fp_text user "Author: Antmicro"
			(at -1.25 6.0194 0)
			(layer "F.Fab")
			(effects
				(font
					(size 0.7 0.7)
					(thickness 0.15)
				)
				(justify right top)
			)
		)
		(fp_text user "${REFERENCE}"
			(at -1.25 4.8194 0)
			(layer "F.Fab")
			(effects
				(font
					(size 0.7 0.7)
					(thickness 0.15)
				)
				(justify right top)
			)
		)
		(fp_text user "License: Apache-2.0"
			(at -1.25 7.2194 0)
			(layer "F.Fab")
			(effects
				(font
					(size 0.7 0.7)
					(thickness 0.15)
				)
				(justify right top)
			)
		)
		(pad "1" smd roundrect
			(at -0.8875 0.45 180)
			(size 0.525 0.5)
			(layers "F.Cu" "F.Mask" "F.Paste")
			(roundrect_rratio 0.25)
			(net 60 "/FPGA GPIO/HDMI_FPGA.TX2_N")
			(pinfunction "R1.1")
			(pintype "passive")
		)
		(pad "2" smd roundrect
			(at -0.25 0.46 180)
			(size 0.25 0.48)
			(layers "F.Cu" "F.Mask" "F.Paste")
			(roundrect_rratio 0.25)
			(net 82 "/FPGA GPIO/HDMI_FPGA.TX2_P")
			(pinfunction "R2.1")
			(pintype "passive")
		)
		(pad "3" smd roundrect
			(at 0.25 0.46 180)
			(size 0.25 0.48)
			(layers "F.Cu" "F.Mask" "F.Paste")
			(roundrect_rratio 0.25)
			(net 83 "/FPGA GPIO/HDMI_FPGA.TX1_N")
			(pinfunction "R3.1")
			(pintype "passive")
		)
		(pad "4" smd roundrect
			(at 0.8875 0.45 180)
			(size 0.525 0.5)
			(layers "F.Cu" "F.Mask" "F.Paste")
			(roundrect_rratio 0.25)
			(net 84 "/FPGA GPIO/HDMI_FPGA.TX1_P")
			(pinfunction "R4.1")
			(pintype "passive")
		)
		(pad "5" smd roundrect
			(at 0.8875 -0.45 180)
			(size 0.525 0.5)
			(layers "F.Cu" "F.Mask" "F.Paste")
			(roundrect_rratio 0.25)
			(net 546 "/HDMI/PI3HDX_C_TX1_P")
			(pinfunction "R4.2")
			(pintype "passive")
		)
		(pad "6" smd roundrect
			(at 0.25 -0.46 180)
			(size 0.25 0.48)
			(layers "F.Cu" "F.Mask" "F.Paste")
			(roundrect_rratio 0.25)
			(net 550 "/HDMI/PI3HDX_C_TX1_N")
			(pinfunction "R3.2")
			(pintype "passive")
		)
		(pad "7" smd roundrect
			(at -0.25 -0.46 180)
			(size 0.25 0.48)
			(layers "F.Cu" "F.Mask" "F.Paste")
			(roundrect_rratio 0.25)
			(net 57 "/HDMI/PI3HDX_C_TX2_P")
			(pinfunction "R2.2")
			(pintype "passive")
		)
		(pad "8" smd roundrect
			(at -0.8875 -0.45 180)
			(size 0.525 0.5)
			(layers "F.Cu" "F.Mask" "F.Paste")
			(roundrect_rratio 0.25)
			(net 549 "/HDMI/PI3HDX_C_TX2_N")
			(pinfunction "R1.2")
			(pintype "passive")
		)
	)
	(footprint "antmicro-footprints:C_0402_1005Metric"
		(layer "F.Cu")
		(at 175.475 140.9675 90)
		(descr "Capacitor SMD 0402")
		(tags "capacitor SMD 0402")
		(property "Reference" "C99"
			(at 0.9675 0.445 90)
			(layer "F.SilkS")
			(effects
				(font
					(size 0.7 0.7)
					(thickness 0.15)
				)
				(justify left bottom)
			)
		)
		(property "Value" "C_22u_0402"
			(at -1.022927 2.155213 90)
			(layer "F.Fab")
			(hide yes)
			(effects
				(font
					(size 0.7 0.7)
					(thickness 0.15)
				)
				(justify left bottom)
			)
		)
		(property "Datasheet" "https://www.murata.com/products/productdetail?partno=GRM158R60J226ME01%23"
			(at 0 0 90)
			(layer "F.Fab")
			(hide yes)
			(effects
				(font
					(size 1.27 1.27)
					(thickness 0.15)
				)
			)
		)
		(property "Description" "SMD Multilayer Ceramic Capacitor, 22 uF, 4 V, 0402 [1005 Metric], X6S"
			(at 0 0 90)
			(layer "F.Fab")
			(hide yes)
			(effects
				(font
					(size 1.27 1.27)
					(thickness 0.15)
				)
			)
		)
		(property "Author" "Antmicro"
			(at 316.4425 -34.5075 0)
			(layer "F.Fab")
			(hide yes)
			(effects
				(font
					(size 1 1)
					(thickness 0.15)
				)
			)
		)
		(property "Dielectric" ""
			(at 316.4425 -34.5075 0)
			(layer "F.Fab")
			(hide yes)
			(effects
				(font
					(size 1 1)
					(thickness 0.15)
				)
			)
		)
		(property "License" "Apache-2.0"
			(at 316.4425 -34.5075 0)
			(layer "F.Fab")
			(hide yes)
			(effects
				(font
					(size 1 1)
					(thickness 0.15)
				)
			)
		)
		(property "MPN" "GRM158R60J226ME01D"
			(at 316.4425 -34.5075 0)
			(layer "F.Fab")
			(hide yes)
			(effects
				(font
					(size 1 1)
					(thickness 0.15)
				)
			)
		)
		(property "Manufacturer" "Murata"
			(at 316.4425 -34.5075 0)
			(layer "F.Fab")
			(hide yes)
			(effects
				(font
					(size 1 1)
					(thickness 0.15)
				)
			)
		)
		(property "Public" ""
			(at 316.4425 -34.5075 0)
			(layer "F.Fab")
			(hide yes)
			(effects
				(font
					(size 1 1)
					(thickness 0.15)
				)
			)
		)
		(property "Val" "22u"
			(at 316.4425 -34.5075 0)
			(layer "F.Fab")
			(hide yes)
			(effects
				(font
					(size 1 1)
					(thickness 0.15)
				)
			)
		)
		(property "Voltage" ""
			(at 316.4425 -34.5075 0)
			(layer "F.Fab")
			(hide yes)
			(effects
				(font
					(size 1 1)
					(thickness 0.15)
				)
			)
		)
		(sheetname "/Supply/")
		(sheetfile "supply.kicad_sch")
		(attr smd)
		(fp_rect
			(start -0.925 -0.47)
			(end 0.925 0.47)
			(stroke
				(width 0.05)
				(type default)
			)
			(fill no)
			(layer "F.CrtYd")
		)
		(fp_line
			(start 0.504 -0.25)
			(end 0.504 0.248)
			(stroke
				(width 0.15)
				(type solid)
			)
			(layer "F.Fab")
		)
		(fp_line
			(start -0.494 -0.25)
			(end 0.504 -0.25)
			(stroke
				(width 0.15)
				(type solid)
			)
			(layer "F.Fab")
		)
		(fp_line
			(start 0.504 0.248)
			(end -0.494 0.248)
			(stroke
				(width 0.15)
				(type solid)
			)
			(layer "F.Fab")
		)
		(fp_line
			(start -0.494 0.248)
			(end -0.494 -0.25)
			(stroke
				(width 0.15)
				(type solid)
			)
			(layer "F.Fab")
		)
		(fp_text user "Author: Antmicro"
			(at -0.939 3.399 90)
			(layer "F.Fab")
			(effects
				(font
					(size 0.7 0.7)
					(thickness 0.15)
				)
				(justify left bottom)
			)
		)
		(fp_text user "${REFERENCE}"
			(at -0.939 4.599 90)
			(layer "F.Fab")
			(effects
				(font
					(size 0.7 0.7)
					(thickness 0.15)
				)
				(justify left bottom)
			)
		)
		(fp_text user "License: Apache-2.0"
			(at -0.939 5.799 90)
			(layer "F.Fab")
			(effects
				(font
					(size 0.7 0.7)
					(thickness 0.15)
				)
				(justify left bottom)
			)
		)
		(pad "1" smd roundrect
			(at -0.48 0 90)
			(size 0.59 0.64)
			(layers "F.Cu" "F.Mask" "F.Paste")
			(roundrect_rratio 0.25)
			(net 417 "GND")
			(pintype "passive")
		)
		(pad "2" smd roundrect
			(at 0.48 0 90)
			(size 0.59 0.64)
			(layers "F.Cu" "F.Mask" "F.Paste")
			(roundrect_rratio 0.25)
			(net 209 "/Supply/SENSE1_P")
			(pintype "passive")
		)
	)
	(footprint "antmicro-footprints:BGA-80_7x7mm_Layout10x10_P0.65mm"
		(layer "F.Cu")
		(at 203.374 147.076 180)
		(property "Reference" "U16"
			(at 1.564 -4.684 0)
			(layer "F.SilkS")
			(effects
				(font
					(size 0.7 0.7)
					(thickness 0.15)
				)
				(justify right bottom)
			)
		)
		(property "Value" "CrossLink_LIF-MD6000-6JMG80I"
			(at 0 4.65 0)
			(layer "F.Fab")
			(hide yes)
			(effects
				(font
					(size 0.7 0.7)
					(thickness 0.15)
				)
				(justify right bottom)
			)
		)
		(property "Datasheet" "https://www.latticesemi.com/view_document?document_id=51662"
			(at 0 0 180)
			(layer "F.Fab")
			(hide yes)
			(effects
				(font
					(size 1.27 1.27)
					(thickness 0.15)
				)
			)
		)
		(property "Description" "FPGA, CrossLink, PLL37 I/O, 400 MHz, 5936 Cells, 1.14 V to 1.26 V, CTFBGA-80"
			(at 0 0 180)
			(layer "F.Fab")
			(hide yes)
			(effects
				(font
					(size 1.27 1.27)
					(thickness 0.15)
				)
			)
		)
		(property "Author" "Antmicro"
			(at 406.748 294.152 0)
			(layer "F.Fab")
			(hide yes)
			(effects
				(font
					(size 1 1)
					(thickness 0.15)
				)
			)
		)
		(property "License" "Apache-2.0"
			(at 406.748 294.152 0)
			(layer "F.Fab")
			(hide yes)
			(effects
				(font
					(size 1 1)
					(thickness 0.15)
				)
			)
		)
		(property "MPN" "LIF-MD6000-6JMG80I"
			(at 406.748 294.152 0)
			(layer "F.Fab")
			(hide yes)
			(effects
				(font
					(size 1 1)
					(thickness 0.15)
				)
			)
		)
		(property "Manufacturer" "Lattice Semiconductor"
			(at 406.748 294.152 0)
			(layer "F.Fab")
			(hide yes)
			(effects
				(font
					(size 1 1)
					(thickness 0.15)
				)
			)
		)
		(sheetname "/MIPI CrossLink/")
		(sheetfile "crosslink.kicad_sch")
		(attr smd)
		(fp_line
			(start 3.62 3.62)
			(end 3.62 1.87)
			(stroke
				(width 0.15)
				(type solid)
			)
			(layer "F.SilkS")
		)
		(fp_line
			(start 3.62 -3.621)
			(end 3.62 -1.871)
			(stroke
				(width 0.15)
				(type solid)
			)
			(layer "F.SilkS")
		)
		(fp_line
			(start 3.62 -3.621)
			(end 3.62 -1.871)
			(stroke
				(width 0.15)
				(type solid)
			)
			(layer "F.SilkS")
		)
		(fp_line
			(start 3.62 -3.621)
			(end 3.62 -1.871)
			(stroke
				(width 0.15)
				(type solid)
			)
			(layer "F.SilkS")
		)
		(fp_line
			(start 1.87 3.62)
			(end 3.62 3.62)
			(stroke
				(width 0.15)
				(type solid)
			)
			(layer "F.SilkS")
		)
		(fp_line
			(start 1.87 -3.621)
			(end 3.62 -3.621)
			(stroke
				(width 0.15)
				(type solid)
			)
			(layer "F.SilkS")
		)
		(fp_line
			(start 1.87 -3.621)
			(end 3.62 -3.621)
			(stroke
				(width 0.15)
				(type solid)
			)
			(layer "F.SilkS")
		)
		(fp_line
			(start 1.87 -3.621)
			(end 3.62 -3.621)
			(stroke
				(width 0.15)
				(type solid)
			)
			(layer "F.SilkS")
		)
		(fp_line
			(start -1.871 3.62)
			(end -3.621 3.62)
			(stroke
				(width 0.15)
				(type solid)
			)
			(layer "F.SilkS")
		)
		(fp_line
			(start -1.871 -3.621)
			(end -2.801 -3.621)
			(stroke
				(width 0.15)
				(type solid)
			)
			(layer "F.SilkS")
		)
		(fp_line
			(start -2.801 -3.621)
			(end -3.621 -2.801)
			(stroke
				(width 0.15)
				(type solid)
			)
			(layer "F.SilkS")
		)
		(fp_line
			(start -3.621 3.62)
			(end -3.621 1.87)
			(stroke
				(width 0.15)
				(type solid)
			)
			(layer "F.SilkS")
		)
		(fp_line
			(start -3.621 -2.801)
			(end -3.621 -1.871)
			(stroke
				(width 0.15)
				(type solid)
			)
			(layer "F.SilkS")
		)
		(fp_circle
			(center -2.925 -4.05)
			(end -2.875 -4.05)
			(stroke
				(width 0.15)
				(type solid)
			)
			(fill yes)
			(layer "F.SilkS")
		)
		(fp_rect
			(start -3.75 -3.75)
			(end 3.75 3.75)
			(stroke
				(width 0.05)
				(type solid)
			)
			(fill no)
			(layer "F.CrtYd")
		)
		(fp_line
			(start 3.499 3.499)
			(end 3.499 -3.5)
			(stroke
				(width 0.15)
				(type solid)
			)
			(layer "F.Fab")
		)
		(fp_line
			(start 3.499 -3.5)
			(end -2.5 -3.5)
			(stroke
				(width 0.15)
				(type solid)
			)
			(layer "F.Fab")
		)
		(fp_line
			(start -2.5 -3.5)
			(end -3.5 -2.5)
			(stroke
				(width 0.15)
				(type solid)
			)
			(layer "F.Fab")
		)
		(fp_line
			(start -3.5 3.499)
			(end 3.499 3.499)
			(stroke
				(width 0.15)
				(type solid)
			)
			(layer "F.Fab")
		)
		(fp_line
			(start -3.5 -2.5)
			(end -3.5 3.499)
			(stroke
				(width 0.15)
				(type solid)
			)
			(layer "F.Fab")
		)
		(fp_text user "Author: Antmicro"
			(at -3.75 9.05 180)
			(layer "F.Fab")
			(effects
				(font
					(size 0.7 0.7)
					(thickness 0.15)
				)
				(justify left bottom)
			)
		)
		(fp_text user "License: Apache-2.0"
			(at -3.75 6.65 180)
			(layer "F.Fab")
			(effects
				(font
					(size 0.7 0.7)
					(thickness 0.15)
				)
				(justify left bottom)
			)
		)
		(fp_text user "${REFERENCE}"
			(at -3.75 7.85 180)
			(layer "F.Fab")
			(effects
				(font
					(size 0.7 0.7)
					(thickness 0.15)
				)
				(justify left bottom)
			)
		)
		(pad "A1" smd circle
			(at -2.925 -2.925 180)
			(size 0.35 0.35)
			(layers "F.Cu" "F.Mask" "F.Paste")
			(net 197 "/Bottom Connector/DSI1.D2_N")
			(pinfunction "DPHY1_DN2")
			(pintype "bidirectional")
			(solder_mask_margin -0.025)
			(solder_paste_margin -0.025)
		)
		(pad "A2" smd circle
			(at -2.275 -2.925 180)
			(size 0.35 0.35)
			(layers "F.Cu" "F.Mask" "F.Paste")
			(net 146 "/Bottom Connector/DSI1.D0_N")
			(pinfunction "DPHY1_DN0")
			(pintype "bidirectional")
			(solder_mask_margin -0.025)
			(solder_paste_margin -0.025)
		)
		(pad "A3" smd circle
			(at -1.625 -2.925 180)
			(size 0.35 0.35)
			(layers "F.Cu" "F.Mask" "F.Paste")
			(net 162 "/Bottom Connector/DSI1.C_N")
			(pinfunction "DPHY1_CKN")
			(pintype "bidirectional")
			(solder_mask_margin -0.025)
			(solder_paste_margin -0.025)
		)
		(pad "A4" smd circle
			(at -0.975 -2.925 180)
			(size 0.35 0.35)
			(layers "F.Cu" "F.Mask" "F.Paste")
			(net 158 "/Bottom Connector/DSI1.D1_N")
			(pinfunction "DPHY1_DN1")
			(pintype "bidirectional")
			(solder_mask_margin -0.025)
			(solder_paste_margin -0.025)
		)
		(pad "A5" smd circle
			(at -0.325 -2.925 180)
			(size 0.35 0.35)
			(layers "F.Cu" "F.Mask" "F.Paste")
			(net 198 "/Bottom Connector/DSI1.D3_N")
			(pinfunction "DPHY1_DN3")
			(pintype "bidirectional")
			(solder_mask_margin -0.025)
			(solder_paste_margin -0.025)
		)
		(pad "A6" smd circle
			(at 0.325 -2.925 180)
			(size 0.35 0.35)
			(layers "F.Cu" "F.Mask" "F.Paste")
			(net 112 "/Bottom Connector/CAM1.D2_N")
			(pinfunction "DPHY0_DN2")
			(pintype "bidirectional")
			(solder_mask_margin -0.025)
			(solder_paste_margin -0.025)
		)
		(pad "A7" smd circle
			(at 0.975 -2.925 180)
			(size 0.35 0.35)
			(layers "F.Cu" "F.Mask" "F.Paste")
			(net 99 "/Bottom Connector/CAM1.D0_N")
			(pinfunction "DPHY0_DN0")
			(pintype "bidirectional")
			(solder_mask_margin -0.025)
			(solder_paste_margin -0.025)
		)
		(pad "A8" smd circle
			(at 1.625 -2.925 180)
			(size 0.35 0.35)
			(layers "F.Cu" "F.Mask" "F.Paste")
			(net 108 "/Bottom Connector/CAM1.C_N")
			(pinfunction "DPHY0_CKN")
			(pintype "bidirectional")
			(solder_mask_margin -0.025)
			(solder_paste_margin -0.025)
		)
		(pad "A9" smd circle
			(at 2.275 -2.925 180)
			(size 0.35 0.35)
			(layers "F.Cu" "F.Mask" "F.Paste")
			(net 106 "/Bottom Connector/CAM1.D1_N")
			(pinfunction "DPHY0_DN1")
			(pintype "bidirectional")
			(solder_mask_margin -0.025)
			(solder_paste_margin -0.025)
		)
		(pad "A10" smd circle
			(at 2.925 -2.925 180)
			(size 0.35 0.35)
			(layers "F.Cu" "F.Mask" "F.Paste")
			(net 116 "/Bottom Connector/CAM1.D3_N")
			(pinfunction "DPHY0_DN3")
			(pintype "bidirectional")
			(solder_mask_margin -0.025)
			(solder_paste_margin -0.025)
		)
		(pad "B1" smd circle
			(at -2.925 -2.275 180)
			(size 0.35 0.35)
			(layers "F.Cu" "F.Mask" "F.Paste")
			(net 199 "/Bottom Connector/DSI1.D2_P")
			(pinfunction "DPHY1_DP2")
			(pintype "bidirectional")
			(solder_mask_margin -0.025)
			(solder_paste_margin -0.025)
		)
		(pad "B2" smd circle
			(at -2.275 -2.275 180)
			(size 0.35 0.35)
			(layers "F.Cu" "F.Mask" "F.Paste")
			(net 156 "/Bottom Connector/DSI1.D0_P")
			(pinfunction "DPHY1_DP0")
			(pintype "bidirectional")
			(solder_mask_margin -0.025)
			(solder_paste_margin -0.025)
		)
		(pad "B3" smd circle
			(at -1.625 -2.275 180)
			(size 0.35 0.35)
			(layers "F.Cu" "F.Mask" "F.Paste")
			(net 195 "/Bottom Connector/DSI1.C_P")
			(pinfunction "DPHY1_CKP")
			(pintype "bidirectional")
			(solder_mask_margin -0.025)
			(solder_paste_margin -0.025)
		)
		(pad "B4" smd circle
			(at -0.975 -2.275 180)
			(size 0.35 0.35)
			(layers "F.Cu" "F.Mask" "F.Paste")
			(net 160 "/Bottom Connector/DSI1.D1_P")
			(pinfunction "DPHY1_DP1")
			(pintype "bidirectional")
			(solder_mask_margin -0.025)
			(solder_paste_margin -0.025)
		)
		(pad "B5" smd circle
			(at -0.325 -2.275 180)
			(size 0.35 0.35)
			(layers "F.Cu" "F.Mask" "F.Paste")
			(net 201 "/Bottom Connector/DSI1.D3_P")
			(pinfunction "DPHY1_DP3")
			(pintype "bidirectional")
			(solder_mask_margin -0.025)
			(solder_paste_margin -0.025)
		)
		(pad "B6" smd circle
			(at 0.325 -2.275 180)
			(size 0.35 0.35)
			(layers "F.Cu" "F.Mask" "F.Paste")
			(net 114 "/Bottom Connector/CAM1.D2_P")
			(pinfunction "DPHY0_DP2")
			(pintype "bidirectional")
			(solder_mask_margin -0.025)
			(solder_paste_margin -0.025)
		)
		(pad "B7" smd circle
			(at 0.975 -2.275 180)
			(size 0.35 0.35)
			(layers "F.Cu" "F.Mask" "F.Paste")
			(net 104 "/Bottom Connector/CAM1.D0_P")
			(pinfunction "DPHY0_DP0")
			(pintype "bidirectional")
			(solder_mask_margin -0.025)
			(solder_paste_margin -0.025)
		)
		(pad "B8" smd circle
			(at 1.625 -2.275 180)
			(size 0.35 0.35)
			(layers "F.Cu" "F.Mask" "F.Paste")
			(net 110 "/Bottom Connector/CAM1.C_P")
			(pinfunction "DPHY0_CKP")
			(pintype "bidirectional")
			(solder_mask_margin -0.025)
			(solder_paste_margin -0.025)
		)
		(pad "B9" smd circle
			(at 2.275 -2.275 180)
			(size 0.35 0.35)
			(layers "F.Cu" "F.Mask" "F.Paste")
			(net 107 "/Bottom Connector/CAM1.D1_P")
			(pinfunction "DPHY0_DP1")
			(pintype "bidirectional")
			(solder_mask_margin -0.025)
			(solder_paste_margin -0.025)
		)
		(pad "B10" smd circle
			(at 2.925 -2.275 180)
			(size 0.35 0.35)
			(layers "F.Cu" "F.Mask" "F.Paste")
			(net 119 "/Bottom Connector/CAM1.D3_P")
			(pinfunction "DPHY0_DP3")
			(pintype "bidirectional")
			(solder_mask_margin -0.025)
			(solder_paste_margin -0.025)
		)
		(pad "C1" smd circle
			(at -2.925 -1.625 180)
			(size 0.35 0.35)
			(layers "F.Cu" "F.Mask" "F.Paste")
			(net 417 "GND")
			(pinfunction "GND")
			(pintype "power_in")
			(solder_mask_margin -0.025)
			(solder_paste_margin -0.025)
		)
		(pad "C2" smd circle
			(at -2.275 -1.625 180)
			(size 0.35 0.35)
			(layers "F.Cu" "F.Mask" "F.Paste")
			(net 417 "GND")
			(pinfunction "GNDA_DPHY1")
			(pintype "power_in")
			(solder_mask_margin -0.025)
			(solder_paste_margin -0.025)
		)
		(pad "C9" smd circle
			(at 2.275 -1.625 180)
			(size 0.35 0.35)
			(layers "F.Cu" "F.Mask" "F.Paste")
			(net 417 "GND")
			(pinfunction "GNDA_DPHY0")
			(pintype "power_in")
			(solder_mask_margin -0.025)
			(solder_paste_margin -0.025)
		)
		(pad "C10" smd circle
			(at 2.925 -1.625 180)
			(size 0.35 0.35)
			(layers "F.Cu" "F.Mask" "F.Paste")
			(net 417 "GND")
			(pinfunction "GND")
			(pintype "passive")
			(solder_mask_margin -0.025)
			(solder_paste_margin -0.025)
		)
		(pad "D1" smd circle
			(at -2.925 -0.975 180)
			(size 0.35 0.35)
			(layers "F.Cu" "F.Mask" "F.Paste")
			(net 564 "/FPGA GPIO/Crosslink.SCL")
			(pinfunction "PB48/PCLKT0_1/USER_SCL")
			(pintype "bidirectional")
			(solder_mask_margin -0.025)
			(solder_paste_margin -0.025)
		)
		(pad "D2" smd circle
			(at -2.275 -0.975 180)
			(size 0.35 0.35)
			(layers "F.Cu" "F.Mask" "F.Paste")
			(net 211 "/MIPI CrossLink/CL_VCCPLL_DPHY1")
			(pinfunction "VCCPLL_DPHY1")
			(pintype "power_in")
			(solder_mask_margin -0.025)
			(solder_paste_margin -0.025)
		)
		(pad "D4" smd circle
			(at -0.975 -0.975 180)
			(size 0.35 0.35)
			(layers "F.Cu" "F.Mask" "F.Paste")
			(net 205 "/MIPI CrossLink/CL_VCCA_DPHY1")
			(pinfunction "VCCA_DPHY1")
			(pintype "power_in")
			(solder_mask_margin -0.025)
			(solder_paste_margin -0.025)
		)
		(pad "D5" smd circle
			(at -0.325 -0.975 180)
			(size 0.35 0.35)
			(layers "F.Cu" "F.Mask" "F.Paste")
			(net 103 "2V5_CL")
			(pinfunction "VCCAUX")
			(pintype "power_in")
			(solder_mask_margin -0.025)
			(solder_paste_margin -0.025)
		)
		(pad "D6" smd circle
			(at 0.325 -0.975 180)
			(size 0.35 0.35)
			(layers "F.Cu" "F.Mask" "F.Paste")
			(net 417 "GND")
			(pinfunction "GNDPLL_DPHY_X")
			(pintype "power_in")
			(solder_mask_margin -0.025)
			(solder_paste_margin -0.025)
		)
		(pad "D7" smd circle
			(at 0.975 -0.975 180)
			(size 0.35 0.35)
			(layers "F.Cu" "F.Mask" "F.Paste")
			(net 204 "/MIPI CrossLink/CL_VCCPLL_DPHY0")
			(pinfunction "VCCPLL_DPHY0")
			(pintype "bidirectional")
			(solder_mask_margin -0.025)
			(solder_paste_margin -0.025)
		)
		(pad "D9" smd circle
			(at 2.275 -0.975 180)
			(size 0.35 0.35)
			(layers "F.Cu" "F.Mask" "F.Paste")
			(net 154 "/FPGA HSIO/Crosslink_B2.D4")
			(pinfunction "PB16A/PCLKT2_0")
			(pintype "bidirectional")
			(solder_mask_margin -0.025)
			(solder_paste_margin -0.025)
		)
		(pad "D10" smd circle
			(at 2.925 -0.975 180)
			(size 0.35 0.35)
			(layers "F.Cu" "F.Mask" "F.Paste")
			(net 501 "unconnected-(U16-PB16B{slash}PCLKC2_0-PadD10)")
			(pinfunction "PB16B/PCLKC2_0")
			(pintype "bidirectional+no_connect")
			(solder_mask_margin -0.025)
			(solder_paste_margin -0.025)
		)
		(pad "E1" smd circle
			(at -2.925 -0.325 180)
			(size 0.35 0.35)
			(layers "F.Cu" "F.Mask" "F.Paste")
			(net 327 "/FPGA HSIO/Crosslink_B1.D4")
			(pinfunction "PB34A/GR_PCLK1_0")
			(pintype "input")
			(solder_mask_margin -0.025)
			(solder_paste_margin -0.025)
		)
		(pad "E2" smd circle
			(at -2.275 -0.325 180)
			(size 0.35 0.35)
			(layers "F.Cu" "F.Mask" "F.Paste")
			(net 502 "unconnected-(U16-PB34B-PadE2)")
			(pinfunction "PB34B")
			(pintype "bidirectional+no_connect")
			(solder_mask_margin -0.025)
			(solder_paste_margin -0.025)
		)
		(pad "E4" smd circle
			(at -0.975 -0.325 180)
			(size 0.35 0.35)
			(layers "F.Cu" "F.Mask" "F.Paste")
			(net 176 "/MIPI CrossLink/CL_VCC")
			(pinfunction "VCC")
			(pintype "power_in")
			(solder_mask_margin -0.025)
			(solder_paste_margin -0.025)
		)
		(pad "E5" smd circle
			(at -0.325 -0.325 180)
			(size 0.35 0.35)
			(layers "F.Cu" "F.Mask" "F.Paste")
			(net 417 "GND")
			(pinfunction "GND")
			(pintype "passive")
			(solder_mask_margin -0.025)
			(solder_paste_margin -0.025)
		)
		(pad "E6" smd circle
			(at 0.325 -0.325 180)
			(size 0.35 0.35)
			(layers "F.Cu" "F.Mask" "F.Paste")
			(net 176 "/MIPI CrossLink/CL_VCC")
			(pinfunction "VCC")
			(pintype "passive")
			(solder_mask_margin -0.025)
			(solder_paste_margin -0.025)
		)
		(pad "E7" smd circle
			(at 0.975 -0.325 180)
			(size 0.35 0.35)
			(layers "F.Cu" "F.Mask" "F.Paste")
			(net 203 "/MIPI CrossLink/CL_VCCA_DPHY0")
			(pinfunction "VCCA_DPHY0")
			(pintype "power_in")
			(solder_mask_margin -0.025)
			(solder_paste_margin -0.025)
		)
		(pad "E9" smd circle
			(at 2.275 -0.325 180)
			(size 0.35 0.35)
			(layers "F.Cu" "F.Mask" "F.Paste")
			(net 503 "unconnected-(U16-PB12A{slash}GPLLT2_0-PadE9)")
			(pinfunction "PB12A/GPLLT2_0")
			(pintype "input+no_connect")
			(solder_mask_margin -0.025)
			(solder_paste_margin -0.025)
		)
		(pad "E10" smd circle
			(at 2.925 -0.325 180)
			(size 0.35 0.35)
			(layers "F.Cu" "F.Mask" "F.Paste")
			(net 504 "unconnected-(U16-PB12B{slash}GPLLC2_0-PadE10)")
			(pinfunction "PB12B/GPLLC2_0")
			(pintype "input+no_connect")
			(solder_mask_margin -0.025)
			(solder_paste_margin -0.025)
		)
		(pad "F1" smd circle
			(at -2.925 0.325 180)
			(size 0.35 0.35)
			(layers "F.Cu" "F.Mask" "F.Paste")
			(net 339 "/FPGA HSIO/Crosslink_B1.VSYNC")
			(pinfunction "PB38A")
			(pintype "bidirectional")
			(solder_mask_margin -0.025)
			(solder_paste_margin -0.025)
		)
		(pad "F2" smd circle
			(at -2.275 0.325 180)
			(size 0.35 0.35)
			(layers "F.Cu" "F.Mask" "F.Paste")
			(net 335 "/FPGA HSIO/Crosslink_B1.HSYNC")
			(pinfunction "PB38B")
			(pintype "bidirectional")
			(solder_mask_margin -0.025)
			(solder_paste_margin -0.025)
		)
		(pad "F4" smd circle
			(at -0.975 0.325 180)
			(size 0.35 0.35)
			(layers "F.Cu" "F.Mask" "F.Paste")
			(net 183 "/MIPI CrossLink/CL_VCCIO0")
			(pinfunction "VCCIO0")
			(pintype "power_in")
			(solder_mask_margin -0.025)
			(solder_paste_margin -0.025)
		)
		(pad "F5" smd circle
			(at -0.325 0.325 180)
			(size 0.35 0.35)
			(layers "F.Cu" "F.Mask" "F.Paste")
			(net 185 "/MIPI CrossLink/CL_VCCIO1")
			(pinfunction "VCCIO1")
			(pintype "power_in")
			(solder_mask_margin -0.025)
			(solder_paste_margin -0.025)
		)
		(pad "F6" smd circle
			(at 0.325 0.325 180)
			(size 0.35 0.35)
			(layers "F.Cu" "F.Mask" "F.Paste")
			(net 191 "/MIPI CrossLink/CL_VCCIO2")
			(pinfunction "VCCIO2")
			(pintype "power_in")
			(solder_mask_margin -0.025)
			(solder_paste_margin -0.025)
		)
		(pad "F7" smd circle
			(at 0.975 0.325 180)
			(size 0.35 0.35)
			(layers "F.Cu" "F.Mask" "F.Paste")
			(net 191 "/MIPI CrossLink/CL_VCCIO2")
			(pinfunction "VCCIO2")
			(pintype "passive")
			(solder_mask_margin -0.025)
			(solder_paste_margin -0.025)
		)
		(pad "F9" smd circle
			(at 2.275 0.325 180)
			(size 0.35 0.35)
			(layers "F.Cu" "F.Mask" "F.Paste")
			(net 347 "/FPGA HSIO/Crosslink_B2.VSYNC")
			(pinfunction "PB6A/GR_PCLK2_0")
			(pintype "input")
			(solder_mask_margin -0.025)
			(solder_paste_margin -0.025)
		)
		(pad "F10" smd circle
			(at 2.925 0.325 180)
			(size 0.35 0.35)
			(layers "F.Cu" "F.Mask" "F.Paste")
			(net 338 "/FPGA HSIO/Crosslink_B2.HSYNC")
			(pinfunction "PB6B")
			(pintype "bidirectional")
			(solder_mask_margin -0.025)
			(solder_paste_margin -0.025)
		)
		(pad "G1" smd circle
			(at -2.925 0.975 180)
			(size 0.35 0.35)
			(layers "F.Cu" "F.Mask" "F.Paste")
			(net 346 "/FPGA GPIO/Crosslink.MOSI")
			(pinfunction "PB50/MOSI")
			(pintype "bidirectional")
			(solder_mask_margin -0.025)
			(solder_paste_margin -0.025)
		)
		(pad "G2" smd circle
			(at -2.275 0.975 180)
			(size 0.35 0.35)
			(layers "F.Cu" "F.Mask" "F.Paste")
			(net 417 "GND")
			(pinfunction "GND")
			(pintype "passive")
			(solder_mask_margin -0.025)
			(solder_paste_margin -0.025)
		)
		(pad "G4" smd circle
			(at -0.975 0.975 180)
			(size 0.35 0.35)
			(layers "F.Cu" "F.Mask" "F.Paste")
			(net 185 "/MIPI CrossLink/CL_VCCIO1")
			(pinfunction "VCCIO1")
			(pintype "passive")
			(solder_mask_margin -0.025)
			(solder_paste_margin -0.025)
		)
		(pad "G5" smd circle
			(at -0.325 0.975 180)
			(size 0.35 0.35)
			(layers "F.Cu" "F.Mask" "F.Paste")
			(net 417 "GND")
			(pinfunction "GND")
			(pintype "passive")
			(solder_mask_margin -0.025)
			(solder_paste_margin -0.025)
		)
		(pad "G6" smd circle
			(at 0.325 0.975 180)
			(size 0.35 0.35)
			(layers "F.Cu" "F.Mask" "F.Paste")
			(net 180 "/MIPI CrossLink/CL_VCCGPLL")
			(pinfunction "VCCGPLL")
			(pintype "power_in")
			(solder_mask_margin -0.025)
			(solder_paste_margin -0.025)
		)
		(pad "G7" smd circle
			(at 0.975 0.975 180)
			(size 0.35 0.35)
			(layers "F.Cu" "F.Mask" "F.Paste")
			(net 417 "GND")
			(pinfunction "GNDGPLL")
			(pintype "power_in")
			(solder_mask_margin -0.025)
			(solder_paste_margin -0.025)
		)
		(pad "G9" smd circle
			(at 2.275 0.975 180)
			(size 0.35 0.35)
			(layers "F.Cu" "F.Mask" "F.Paste")
			(net 331 "/FPGA HSIO/Crosslink_B2.PCLK")
			(pinfunction "PB2A")
			(pintype "bidirectional")
			(solder_mask_margin -0.025)
			(solder_paste_margin -0.025)
		)
		(pad "G10" smd circle
			(at 2.925 0.975 180)
			(size 0.35 0.35)
			(layers "F.Cu" "F.Mask" "F.Paste")
			(net 223 "/FPGA HSIO/Crosslink_B2.D0")
			(pinfunction "PB2B")
			(pintype "bidirectional")
			(solder_mask_margin -0.025)
			(solder_paste_margin -0.025)
		)
		(pad "H1" smd circle
			(at -2.925 1.625 180)
			(size 0.35 0.35)
			(layers "F.Cu" "F.Mask" "F.Paste")
			(net 345 "/FPGA GPIO/Crosslink.CS")
			(pinfunction "PB52/SPI_SS/CSN/SCL")
			(pintype "bidirectional")
			(solder_mask_margin -0.025)
			(solder_paste_margin -0.025)
		)
		(pad "H2" smd circle
			(at -2.275 1.625 180)
			(size 0.35 0.35)
			(layers "F.Cu" "F.Mask" "F.Paste")
			(net 289 "~{Crosslink_RESET}")
			(pinfunction "CRESET_B")
			(pintype "input")
			(solder_mask_margin -0.025)
			(solder_paste_margin -0.025)
		)
		(pad "H9" smd circle
			(at 2.275 1.625 180)
			(size 0.35 0.35)
			(layers "F.Cu" "F.Mask" "F.Paste")
			(net 329 "/FPGA HSIO/Crosslink_B2.D1")
			(pinfunction "PB2D/MIPI_CLKC2_0")
			(pintype "bidirectional")
			(solder_mask_margin -0.025)
			(solder_paste_margin -0.025)
		)
		(pad "H10" smd circle
			(at 2.925 1.625 180)
			(size 0.35 0.35)
			(layers "F.Cu" "F.Mask" "F.Paste")
			(net 131 "/FPGA HSIO/Crosslink_B2.D2")
			(pinfunction "PB2C/MIPI_CLKT2_0")
			(pintype "bidirectional")
			(solder_mask_margin -0.025)
			(solder_paste_margin -0.025)
		)
		(pad "J1" smd circle
			(at -2.925 2.275 180)
			(size 0.35 0.35)
			(layers "F.Cu" "F.Mask" "F.Paste")
			(net 545 "/FPGA GPIO/Crosslink.CLK")
			(pinfunction "PB53/SPI_SCK/MCK/SDA")
			(pintype "bidirectional")
			(solder_mask_margin -0.025)
			(solder_paste_margin -0.025)
		)
		(pad "J2" smd circle
			(at -2.275 2.275 180)
			(size 0.35 0.35)
			(layers "F.Cu" "F.Mask" "F.Paste")
			(net 332 "Net-(U16-PB49{slash}PMU_WKUPN{slash}CDONE)")
			(pinfunction "PB49/PMU_WKUPN/CDONE")
			(pintype "passive")
			(solder_mask_margin -0.025)
			(solder_paste_margin -0.025)
		)
		(pad "J3" smd circle
			(at -1.625 2.275 180)
			(size 0.35 0.35)
			(layers "F.Cu" "F.Mask" "F.Paste")
			(net 299 "/FPGA HSIO/Crosslink_B1.D3")
			(pinfunction "PB43D")
			(pintype "bidirectional")
			(solder_mask_margin -0.025)
			(solder_paste_margin -0.025)
		)
		(pad "J4" smd circle
			(at -0.975 2.275 180)
			(size 0.35 0.35)
			(layers "F.Cu" "F.Mask" "F.Paste")
			(net 298 "/FPGA HSIO/Crosslink_B1.D2")
			(pinfunction "PB38D")
			(pintype "bidirectional")
			(solder_mask_margin -0.025)
			(solder_paste_margin -0.025)
		)
		(pad "J5" smd circle
			(at -0.325 2.275 180)
			(size 0.35 0.35)
			(layers "F.Cu" "F.Mask" "F.Paste")
			(net 300 "/FPGA HSIO/Crosslink_B1.D1")
			(pinfunction "PB34D/MIPI_CLKC1_0")
			(pintype "bidirectional")
			(solder_mask_margin -0.025)
			(solder_paste_margin -0.025)
		)
		(pad "J6" smd circle
			(at 0.325 2.275 180)
			(size 0.35 0.35)
			(layers "F.Cu" "F.Mask" "F.Paste")
			(net 303 "/FPGA HSIO/Crosslink_B1.D0")
			(pinfunction "PB29D/PCLKC1_1")
			(pintype "bidirectional")
			(solder_mask_margin -0.025)
			(solder_paste_margin -0.025)
		)
		(pad "J7" smd circle
			(at 0.975 2.275 180)
			(size 0.35 0.35)
			(layers "F.Cu" "F.Mask" "F.Paste")
			(net 340 "/FPGA HSIO/Crosslink_B1.PCLK")
			(pinfunction "PB29A/PCLKT1_0")
			(pintype "bidirectional")
			(solder_mask_margin -0.025)
			(solder_paste_margin -0.025)
		)
		(pad "J8" smd circle
			(at 1.625 2.275 180)
			(size 0.35 0.35)
			(layers "F.Cu" "F.Mask" "F.Paste")
			(net 210 "/FPGA HSIO/Crosslink_B2.D3")
			(pinfunction "PB16D/PCLKC2_1")
			(pintype "bidirectional")
			(solder_mask_margin -0.025)
			(solder_paste_margin -0.025)
		)
		(pad "J9" smd circle
			(at 2.275 2.275 180)
			(size 0.35 0.35)
			(layers "F.Cu" "F.Mask" "F.Paste")
			(net 136 "/FPGA HSIO/Crosslink_B2.D5")
			(pinfunction "PB6D")
			(pintype "bidirectional")
			(solder_mask_margin -0.025)
			(solder_paste_margin -0.025)
		)
		(pad "J10" smd circle
			(at 2.925 2.275 180)
			(size 0.35 0.35)
			(layers "F.Cu" "F.Mask" "F.Paste")
			(net 130 "/FPGA HSIO/Crosslink_B2.D6")
			(pinfunction "PB6C")
			(pintype "bidirectional")
			(solder_mask_margin -0.025)
			(solder_paste_margin -0.025)
		)
		(pad "K1" smd circle
			(at -2.925 2.925 180)
			(size 0.35 0.35)
			(layers "F.Cu" "F.Mask" "F.Paste")
			(net 563 "/FPGA GPIO/Crosslink.MISO")
			(pinfunction "PB51/MISO")
			(pintype "bidirectional")
			(solder_mask_margin -0.025)
			(solder_paste_margin -0.025)
		)
		(pad "K2" smd circle
			(at -2.275 2.925 180)
			(size 0.35 0.35)
			(layers "F.Cu" "F.Mask" "F.Paste")
			(net 537 "/FPGA GPIO/Crosslink.SDA")
			(pinfunction "PB47/PCLKT0_0/USER_SDA")
			(pintype "bidirectional")
			(solder_mask_margin -0.025)
			(solder_paste_margin -0.025)
		)
		(pad "K3" smd circle
			(at -1.625 2.925 180)
			(size 0.35 0.35)
			(layers "F.Cu" "F.Mask" "F.Paste")
			(net 291 "/FPGA HSIO/Crosslink_B1.D9")
			(pinfunction "PB43C")
			(pintype "bidirectional")
			(solder_mask_margin -0.025)
			(solder_paste_margin -0.025)
		)
		(pad "K4" smd circle
			(at -0.975 2.925 180)
			(size 0.35 0.35)
			(layers "F.Cu" "F.Mask" "F.Paste")
			(net 292 "/FPGA HSIO/Crosslink_B1.D8")
			(pinfunction "PB38C")
			(pintype "bidirectional")
			(solder_mask_margin -0.025)
			(solder_paste_margin -0.025)
		)
		(pad "K5" smd circle
			(at -0.325 2.925 180)
			(size 0.35 0.35)
			(layers "F.Cu" "F.Mask" "F.Paste")
			(net 293 "/FPGA HSIO/Crosslink_B1.D7")
			(pinfunction "PB34C/MIPI_CLKT1_0")
			(pintype "bidirectional")
			(solder_mask_margin -0.025)
			(solder_paste_margin -0.025)
		)
		(pad "K6" smd circle
			(at 0.325 2.925 180)
			(size 0.35 0.35)
			(layers "F.Cu" "F.Mask" "F.Paste")
			(net 328 "/FPGA HSIO/Crosslink_B1.D6")
			(pinfunction "PB29C/PCLKT1_1")
			(pintype "bidirectional")
			(solder_mask_margin -0.025)
			(solder_paste_margin -0.025)
		)
		(pad "K7" smd circle
			(at 0.975 2.925 180)
			(size 0.35 0.35)
			(layers "F.Cu" "F.Mask" "F.Paste")
			(net 337 "/FPGA HSIO/Crosslink_B1.D5")
			(pinfunction "PB29B/PCLKC1_0")
			(pintype "bidirectional")
			(solder_mask_margin -0.025)
			(solder_paste_margin -0.025)
		)
		(pad "K8" smd circle
			(at 1.625 2.925 180)
			(size 0.35 0.35)
			(layers "F.Cu" "F.Mask" "F.Paste")
			(net 304 "/FPGA HSIO/Crosslink_B2.D7")
			(pinfunction "PB16C/PCLKT2_1")
			(pintype "bidirectional")
			(solder_mask_margin -0.025)
			(solder_paste_margin -0.025)
		)
		(pad "K9" smd circle
			(at 2.275 2.925 180)
			(size 0.35 0.35)
			(layers "F.Cu" "F.Mask" "F.Paste")
			(net 294 "/FPGA HSIO/Crosslink_B2.D8")
			(pinfunction "PB12D")
			(pintype "bidirectional")
			(solder_mask_margin -0.025)
			(solder_paste_margin -0.025)
		)
		(pad "K10" smd circle
			(at 2.925 2.925 180)
			(size 0.35 0.35)
			(layers "F.Cu" "F.Mask" "F.Paste")
			(net 145 "/FPGA HSIO/Crosslink_B2.D9")
			(pinfunction "PB12C")
			(pintype "bidirectional")
			(solder_mask_margin -0.025)
			(solder_paste_margin -0.025)
		)
	)
	(footprint "antmicro-footprints:C_0402_1005Metric"
		(layer "F.Cu")
		(at 184.975 142.9875 -90)
		(descr "Capacitor SMD 0402")
		(tags "capacitor SMD 0402")
		(property "Reference" "C103"
			(at 0.8625 -0.485 90)
			(layer "F.SilkS")
			(effects
				(font
					(size 0.7 0.7)
					(thickness 0.15)
				)
				(justify right bottom)
			)
		)
		(property "Value" "C_22u_0402"
			(at -1.022927 2.155213 90)
			(layer "F.Fab")
			(hide yes)
			(effects
				(font
					(size 0.7 0.7)
					(thickness 0.15)
				)
				(justify right bottom)
			)
		)
		(property "Datasheet" "https://www.murata.com/products/productdetail?partno=GRM158R60J226ME01%23"
			(at 0 0 270)
			(layer "F.Fab")
			(hide yes)
			(effects
				(font
					(size 1.27 1.27)
					(thickness 0.15)
				)
			)
		)
		(property "Description" "SMD Multilayer Ceramic Capacitor, 22 uF, 4 V, 0402 [1005 Metric], X6S"
			(at 0 0 270)
			(layer "F.Fab")
			(hide yes)
			(effects
				(font
					(size 1.27 1.27)
					(thickness 0.15)
				)
			)
		)
		(property "Author" "Antmicro"
			(at 41.9875 327.9625 0)
			(layer "F.Fab")
			(hide yes)
			(effects
				(font
					(size 1 1)
					(thickness 0.15)
				)
			)
		)
		(property "Dielectric" ""
			(at 41.9875 327.9625 0)
			(layer "F.Fab")
			(hide yes)
			(effects
				(font
					(size 1 1)
					(thickness 0.15)
				)
			)
		)
		(property "License" "Apache-2.0"
			(at 41.9875 327.9625 0)
			(layer "F.Fab")
			(hide yes)
			(effects
				(font
					(size 1 1)
					(thickness 0.15)
				)
			)
		)
		(property "MPN" "GRM158R60J226ME01D"
			(at 41.9875 327.9625 0)
			(layer "F.Fab")
			(hide yes)
			(effects
				(font
					(size 1 1)
					(thickness 0.15)
				)
			)
		)
		(property "Manufacturer" "Murata"
			(at 41.9875 327.9625 0)
			(layer "F.Fab")
			(hide yes)
			(effects
				(font
					(size 1 1)
					(thickness 0.15)
				)
			)
		)
		(property "Public" ""
			(at 41.9875 327.9625 0)
			(layer "F.Fab")
			(hide yes)
			(effects
				(font
					(size 1 1)
					(thickness 0.15)
				)
			)
		)
		(property "Val" "22u"
			(at 41.9875 327.9625 0)
			(layer "F.Fab")
			(hide yes)
			(effects
				(font
					(size 1 1)
					(thickness 0.15)
				)
			)
		)
		(property "Voltage" ""
			(at 41.9875 327.9625 0)
			(layer "F.Fab")
			(hide yes)
			(effects
				(font
					(size 1 1)
					(thickness 0.15)
				)
			)
		)
		(sheetname "/Supply/")
		(sheetfile "supply.kicad_sch")
		(attr smd)
		(fp_rect
			(start -0.925 -0.47)
			(end 0.925 0.47)
			(stroke
				(width 0.05)
				(type default)
			)
			(fill no)
			(layer "F.CrtYd")
		)
		(fp_line
			(start -0.494 0.248)
			(end -0.494 -0.25)
			(stroke
				(width 0.15)
				(type solid)
			)
			(layer "F.Fab")
		)
		(fp_line
			(start 0.504 0.248)
			(end -0.494 0.248)
			(stroke
				(width 0.15)
				(type solid)
			)
			(layer "F.Fab")
		)
		(fp_line
			(start -0.494 -0.25)
			(end 0.504 -0.25)
			(stroke
				(width 0.15)
				(type solid)
			)
			(layer "F.Fab")
		)
		(fp_line
			(start 0.504 -0.25)
			(end 0.504 0.248)
			(stroke
				(width 0.15)
				(type solid)
			)
			(layer "F.Fab")
		)
		(fp_text user "License: Apache-2.0"
			(at -0.939 5.799 270)
			(layer "F.Fab")
			(effects
				(font
					(size 0.7 0.7)
					(thickness 0.15)
				)
				(justify left bottom)
			)
		)
		(fp_text user "Author: Antmicro"
			(at -0.939 3.399 270)
			(layer "F.Fab")
			(effects
				(font
					(size 0.7 0.7)
					(thickness 0.15)
				)
				(justify left bottom)
			)
		)
		(fp_text user "${REFERENCE}"
			(at -0.939 4.599 270)
			(layer "F.Fab")
			(effects
				(font
					(size 0.7 0.7)
					(thickness 0.15)
				)
				(justify left bottom)
			)
		)
		(pad "1" smd roundrect
			(at -0.48 0 270)
			(size 0.59 0.64)
			(layers "F.Cu" "F.Mask" "F.Paste")
			(roundrect_rratio 0.25)
			(net 417 "GND")
			(pintype "passive")
		)
		(pad "2" smd roundrect
			(at 0.48 0 270)
			(size 0.59 0.64)
			(layers "F.Cu" "F.Mask" "F.Paste")
			(roundrect_rratio 0.25)
			(net 409 "/Supply/SENSE4_P")
			(pintype "passive")
		)
	)
	(footprint "antmicro-footprints:UQFN-10_1.4x1.8x0.5mm_P0.4mm"
		(layer "F.Cu")
		(at 215.983 153.0715)
		(property "Reference" "U23"
			(at 1.527 -0.3615 90)
			(layer "F.SilkS")
			(effects
				(font
					(size 0.7 0.7)
					(thickness 0.15)
				)
				(justify left bottom)
			)
		)
		(property "Value" "PI3USB102GZLEX"
			(at 0 2.4 0)
			(layer "F.Fab")
			(hide yes)
			(effects
				(font
					(size 0.7 0.7)
					(thickness 0.15)
				)
				(justify left bottom)
			)
		)
		(property "Datasheet" "https://www.diodes.com/assets/Datasheets/PI3USB102G.pdf"
			(at 0 0 0)
			(layer "F.Fab")
			(hide yes)
			(effects
				(font
					(size 1.27 1.27)
					(thickness 0.15)
				)
			)
		)
		(property "Description" "USB Switch IC 1 Channel 10-TQFN (1.3x1.6)"
			(at 0 0 0)
			(layer "F.Fab")
			(hide yes)
			(effects
				(font
					(size 1.27 1.27)
					(thickness 0.15)
				)
			)
		)
		(property "Author" "Antmicro"
			(at 0 0 0)
			(layer "F.Fab")
			(hide yes)
			(effects
				(font
					(size 1 1)
					(thickness 0.15)
				)
			)
		)
		(property "License" "Apache-2.0"
			(at 0 0 0)
			(layer "F.Fab")
			(hide yes)
			(effects
				(font
					(size 1 1)
					(thickness 0.15)
				)
			)
		)
		(property "MPN" "PI3USB102GZLEX"
			(at 0 0 0)
			(layer "F.Fab")
			(hide yes)
			(effects
				(font
					(size 1 1)
					(thickness 0.15)
				)
			)
		)
		(property "Manufacturer" "Diodes Incorporated"
			(at 0 0 0)
			(layer "F.Fab")
			(hide yes)
			(effects
				(font
					(size 1 1)
					(thickness 0.15)
				)
			)
		)
		(property ki_fp_filters "MSOP*3x3mm*P0.5mm*")
		(sheetname "/USB/")
		(sheetfile "usb.kicad_sch")
		(attr smd)
		(fp_line
			(start -0.7305 -0.552)
			(end -1.2005 -0.552)
			(stroke
				(width 0.15)
				(type solid)
			)
			(layer "F.SilkS")
		)
		(fp_line
			(start -0.7305 -0.552)
			(end -0.7305 -0.93)
			(stroke
				(width 0.15)
				(type solid)
			)
			(layer "F.SilkS")
		)
		(fp_circle
			(center -1.0515 -1.151)
			(end -0.9805 -1.151)
			(stroke
				(width 0.15)
				(type solid)
			)
			(fill no)
			(layer "F.SilkS")
		)
		(fp_rect
			(start -1.3 -1.5)
			(end 1.3 1.5)
			(stroke
				(width 0.05)
				(type solid)
			)
			(fill no)
			(layer "F.CrtYd")
		)
		(fp_line
			(start -0.7 -0.4)
			(end -0.175 -0.925)
			(stroke
				(width 0.15)
				(type solid)
			)
			(layer "F.Fab")
		)
		(fp_line
			(start -0.7 0.93)
			(end -0.7 -0.4)
			(stroke
				(width 0.15)
				(type solid)
			)
			(layer "F.Fab")
		)
		(fp_line
			(start -0.175 -0.925)
			(end 0.7295 -0.925)
			(stroke
				(width 0.15)
				(type solid)
			)
			(layer "F.Fab")
		)
		(fp_line
			(start 0.725 0.93)
			(end -0.7 0.93)
			(stroke
				(width 0.15)
				(type solid)
			)
			(layer "F.Fab")
		)
		(fp_line
			(start 0.7295 -0.925)
			(end 0.725 0.93)
			(stroke
				(width 0.15)
				(type solid)
			)
			(layer "F.Fab")
		)
		(fp_text user "Author: Antmicro"
			(at -0.657 5.7 0)
			(layer "F.Fab")
			(effects
				(font
					(size 0.7 0.7)
					(thickness 0.15)
				)
				(justify left bottom)
			)
		)
		(fp_text user "License: Apache-2.0"
			(at -0.657 6.9 0)
			(layer "F.Fab")
			(effects
				(font
					(size 0.7 0.7)
					(thickness 0.15)
				)
				(justify left bottom)
			)
		)
		(fp_text user "${REFERENCE}"
			(at -0.657 4.498 0)
			(layer "F.Fab")
			(effects
				(font
					(size 0.7 0.7)
					(thickness 0.15)
				)
				(justify left bottom)
			)
		)
		(pad "1" smd roundrect
			(at -0.6445 -0.2)
			(size 0.81 0.22)
			(layers "F.Cu" "F.Mask" "F.Paste")
			(roundrect_rratio 0.25)
			(net 499 "/USB/USB_P")
			(pinfunction "D+")
			(pintype "bidirectional")
		)
		(pad "2" smd roundrect
			(at -0.6445 0.2)
			(size 0.81 0.22)
			(layers "F.Cu" "F.Mask" "F.Paste")
			(roundrect_rratio 0.25)
			(net 498 "/USB/USB_N")
			(pinfunction "D-")
			(pintype "bidirectional")
		)
		(pad "3" smd roundrect
			(at -0.4015 0.844 270)
			(size 0.81 0.22)
			(layers "F.Cu" "F.Mask" "F.Paste")
			(roundrect_rratio 0.25)
			(net 417 "GND")
			(pinfunction "GND")
			(pintype "power_in")
		)
		(pad "4" smd roundrect
			(at 0.0005 0.844 270)
			(size 0.81 0.22)
			(layers "F.Cu" "F.Mask" "F.Paste")
			(roundrect_rratio 0.25)
			(net 512 "/USB/USB_UP_N")
			(pinfunction "D1-")
			(pintype "bidirectional")
		)
		(pad "5" smd roundrect
			(at 0.3995 0.844 270)
			(size 0.81 0.22)
			(layers "F.Cu" "F.Mask" "F.Paste")
			(roundrect_rratio 0.25)
			(net 513 "/USB/USB_UP_P")
			(pinfunction "D1+")
			(pintype "bidirectional")
		)
		(pad "6" smd roundrect
			(at 0.6455 0.2)
			(size 0.81 0.22)
			(layers "F.Cu" "F.Mask" "F.Paste")
			(roundrect_rratio 0.25)
			(net 510 "/USB/USB_BYP_N")
			(pinfunction "D2-")
			(pintype "bidirectional")
		)
		(pad "7" smd roundrect
			(at 0.6455 -0.2)
			(size 0.81 0.22)
			(layers "F.Cu" "F.Mask" "F.Paste")
			(roundrect_rratio 0.25)
			(net 511 "/USB/USB_BYP_P")
			(pinfunction "D2+")
			(pintype "bidirectional")
		)
		(pad "8" smd roundrect
			(at 0.3995 -0.847 270)
			(size 0.81 0.22)
			(layers "F.Cu" "F.Mask" "F.Paste")
			(roundrect_rratio 0.25)
			(net 417 "GND")
			(pinfunction "~{OE}")
			(pintype "input")
		)
		(pad "9" smd roundrect
			(at 0.0005 -0.847 270)
			(size 0.81 0.22)
			(layers "F.Cu" "F.Mask" "F.Paste")
			(roundrect_rratio 0.25)
			(net 50 "+3V3")
			(pinfunction "V_{DD}")
			(pintype "power_in")
		)
		(pad "10" smd roundrect
			(at -0.4015 -0.847 270)
			(size 0.81 0.22)
			(layers "F.Cu" "F.Mask" "F.Paste")
			(roundrect_rratio 0.25)
			(net 62 "USB_OTG_ID")
			(pinfunction "SEL")
			(pintype "input")
		)
	)
	(footprint "antmicro-footprints:FB_0402_1005Metric"
		(layer "F.Cu")
		(at 208.085 146.8)
		(descr "Ferrite Bead SMD 0402")
		(tags "ferrite bead SMD 0402")
		(property "Reference" "FB2"
			(at -5.135 7.515 90)
			(layer "F.SilkS")
			(effects
				(font
					(size 0.7 0.7)
					(thickness 0.15)
				)
				(justify left bottom)
			)
		)
		(property "Value" "FB_120Z_1.2A_TDK-MPZ_0402"
			(at 0 1.4 0)
			(layer "F.Fab")
			(hide yes)
			(effects
				(font
					(size 0.7 0.7)
					(thickness 0.15)
				)
				(justify left bottom)
			)
		)
		(property "Datasheet" "https://product.tdk.com/en/search/emc/emc/beads/info?part_no=MPZ1005S121CT000"
			(at 0 0 0)
			(layer "F.Fab")
			(hide yes)
			(effects
				(font
					(size 1.27 1.27)
					(thickness 0.15)
				)
			)
		)
		(property "Description" "Ferrite Bead, 0402 [1005 Metric], 120 ohm, 1.2A, MPZ, 0.06 ohm, ± 25%, DC Power line"
			(at 0 0 0)
			(layer "F.Fab")
			(hide yes)
			(effects
				(font
					(size 1.27 1.27)
					(thickness 0.15)
				)
			)
		)
		(property "Author" "Antmicro"
			(at 0 0 0)
			(layer "F.Fab")
			(hide yes)
			(effects
				(font
					(size 1 1)
					(thickness 0.15)
				)
			)
		)
		(property "Current" ""
			(at 0 0 0)
			(layer "F.Fab")
			(hide yes)
			(effects
				(font
					(size 1 1)
					(thickness 0.15)
				)
			)
		)
		(property "License" "Apache-2.0"
			(at 0 0 0)
			(layer "F.Fab")
			(hide yes)
			(effects
				(font
					(size 1 1)
					(thickness 0.15)
				)
			)
		)
		(property "MPN" "MPZ1005S121CT000"
			(at 0 0 0)
			(layer "F.Fab")
			(hide yes)
			(effects
				(font
					(size 1 1)
					(thickness 0.15)
				)
			)
		)
		(property "Manufacturer" "TDK"
			(at 0 0 0)
			(layer "F.Fab")
			(hide yes)
			(effects
				(font
					(size 1 1)
					(thickness 0.15)
				)
			)
		)
		(property "Public" ""
			(at 0 0 0)
			(layer "F.Fab")
			(hide yes)
			(effects
				(font
					(size 1 1)
					(thickness 0.15)
				)
			)
		)
		(property "Val" "120Z/1.2A"
			(at 0 0 0)
			(layer "F.Fab")
			(hide yes)
			(effects
				(font
					(size 1 1)
					(thickness 0.15)
				)
			)
		)
		(sheetname "/MIPI CrossLink/")
		(sheetfile "crosslink.kicad_sch")
		(attr smd)
		(fp_rect
			(start -0.925 -0.47)
			(end 0.925 0.47)
			(stroke
				(width 0.05)
				(type default)
			)
			(fill no)
			(layer "F.CrtYd")
		)
		(fp_rect
			(start -0.5 -0.25)
			(end 0.5 0.25)
			(stroke
				(width 0.15)
				(type solid)
			)
			(fill no)
			(layer "F.Fab")
		)
		(fp_text user "${REFERENCE}"
			(at -0.95 3.168 0)
			(layer "F.Fab")
			(effects
				(font
					(size 0.7 0.7)
					(thickness 0.15)
				)
				(justify left bottom)
			)
		)
		(fp_text user "License: Apache-2.0"
			(at -0.95 5.169 0)
			(layer "F.Fab")
			(effects
				(font
					(size 0.7 0.7)
					(thickness 0.15)
				)
				(justify left bottom)
			)
		)
		(fp_text user "Author: Antmicro"
			(at -0.95 4.169 0)
			(layer "F.Fab")
			(effects
				(font
					(size 0.7 0.7)
					(thickness 0.15)
				)
				(justify left bottom)
			)
		)
		(pad "1" smd roundrect
			(at -0.48 0)
			(size 0.59 0.64)
			(layers "F.Cu" "F.Mask" "F.Paste")
			(roundrect_rratio 0.25)
			(net 183 "/MIPI CrossLink/CL_VCCIO0")
			(pintype "passive")
		)
		(pad "2" smd roundrect
			(at 0.48 0)
			(size 0.59 0.64)
			(layers "F.Cu" "F.Mask" "F.Paste")
			(roundrect_rratio 0.25)
			(net 649 "VDD")
			(pintype "passive")
		)
	)
	(footprint "antmicro-footprints:R_0402_1005Metric"
		(layer "F.Cu")
		(at 185.05 121.45)
		(descr "Resistor SMD 0402")
		(tags "resistor SMD 0402")
		(property "Reference" "R90"
			(at 1.19 2.65 90)
			(layer "F.SilkS")
			(effects
				(font
					(size 0.7 0.7)
					(thickness 0.15)
				)
				(justify left bottom)
			)
		)
		(property "Value" "R_0R_0402"
			(at -1.011843 1.772047 0)
			(layer "F.Fab")
			(hide yes)
			(effects
				(font
					(size 0.7 0.7)
					(thickness 0.15)
				)
				(justify left bottom)
			)
		)
		(property "Datasheet" "https://industrial.panasonic.com/cdbs/www-data/pdf/RDA0000/AOA0000C301.pdf"
			(at 0 0 0)
			(layer "F.Fab")
			(hide yes)
			(effects
				(font
					(size 1.27 1.27)
					(thickness 0.15)
				)
			)
		)
		(property "Description" "SMD Chip Resistor, Jumper, 0 ohm, 100 mW, 0402 [1005 Metric], Thick Film, General Purpose"
			(at 0 0 0)
			(layer "F.Fab")
			(hide yes)
			(effects
				(font
					(size 1.27 1.27)
					(thickness 0.15)
				)
			)
		)
		(property "Author" "Antmicro"
			(at 0 0 0)
			(layer "F.Fab")
			(hide yes)
			(effects
				(font
					(size 1 1)
					(thickness 0.15)
				)
			)
		)
		(property "Current" "1A"
			(at 0 0 0)
			(layer "F.Fab")
			(hide yes)
			(effects
				(font
					(size 1 1)
					(thickness 0.15)
				)
			)
		)
		(property "License" "Apache-2.0"
			(at 0 0 0)
			(layer "F.Fab")
			(hide yes)
			(effects
				(font
					(size 1 1)
					(thickness 0.15)
				)
			)
		)
		(property "MPN" "ERJ2GE0R00X"
			(at 0 0 0)
			(layer "F.Fab")
			(hide yes)
			(effects
				(font
					(size 1 1)
					(thickness 0.15)
				)
			)
		)
		(property "Manufacturer" "Panasonic"
			(at 0 0 0)
			(layer "F.Fab")
			(hide yes)
			(effects
				(font
					(size 1 1)
					(thickness 0.15)
				)
			)
		)
		(property "Public" ""
			(at 0 0 0)
			(layer "F.Fab")
			(hide yes)
			(effects
				(font
					(size 1 1)
					(thickness 0.15)
				)
			)
		)
		(property "Tolerance" "~"
			(at 0 0 0)
			(layer "F.Fab")
			(hide yes)
			(effects
				(font
					(size 1 1)
					(thickness 0.15)
				)
			)
		)
		(property "Val" "0R"
			(at 0 0 0)
			(layer "F.Fab")
			(hide yes)
			(effects
				(font
					(size 1 1)
					(thickness 0.15)
				)
			)
		)
		(sheetname "/FPGA Config/")
		(sheetfile "fpga-config.kicad_sch")
		(attr smd dnp)
		(fp_rect
			(start -0.925 -0.47)
			(end 0.925 0.47)
			(stroke
				(width 0.05)
				(type default)
			)
			(fill no)
			(layer "F.CrtYd")
		)
		(fp_rect
			(start -0.5 -0.25)
			(end 0.5 0.25)
			(stroke
				(width 0.15)
				(type solid)
			)
			(fill no)
			(layer "F.Fab")
		)
		(fp_text user "${REFERENCE}"
			(at -0.95 3.168 0)
			(layer "F.Fab")
			(effects
				(font
					(size 0.7 0.7)
					(thickness 0.15)
				)
				(justify left bottom)
			)
		)
		(fp_text user "License: Apache-2.0"
			(at -0.95 5.169 0)
			(layer "F.Fab")
			(effects
				(font
					(size 0.7 0.7)
					(thickness 0.15)
				)
				(justify left bottom)
			)
		)
		(fp_text user "Author: Antmicro"
			(at -0.95 4.169 0)
			(layer "F.Fab")
			(effects
				(font
					(size 0.7 0.7)
					(thickness 0.15)
				)
				(justify left bottom)
			)
		)
		(pad "1" smd roundrect
			(at -0.48 0)
			(size 0.59 0.64)
			(layers "F.Cu" "F.Mask" "F.Paste")
			(roundrect_rratio 0.25)
			(net 189 "Net-(U1D-TDO)")
			(pintype "passive")
		)
		(pad "2" smd roundrect
			(at 0.48 0)
			(size 0.59 0.64)
			(layers "F.Cu" "F.Mask" "F.Paste")
			(roundrect_rratio 0.25)
			(net 192 "PF_TDO")
			(pintype "passive")
		)
	)
	(footprint "antmicro-footprints:SOT-523"
		(layer "F.Cu")
		(at 211 147)
		(property "Reference" "Q4"
			(at 0.19 -0.3 0)
			(layer "F.SilkS")
			(effects
				(font
					(size 0.7 0.7)
					(thickness 0.15)
				)
				(justify left bottom)
			)
		)
		(property "Value" "DMG1012T-7"
			(at 0.1 1.824 0)
			(layer "F.Fab")
			(hide yes)
			(effects
				(font
					(size 0.7 0.7)
					(thickness 0.15)
				)
				(justify left bottom)
			)
		)
		(property "Datasheet" "https://www.diodes.com/assets/Datasheets/ds31783.pdf"
			(at 0 0 0)
			(layer "F.Fab")
			(hide yes)
			(effects
				(font
					(size 1.27 1.27)
					(thickness 0.15)
				)
			)
		)
		(property "Description" "Power MOSFET, N Channel, 20 V, 630 mA, 0.3 ohm, SOT-523, Surface Mount"
			(at 0 0 0)
			(layer "F.Fab")
			(hide yes)
			(effects
				(font
					(size 1.27 1.27)
					(thickness 0.15)
				)
			)
		)
		(property "Author" "Antmicro"
			(at 0 0 0)
			(layer "F.Fab")
			(hide yes)
			(effects
				(font
					(size 1 1)
					(thickness 0.15)
				)
			)
		)
		(property "License" "Apache-2.0"
			(at 0 0 0)
			(layer "F.Fab")
			(hide yes)
			(effects
				(font
					(size 1 1)
					(thickness 0.15)
				)
			)
		)
		(property "MPN" "DMG1012T-7"
			(at 0 0 0)
			(layer "F.Fab")
			(hide yes)
			(effects
				(font
					(size 1 1)
					(thickness 0.15)
				)
			)
		)
		(property "Manufacturer" "Diodes Incorporated"
			(at 0 0 0)
			(layer "F.Fab")
			(hide yes)
			(effects
				(font
					(size 1 1)
					(thickness 0.15)
				)
			)
		)
		(property "Public" ""
			(at 0 0 0)
			(layer "F.Fab")
			(hide yes)
			(effects
				(font
					(size 1 1)
					(thickness 0.15)
				)
			)
		)
		(sheetname "/USB/")
		(sheetfile "usb.kicad_sch")
		(attr smd)
		(fp_line
			(start -0.927 -0.351)
			(end -0.725 -0.551)
			(stroke
				(width 0.15)
				(type solid)
			)
			(layer "F.SilkS")
		)
		(fp_line
			(start -0.927 -0.051)
			(end -0.927 -0.351)
			(stroke
				(width 0.15)
				(type solid)
			)
			(layer "F.SilkS")
		)
		(fp_line
			(start -0.725 -0.551)
			(end -0.277 -0.551)
			(stroke
				(width 0.15)
				(type solid)
			)
			(layer "F.SilkS")
		)
		(fp_line
			(start -0.277 -0.551)
			(end -0.277 -0.75)
			(stroke
				(width 0.15)
				(type solid)
			)
			(layer "F.SilkS")
		)
		(fp_circle
			(center -0.9652 0.9652)
			(end -0.9152 0.9652)
			(stroke
				(width 0.15)
				(type solid)
			)
			(fill yes)
			(layer "F.SilkS")
		)
		(fp_line
			(start -1.12 -1.16)
			(end -1.12 1.15)
			(stroke
				(width 0.05)
				(type solid)
			)
			(layer "F.CrtYd")
		)
		(fp_line
			(start -1.12 -1.16)
			(end 1.1 -1.16)
			(stroke
				(width 0.05)
				(type solid)
			)
			(layer "F.CrtYd")
		)
		(fp_line
			(start -1.12 1.15)
			(end 1.1 1.15)
			(stroke
				(width 0.05)
				(type solid)
			)
			(layer "F.CrtYd")
		)
		(fp_line
			(start 1.1 -1.16)
			(end 1.1 1.15)
			(stroke
				(width 0.05)
				(type solid)
			)
			(layer "F.CrtYd")
		)
		(fp_line
			(start -0.802 -0.276)
			(end -0.802 0.424)
			(stroke
				(width 0.15)
				(type solid)
			)
			(layer "F.Fab")
		)
		(fp_line
			(start -0.652 -0.425)
			(end -0.802 -0.276)
			(stroke
				(width 0.15)
				(type solid)
			)
			(layer "F.Fab")
		)
		(fp_line
			(start 0.8 -0.425)
			(end -0.652 -0.425)
			(stroke
				(width 0.15)
				(type solid)
			)
			(layer "F.Fab")
		)
		(fp_line
			(start 0.8 -0.425)
			(end 0.8 0.424)
			(stroke
				(width 0.15)
				(type solid)
			)
			(layer "F.Fab")
		)
		(fp_line
			(start 0.8 0.424)
			(end -0.802 0.424)
			(stroke
				(width 0.15)
				(type solid)
			)
			(layer "F.Fab")
		)
		(fp_circle
			(center -0.9652 0.9652)
			(end -0.9144 0.9652)
			(stroke
				(width 0.15)
				(type solid)
			)
			(fill no)
			(layer "F.Fab")
		)
		(fp_text user "Author: Antmicro"
			(at -1.12 6.224 0)
			(layer "F.Fab")
			(effects
				(font
					(size 0.7 0.7)
					(thickness 0.15)
				)
				(justify left bottom)
			)
		)
		(fp_text user "License: Apache-2.0"
			(at -1.12 5.024 0)
			(layer "F.Fab")
			(effects
				(font
					(size 0.7 0.7)
					(thickness 0.15)
				)
				(justify left bottom)
			)
		)
		(fp_text user "${REFERENCE}"
			(at -1.12 3.824 0)
			(layer "F.Fab")
			(effects
				(font
					(size 0.7 0.7)
					(thickness 0.15)
				)
				(justify left bottom)
			)
		)
		(pad "1" smd rect
			(at -0.5 0.65)
			(size 0.4 0.51)
			(layers "F.Cu" "F.Mask" "F.Paste")
			(net 635 "/FPGA GPIO/ULPI.RESET")
			(pinfunction "G")
			(pintype "input")
		)
		(pad "2" smd rect
			(at 0.498 0.65)
			(size 0.4 0.51)
			(layers "F.Cu" "F.Mask" "F.Paste")
			(net 417 "GND")
			(pinfunction "S")
			(pintype "passive")
		)
		(pad "3" smd rect
			(at 0 -0.652)
			(size 0.4 0.51)
			(layers "F.Cu" "F.Mask" "F.Paste")
			(net 379 "/USB/RESETB")
			(pinfunction "D")
			(pintype "passive")
		)
	)
	(footprint "antmicro-footprints:TP_SMD_0.75mm"
		(layer "F.Cu")
		(at 188.645 116.6)
		(property "Reference" "TP1"
			(at 0 -0.6 0)
			(layer "F.SilkS")
			(hide yes)
			(effects
				(font
					(size 0.7 0.7)
					(thickness 0.15)
				)
				(justify left bottom)
			)
		)
		(property "Value" "TP_0.75mm_SMD"
			(at 0 1.2 0)
			(layer "F.Fab")
			(hide yes)
			(effects
				(font
					(size 0.7 0.7)
					(thickness 0.15)
				)
				(justify left bottom)
			)
		)
		(property "Description" "SMT test point"
			(at 0 0 0)
			(layer "F.Fab")
			(hide yes)
			(effects
				(font
					(size 1.27 1.27)
					(thickness 0.15)
				)
			)
		)
		(property "Author" "Antmicro"
			(at 0 0 0)
			(layer "F.Fab")
			(hide yes)
			(effects
				(font
					(size 1 1)
					(thickness 0.15)
				)
			)
		)
		(property "License" "Apache-2.0"
			(at 0 0 0)
			(layer "F.Fab")
			(hide yes)
			(effects
				(font
					(size 1 1)
					(thickness 0.15)
				)
			)
		)
		(property "MPN" ""
			(at 0 0 0)
			(layer "F.Fab")
			(hide yes)
			(effects
				(font
					(size 1 1)
					(thickness 0.15)
				)
			)
		)
		(property "Manufacturer" ""
			(at 0 0 0)
			(layer "F.Fab")
			(hide yes)
			(effects
				(font
					(size 1 1)
					(thickness 0.15)
				)
			)
		)
		(property "Public" "False"
			(at 0 0 0)
			(layer "F.Fab")
			(hide yes)
			(effects
				(font
					(size 1 1)
					(thickness 0.15)
				)
			)
		)
		(sheetname "/FPGA Config/")
		(sheetfile "fpga-config.kicad_sch")
		(attr exclude_from_pos_files exclude_from_bom)
		(fp_circle
			(center 0 0)
			(end 0.475 0)
			(stroke
				(width 0.05)
				(type default)
			)
			(fill no)
			(layer "F.CrtYd")
		)
		(fp_text user "${REFERENCE}"
			(at -0.4 2.7 0)
			(layer "F.Fab")
			(effects
				(font
					(size 0.7 0.7)
					(thickness 0.15)
				)
				(justify left bottom)
			)
		)
		(fp_text user "License: Apache-2.0"
			(at -0.4 5.101 0)
			(layer "F.Fab")
			(effects
				(font
					(size 0.7 0.7)
					(thickness 0.15)
				)
				(justify left bottom)
			)
		)
		(fp_text user "Author: Antmicro"
			(at -0.4 3.901 0)
			(layer "F.Fab")
			(effects
				(font
					(size 0.7 0.7)
					(thickness 0.15)
				)
				(justify left bottom)
			)
		)
		(pad "1" smd circle
			(at 0 0)
			(size 0.75 0.75)
			(layers "F.Cu" "F.Mask")
			(net 655 "/FPGA Config/DEVRST_N")
			(pinfunction "1")
			(pintype "passive")
		)
	)
	(footprint "antmicro-footprints:TP_SMD_0.75mm"
		(layer "F.Cu")
		(at 228.47 146.545)
		(property "Reference" "TP28"
			(at 9.69 2.225 0)
			(layer "F.SilkS")
			(hide yes)
			(effects
				(font
					(size 0.7 0.7)
					(thickness 0.15)
				)
				(justify left bottom)
			)
		)
		(property "Value" "TP_0.75mm_SMD"
			(at 0 1.2 0)
			(layer "F.Fab")
			(hide yes)
			(effects
				(font
					(size 0.7 0.7)
					(thickness 0.15)
				)
				(justify left bottom)
			)
		)
		(property "Description" "SMT test point"
			(at 0 0 0)
			(layer "F.Fab")
			(hide yes)
			(effects
				(font
					(size 1.27 1.27)
					(thickness 0.15)
				)
			)
		)
		(property "Author" "Antmicro"
			(at 0 0 0)
			(layer "F.Fab")
			(hide yes)
			(effects
				(font
					(size 1 1)
					(thickness 0.15)
				)
			)
		)
		(property "License" "Apache-2.0"
			(at 0 0 0)
			(layer "F.Fab")
			(hide yes)
			(effects
				(font
					(size 1 1)
					(thickness 0.15)
				)
			)
		)
		(property "MPN" ""
			(at 0 0 0)
			(layer "F.Fab")
			(hide yes)
			(effects
				(font
					(size 1 1)
					(thickness 0.15)
				)
			)
		)
		(property "Manufacturer" ""
			(at 0 0 0)
			(layer "F.Fab")
			(hide yes)
			(effects
				(font
					(size 1 1)
					(thickness 0.15)
				)
			)
		)
		(property "Public" "False"
			(at 0 0 0)
			(layer "F.Fab")
			(hide yes)
			(effects
				(font
					(size 1 1)
					(thickness 0.15)
				)
			)
		)
		(sheetname "/WiFi_Bluetooth/")
		(sheetfile "wifi_bt.kicad_sch")
		(attr exclude_from_pos_files exclude_from_bom)
		(fp_circle
			(center 0 0)
			(end 0.475 0)
			(stroke
				(width 0.05)
				(type default)
			)
			(fill no)
			(layer "F.CrtYd")
		)
		(fp_text user "Author: Antmicro"
			(at -0.4 3.901 0)
			(layer "F.Fab")
			(effects
				(font
					(size 0.7 0.7)
					(thickness 0.15)
				)
				(justify left bottom)
			)
		)
		(fp_text user "License: Apache-2.0"
			(at -0.4 5.101 0)
			(layer "F.Fab")
			(effects
				(font
					(size 0.7 0.7)
					(thickness 0.15)
				)
				(justify left bottom)
			)
		)
		(fp_text user "${REFERENCE}"
			(at -0.4 2.7 0)
			(layer "F.Fab")
			(effects
				(font
					(size 0.7 0.7)
					(thickness 0.15)
				)
				(justify left bottom)
			)
		)
		(pad "1" smd circle
			(at 0 0)
			(size 0.75 0.75)
			(layers "F.Cu" "F.Mask")
			(net 525 "Net-(U26A-WL_HOST_WAKE)")
			(pinfunction "1")
			(pintype "passive")
		)
	)
	(footprint "antmicro-footprints:R_0402_1005Metric"
		(layer "F.Cu")
		(at 192.72 118.89 45)
		(descr "Resistor SMD 0402")
		(tags "resistor SMD 0402")
		(property "Reference" "R101"
			(at -1.534422 -0.601041 45)
			(layer "F.SilkS")
			(effects
				(font
					(size 0.7 0.7)
					(thickness 0.15)
				)
				(justify left bottom)
			)
		)
		(property "Value" "R_10k_0402"
			(at -1.011843 1.772046 45)
			(layer "F.Fab")
			(hide yes)
			(effects
				(font
					(size 0.7 0.7)
					(thickness 0.15)
				)
				(justify left bottom)
			)
		)
		(property "Datasheet" "https://www.bourns.com/docs/product-datasheets/cr.pdf"
			(at 0 0 45)
			(layer "F.Fab")
			(hide yes)
			(effects
				(font
					(size 1.27 1.27)
					(thickness 0.15)
				)
			)
		)
		(property "Description" "SMD Chip Resistor, 10 kohm, ± 1%, 62.5 mW, 0402 [1005 Metric], Thick Film, General Purpose"
			(at 0 0 45)
			(layer "F.Fab")
			(hide yes)
			(effects
				(font
					(size 1.27 1.27)
					(thickness 0.15)
				)
			)
		)
		(property "Author" "Antmicro"
			(at 140.514307 -101.451544 0)
			(layer "F.Fab")
			(hide yes)
			(effects
				(font
					(size 1 1)
					(thickness 0.15)
				)
			)
		)
		(property "License" "Apache-2.0"
			(at 140.514307 -101.451544 0)
			(layer "F.Fab")
			(hide yes)
			(effects
				(font
					(size 1 1)
					(thickness 0.15)
				)
			)
		)
		(property "MPN" "CR0402-FX-1002GLF"
			(at 140.514307 -101.451544 0)
			(layer "F.Fab")
			(hide yes)
			(effects
				(font
					(size 1 1)
					(thickness 0.15)
				)
			)
		)
		(property "Manufacturer" "Bourns"
			(at 140.514307 -101.451544 0)
			(layer "F.Fab")
			(hide yes)
			(effects
				(font
					(size 1 1)
					(thickness 0.15)
				)
			)
		)
		(property "Public" ""
			(at 140.514307 -101.451544 0)
			(layer "F.Fab")
			(hide yes)
			(effects
				(font
					(size 1 1)
					(thickness 0.15)
				)
			)
		)
		(property "Tolerance" "1%"
			(at 140.514307 -101.451544 0)
			(layer "F.Fab")
			(hide yes)
			(effects
				(font
					(size 1 1)
					(thickness 0.15)
				)
			)
		)
		(property "Val" "10k"
			(at 140.514307 -101.451544 0)
			(layer "F.Fab")
			(hide yes)
			(effects
				(font
					(size 1 1)
					(thickness 0.15)
				)
			)
		)
		(sheetname "/Top Connector/")
		(sheetfile "top-connector.kicad_sch")
		(attr smd)
		(fp_poly
			(pts
				(xy -0.925 -0.47) (xy 0.925 -0.47) (xy 0.925 0.47) (xy -0.925 0.47)
			)
			(stroke
				(width 0.05)
				(type default)
			)
			(fill no)
			(layer "F.CrtYd")
		)
		(fp_poly
			(pts
				(xy -0.5 -0.25) (xy 0.5 -0.25) (xy 0.5 0.25) (xy -0.5 0.25)
			)
			(stroke
				(width 0.15)
				(type solid)
			)
			(fill no)
			(layer "F.Fab")
		)
		(fp_text user "License: Apache-2.0"
			(at -0.949999 5.169 45)
			(layer "F.Fab")
			(effects
				(font
					(size 0.7 0.7)
					(thickness 0.15)
				)
				(justify left bottom)
			)
		)
		(fp_text user "Author: Antmicro"
			(at -0.95 4.169 45)
			(layer "F.Fab")
			(effects
				(font
					(size 0.7 0.7)
					(thickness 0.15)
				)
				(justify left bottom)
			)
		)
		(fp_text user "${REFERENCE}"
			(at -0.95 3.168 45)
			(layer "F.Fab")
			(effects
				(font
					(size 0.7 0.7)
					(thickness 0.15)
				)
				(justify left bottom)
			)
		)
		(pad "1" smd roundrect
			(at -0.48 0 45)
			(size 0.59 0.64)
			(layers "F.Cu" "F.Mask" "F.Paste")
			(roundrect_rratio 0.25)
			(net 98 "/Top Connector/PI_LED_nPWR")
			(pintype "passive")
		)
		(pad "2" smd roundrect
			(at 0.48 0 45)
			(size 0.59 0.64)
			(layers "F.Cu" "F.Mask" "F.Paste")
			(roundrect_rratio 0.25)
			(net 50 "+3V3")
			(pintype "passive")
		)
	)
	(footprint "antmicro-footprints:C_0402_1005Metric"
		(layer "F.Cu")
		(at 179.718763 147.663922 180)
		(descr "Capacitor SMD 0402")
		(tags "capacitor SMD 0402")
		(property "Reference" "C94"
			(at 0.808763 0.303922 90)
			(layer "F.SilkS")
			(effects
				(font
					(size 0.7 0.7)
					(thickness 0.15)
				)
				(justify right bottom)
			)
		)
		(property "Value" "C_100n_0402"
			(at -1.022927 2.155213 0)
			(layer "F.Fab")
			(hide yes)
			(effects
				(font
					(size 0.7 0.7)
					(thickness 0.15)
				)
				(justify right bottom)
			)
		)
		(property "Datasheet" "https://www.murata.com/products/productdetail?partno=GRM155R61H104KE14%23"
			(at 0 0 180)
			(layer "F.Fab")
			(hide yes)
			(effects
				(font
					(size 1.27 1.27)
					(thickness 0.15)
				)
			)
		)
		(property "Description" "SMD Multilayer Ceramic Capacitor, 0.1 µF, 50 V, 0402 [1005 Metric], ± 10%, X5R, GRM Series"
			(at 0 0 180)
			(layer "F.Fab")
			(hide yes)
			(effects
				(font
					(size 1.27 1.27)
					(thickness 0.15)
				)
			)
		)
		(property "Author" "Antmicro"
			(at 359.437526 295.327844 0)
			(layer "F.Fab")
			(hide yes)
			(effects
				(font
					(size 1 1)
					(thickness 0.15)
				)
			)
		)
		(property "Dielectric" "X5R"
			(at 359.437526 295.327844 0)
			(layer "F.Fab")
			(hide yes)
			(effects
				(font
					(size 1 1)
					(thickness 0.15)
				)
			)
		)
		(property "License" "Apache-2.0"
			(at 359.437526 295.327844 0)
			(layer "F.Fab")
			(hide yes)
			(effects
				(font
					(size 1 1)
					(thickness 0.15)
				)
			)
		)
		(property "MPN" "GRM155R61H104KE14D"
			(at 359.437526 295.327844 0)
			(layer "F.Fab")
			(hide yes)
			(effects
				(font
					(size 1 1)
					(thickness 0.15)
				)
			)
		)
		(property "Manufacturer" "Murata"
			(at 359.437526 295.327844 0)
			(layer "F.Fab")
			(hide yes)
			(effects
				(font
					(size 1 1)
					(thickness 0.15)
				)
			)
		)
		(property "Public" ""
			(at 359.437526 295.327844 0)
			(layer "F.Fab")
			(hide yes)
			(effects
				(font
					(size 1 1)
					(thickness 0.15)
				)
			)
		)
		(property "Val" "100n"
			(at 359.437526 295.327844 0)
			(layer "F.Fab")
			(hide yes)
			(effects
				(font
					(size 1 1)
					(thickness 0.15)
				)
			)
		)
		(property "Voltage" "50V"
			(at 359.437526 295.327844 0)
			(layer "F.Fab")
			(hide yes)
			(effects
				(font
					(size 1 1)
					(thickness 0.15)
				)
			)
		)
		(sheetname "/Supply/")
		(sheetfile "supply.kicad_sch")
		(attr smd)
		(fp_rect
			(start -0.925 -0.47)
			(end 0.925 0.47)
			(stroke
				(width 0.05)
				(type default)
			)
			(fill no)
			(layer "F.CrtYd")
		)
		(fp_line
			(start 0.504 0.248)
			(end -0.494 0.248)
			(stroke
				(width 0.15)
				(type solid)
			)
			(layer "F.Fab")
		)
		(fp_line
			(start 0.504 -0.25)
			(end 0.504 0.248)
			(stroke
				(width 0.15)
				(type solid)
			)
			(layer "F.Fab")
		)
		(fp_line
			(start -0.494 0.248)
			(end -0.494 -0.25)
			(stroke
				(width 0.15)
				(type solid)
			)
			(layer "F.Fab")
		)
		(fp_line
			(start -0.494 -0.25)
			(end 0.504 -0.25)
			(stroke
				(width 0.15)
				(type solid)
			)
			(layer "F.Fab")
		)
		(fp_text user "License: Apache-2.0"
			(at -0.939 5.799 180)
			(layer "F.Fab")
			(effects
				(font
					(size 0.7 0.7)
					(thickness 0.15)
				)
				(justify left bottom)
			)
		)
		(fp_text user "${REFERENCE}"
			(at -0.939 4.599 180)
			(layer "F.Fab")
			(effects
				(font
					(size 0.7 0.7)
					(thickness 0.15)
				)
				(justify left bottom)
			)
		)
		(fp_text user "Author: Antmicro"
			(at -0.939 3.399 180)
			(layer "F.Fab")
			(effects
				(font
					(size 0.7 0.7)
					(thickness 0.15)
				)
				(justify left bottom)
			)
		)
		(pad "1" smd roundrect
			(at -0.48 0 180)
			(size 0.59 0.64)
			(layers "F.Cu" "F.Mask" "F.Paste")
			(roundrect_rratio 0.25)
			(net 417 "GND")
			(pintype "passive")
		)
		(pad "2" smd roundrect
			(at 0.48 0 180)
			(size 0.59 0.64)
			(layers "F.Cu" "F.Mask" "F.Paste")
			(roundrect_rratio 0.25)
			(net 90 "+5V")
			(pintype "passive")
		)
	)
	(footprint "antmicro-footprints:L_Coilcraft-XEL4020"
		(layer "F.Cu")
		(at 187.784404 151.354531 90)
		(property "Reference" "L1"
			(at -3.265469 1.175596 180)
			(layer "F.SilkS")
			(effects
				(font
					(size 0.7 0.7)
					(thickness 0.15)
				)
				(justify left bottom)
			)
		)
		(property "Value" "L_1u5_7.5A_Coilcraft-XEL4020"
			(at 0 3.35 90)
			(layer "F.Fab")
			(hide yes)
			(effects
				(font
					(size 0.7 0.7)
					(thickness 0.15)
				)
				(justify left bottom)
			)
		)
		(property "Datasheet" "https://www.coilcraft.com/getmedia/3c7caaa2-c1ed-4ff8-84e5-0b1b14a30417/xel4020.pdf"
			(at 0 0 90)
			(layer "F.Fab")
			(hide yes)
			(effects
				(font
					(size 1.27 1.27)
					(thickness 0.15)
				)
			)
		)
		(property "Description" "Power Inductor (SMT), 1.5 µH, 7.5 A, Shielded, 7.4 A, XEL4020-152MEC"
			(at 0 0 90)
			(layer "F.Fab")
			(hide yes)
			(effects
				(font
					(size 1.27 1.27)
					(thickness 0.15)
				)
			)
		)
		(property "Author" "Antmicro"
			(at 339.138935 -36.429873 0)
			(layer "F.Fab")
			(hide yes)
			(effects
				(font
					(size 1 1)
					(thickness 0.15)
				)
			)
		)
		(property "IMax" "7.5 A"
			(at 339.138935 -36.429873 0)
			(layer "F.Fab")
			(hide yes)
			(effects
				(font
					(size 1 1)
					(thickness 0.15)
				)
			)
		)
		(property "ISat" "7.4 A"
			(at 339.138935 -36.429873 0)
			(layer "F.Fab")
			(hide yes)
			(effects
				(font
					(size 1 1)
					(thickness 0.15)
				)
			)
		)
		(property "License" "Apache-2.0"
			(at 339.138935 -36.429873 0)
			(layer "F.Fab")
			(hide yes)
			(effects
				(font
					(size 1 1)
					(thickness 0.15)
				)
			)
		)
		(property "MPN" "XEL4020-152MEC "
			(at 339.138935 -36.429873 0)
			(layer "F.Fab")
			(hide yes)
			(effects
				(font
					(size 1 1)
					(thickness 0.15)
				)
			)
		)
		(property "Manufacturer" "Coilcraft"
			(at 339.138935 -36.429873 0)
			(layer "F.Fab")
			(hide yes)
			(effects
				(font
					(size 1 1)
					(thickness 0.15)
				)
			)
		)
		(property "Public" ""
			(at 339.138935 -36.429873 0)
			(layer "F.Fab")
			(hide yes)
			(effects
				(font
					(size 1 1)
					(thickness 0.15)
				)
			)
		)
		(property "Size" "4x4"
			(at 339.138935 -36.429873 0)
			(layer "F.Fab")
			(hide yes)
			(effects
				(font
					(size 1 1)
					(thickness 0.15)
				)
			)
		)
		(property "Val" "1u5/7.5A"
			(at 339.138935 -36.429873 0)
			(layer "F.Fab")
			(hide yes)
			(effects
				(font
					(size 1 1)
					(thickness 0.15)
				)
			)
		)
		(sheetname "/Supply/")
		(sheetfile "supply.kicad_sch")
		(attr smd)
		(fp_line
			(start -2.2 -2.2)
			(end 2.2 -2.2)
			(stroke
				(width 0.15)
				(type solid)
			)
			(layer "F.SilkS")
		)
		(fp_line
			(start 2.2 2.2)
			(end 2.2 -2.2)
			(stroke
				(width 0.15)
				(type solid)
			)
			(layer "F.SilkS")
		)
		(fp_line
			(start -2.2 2.2)
			(end -2.2 -2.2)
			(stroke
				(width 0.15)
				(type solid)
			)
			(layer "F.SilkS")
		)
		(fp_line
			(start -2.2 2.2)
			(end 2.2 2.2)
			(stroke
				(width 0.15)
				(type solid)
			)
			(layer "F.SilkS")
		)
		(fp_rect
			(start -2.4 -2.4)
			(end 2.4 2.4)
			(stroke
				(width 0.05)
				(type solid)
			)
			(fill no)
			(layer "F.CrtYd")
		)
		(fp_rect
			(start -2.15 -2.15)
			(end 2.15 2.15)
			(stroke
				(width 0.15)
				(type solid)
			)
			(fill no)
			(layer "F.Fab")
		)
		(fp_text user "Author: Antmicro"
			(at -2.4 5.35 90)
			(layer "F.Fab")
			(effects
				(font
					(size 0.7 0.7)
					(thickness 0.15)
				)
				(justify left bottom)
			)
		)
		(fp_text user "License: Apache-2.0"
			(at -2.4 7.75 90)
			(layer "F.Fab")
			(effects
				(font
					(size 0.7 0.7)
					(thickness 0.15)
				)
				(justify left bottom)
			)
		)
		(fp_text user "${REFERENCE}"
			(at -2.4 6.55 90)
			(layer "F.Fab")
			(effects
				(font
					(size 0.7 0.7)
					(thickness 0.15)
				)
				(justify left bottom)
			)
		)
		(pad "1" smd roundrect
			(at -1.185 0 90)
			(size 0.98 3.4)
			(layers "F.Cu" "F.Mask" "F.Paste")
			(roundrect_rratio 0.1)
			(net 150 "/Supply/1V05_SW")
			(pintype "passive")
		)
		(pad "2" smd roundrect
			(at 1.185 0 90)
			(size 0.98 3.4)
			(layers "F.Cu" "F.Mask" "F.Paste")
			(roundrect_rratio 0.1)
			(net 522 "/Supply/1V05_REG")
			(pintype "passive")
		)
	)
	(footprint "antmicro-footprints:R_0402_1005Metric"
		(layer "F.Cu")
		(at 198.762486 117.687335 180)
		(descr "Resistor SMD 0402")
		(tags "resistor SMD 0402")
		(property "Reference" "R13"
			(at 1.092486 0.697335 180)
			(layer "F.SilkS")
			(effects
				(font
					(size 0.7 0.7)
					(thickness 0.15)
				)
				(justify left bottom)
			)
		)
		(property "Value" "R_10k_0402"
			(at -1.011843 1.772047 180)
			(layer "F.Fab")
			(hide yes)
			(effects
				(font
					(size 0.7 0.7)
					(thickness 0.15)
				)
				(justify left bottom)
			)
		)
		(property "Datasheet" "https://www.bourns.com/docs/product-datasheets/cr.pdf"
			(at 0 0 180)
			(layer "F.Fab")
			(hide yes)
			(effects
				(font
					(size 1.27 1.27)
					(thickness 0.15)
				)
			)
		)
		(property "Description" "SMD Chip Resistor, 10 kohm, ± 1%, 62.5 mW, 0402 [1005 Metric], Thick Film, General Purpose"
			(at 0 0 180)
			(layer "F.Fab")
			(hide yes)
			(effects
				(font
					(size 1.27 1.27)
					(thickness 0.15)
				)
			)
		)
		(property "Author" "Antmicro"
			(at 397.524972 235.37467 0)
			(layer "F.Fab")
			(hide yes)
			(effects
				(font
					(size 1 1)
					(thickness 0.15)
				)
			)
		)
		(property "License" "Apache-2.0"
			(at 397.524972 235.37467 0)
			(layer "F.Fab")
			(hide yes)
			(effects
				(font
					(size 1 1)
					(thickness 0.15)
				)
			)
		)
		(property "MPN" "CR0402-FX-1002GLF"
			(at 397.524972 235.37467 0)
			(layer "F.Fab")
			(hide yes)
			(effects
				(font
					(size 1 1)
					(thickness 0.15)
				)
			)
		)
		(property "Manufacturer" "Bourns"
			(at 397.524972 235.37467 0)
			(layer "F.Fab")
			(hide yes)
			(effects
				(font
					(size 1 1)
					(thickness 0.15)
				)
			)
		)
		(property "Public" ""
			(at 397.524972 235.37467 0)
			(layer "F.Fab")
			(hide yes)
			(effects
				(font
					(size 1 1)
					(thickness 0.15)
				)
			)
		)
		(property "Tolerance" "1%"
			(at 397.524972 235.37467 0)
			(layer "F.Fab")
			(hide yes)
			(effects
				(font
					(size 1 1)
					(thickness 0.15)
				)
			)
		)
		(property "Val" "10k"
			(at 397.524972 235.37467 0)
			(layer "F.Fab")
			(hide yes)
			(effects
				(font
					(size 1 1)
					(thickness 0.15)
				)
			)
		)
		(sheetname "/Top Connector/")
		(sheetfile "top-connector.kicad_sch")
		(attr smd)
		(fp_rect
			(start -0.925 -0.47)
			(end 0.925 0.47)
			(stroke
				(width 0.05)
				(type default)
			)
			(fill no)
			(layer "F.CrtYd")
		)
		(fp_rect
			(start -0.5 -0.25)
			(end 0.5 0.25)
			(stroke
				(width 0.15)
				(type solid)
			)
			(fill no)
			(layer "F.Fab")
		)
		(fp_text user "${REFERENCE}"
			(at -0.95 3.168 180)
			(layer "F.Fab")
			(effects
				(font
					(size 0.7 0.7)
					(thickness 0.15)
				)
				(justify left bottom)
			)
		)
		(fp_text user "License: Apache-2.0"
			(at -0.95 5.169 180)
			(layer "F.Fab")
			(effects
				(font
					(size 0.7 0.7)
					(thickness 0.15)
				)
				(justify left bottom)
			)
		)
		(fp_text user "Author: Antmicro"
			(at -0.95 4.169 180)
			(layer "F.Fab")
			(effects
				(font
					(size 0.7 0.7)
					(thickness 0.15)
				)
				(justify left bottom)
			)
		)
		(pad "1" smd roundrect
			(at -0.48 0 180)
			(size 0.59 0.64)
			(layers "F.Cu" "F.Mask" "F.Paste")
			(roundrect_rratio 0.25)
			(net 28 "GPIO17")
			(pintype "passive")
		)
		(pad "2" smd roundrect
			(at 0.48 0 180)
			(size 0.59 0.64)
			(layers "F.Cu" "F.Mask" "F.Paste")
			(roundrect_rratio 0.25)
			(net 245 "Net-(J1-Pad50)")
			(pintype "passive")
		)
	)
	(footprint "antmicro-footprints:C_Pol_EIA-B"
		(layer "F.Cu")
		(at 189.1855 145.039)
		(property "Reference" "C60"
			(at -2.123 -1.676 0)
			(layer "F.SilkS")
			(effects
				(font
					(size 0.7 0.7)
					(thickness 0.15)
				)
				(justify left bottom)
			)
		)
		(property "Value" "C_Pol_330u_6.3V_KEMET-T520-B"
			(at 0 2.85 0)
			(layer "F.Fab")
			(hide yes)
			(effects
				(font
					(size 0.7 0.7)
					(thickness 0.15)
				)
				(justify left bottom)
			)
		)
		(property "Datasheet" "https://www.kemet.com/en/us/capacitors/product/T520B337M006ATE040.html"
			(at 0 0 0)
			(layer "F.Fab")
			(hide yes)
			(effects
				(font
					(size 1.27 1.27)
					(thickness 0.15)
				)
			)
		)
		(property "Description" "Tantalum Polymer Capacitor, KO-CAP®, 330 µF, ± 20%, 6.3 V, B, 0.04 ohm, 1411 [3528 Metric]"
			(at 0 0 0)
			(layer "F.Fab")
			(hide yes)
			(effects
				(font
					(size 1.27 1.27)
					(thickness 0.15)
				)
			)
		)
		(property "Author" "Antmicro"
			(at 0 0 0)
			(layer "F.Fab")
			(hide yes)
			(effects
				(font
					(size 1 1)
					(thickness 0.15)
				)
			)
		)
		(property "Capacitance" "330u"
			(at 0 0 0)
			(layer "F.Fab")
			(hide yes)
			(effects
				(font
					(size 1 1)
					(thickness 0.15)
				)
			)
		)
		(property "Dielectric" "template_dielectric"
			(at 0 0 0)
			(layer "F.Fab")
			(hide yes)
			(effects
				(font
					(size 1 1)
					(thickness 0.15)
				)
			)
		)
		(property "License" "Apache-2.0"
			(at 0 0 0)
			(layer "F.Fab")
			(hide yes)
			(effects
				(font
					(size 1 1)
					(thickness 0.15)
				)
			)
		)
		(property "MPN" "T520B337M006ATE040"
			(at 0 0 0)
			(layer "F.Fab")
			(hide yes)
			(effects
				(font
					(size 1 1)
					(thickness 0.15)
				)
			)
		)
		(property "Manufacturer" "KEMET"
			(at 0 0 0)
			(layer "F.Fab")
			(hide yes)
			(effects
				(font
					(size 1 1)
					(thickness 0.15)
				)
			)
		)
		(property "Public" ""
			(at 0 0 0)
			(layer "F.Fab")
			(hide yes)
			(effects
				(font
					(size 1 1)
					(thickness 0.15)
				)
			)
		)
		(property "Val" "330u"
			(at 0 0 0)
			(layer "F.Fab")
			(hide yes)
			(effects
				(font
					(size 1 1)
					(thickness 0.15)
				)
			)
		)
		(property "Voltage" "6.3V"
			(at 0 0 0)
			(layer "F.Fab")
			(hide yes)
			(effects
				(font
					(size 1 1)
					(thickness 0.15)
				)
			)
		)
		(sheetname "/FPGA Supply/")
		(sheetfile "fpga-supply.kicad_sch")
		(attr smd)
		(fp_line
			(start -2.521 -1.676)
			(end -2.123 -1.676)
			(stroke
				(width 0.15)
				(type solid)
			)
			(layer "F.SilkS")
		)
		(fp_line
			(start -2.325 -1.475)
			(end -2.325 -1.878)
			(stroke
				(width 0.15)
				(type solid)
			)
			(layer "F.SilkS")
		)
		(fp_line
			(start -1.8 -1.6)
			(end 1.8 -1.6)
			(stroke
				(width 0.15)
				(type solid)
			)
			(layer "F.SilkS")
		)
		(fp_line
			(start -1.8 -1.3)
			(end -1.8 -1.6)
			(stroke
				(width 0.15)
				(type solid)
			)
			(layer "F.SilkS")
		)
		(fp_line
			(start -1.8 1.3)
			(end -1.8 1.6)
			(stroke
				(width 0.15)
				(type solid)
			)
			(layer "F.SilkS")
		)
		(fp_line
			(start 1.8 -1.3)
			(end 1.8 -1.6)
			(stroke
				(width 0.15)
				(type solid)
			)
			(layer "F.SilkS")
		)
		(fp_line
			(start 1.8 1.3)
			(end 1.8 1.6)
			(stroke
				(width 0.15)
				(type solid)
			)
			(layer "F.SilkS")
		)
		(fp_line
			(start 1.8 1.6)
			(end -1.8 1.6)
			(stroke
				(width 0.15)
				(type solid)
			)
			(layer "F.SilkS")
		)
		(fp_line
			(start -2.411 -1.35)
			(end -2.41 1.35)
			(stroke
				(width 0.05)
				(type solid)
			)
			(layer "F.CrtYd")
		)
		(fp_line
			(start -1.97 -1.75)
			(end -1.97 -1.35)
			(stroke
				(width 0.05)
				(type solid)
			)
			(layer "F.CrtYd")
		)
		(fp_line
			(start -1.97 -1.35)
			(end -2.41 -1.35)
			(stroke
				(width 0.05)
				(type solid)
			)
			(layer "F.CrtYd")
		)
		(fp_line
			(start -1.97 1.35)
			(end -2.41 1.35)
			(stroke
				(width 0.05)
				(type solid)
			)
			(layer "F.CrtYd")
		)
		(fp_line
			(start -1.97 1.35)
			(end -1.97 1.75)
			(stroke
				(width 0.05)
				(type solid)
			)
			(layer "F.CrtYd")
		)
		(fp_line
			(start 1.959 -1.75)
			(end -1.97 -1.75)
			(stroke
				(width 0.05)
				(type solid)
			)
			(layer "F.CrtYd")
		)
		(fp_line
			(start 1.959 -1.75)
			(end 1.959 -1.35)
			(stroke
				(width 0.05)
				(type solid)
			)
			(layer "F.CrtYd")
		)
		(fp_line
			(start 1.96 1.35)
			(end 1.96 1.75)
			(stroke
				(width 0.05)
				(type solid)
			)
			(layer "F.CrtYd")
		)
		(fp_line
			(start 1.96 1.75)
			(end -1.97 1.75)
			(stroke
				(width 0.05)
				(type solid)
			)
			(layer "F.CrtYd")
		)
		(fp_line
			(start 2.399 -1.35)
			(end 1.959 -1.35)
			(stroke
				(width 0.05)
				(type solid)
			)
			(layer "F.CrtYd")
		)
		(fp_line
			(start 2.399 -1.35)
			(end 2.4 1.35)
			(stroke
				(width 0.05)
				(type solid)
			)
			(layer "F.CrtYd")
		)
		(fp_line
			(start 2.4 1.35)
			(end 1.96 1.35)
			(stroke
				(width 0.05)
				(type solid)
			)
			(layer "F.CrtYd")
		)
		(fp_line
			(start -1.7 1.324)
			(end -1.551 1.475)
			(stroke
				(width 0.15)
				(type solid)
			)
			(layer "F.Fab")
		)
		(fp_rect
			(start -1.72 -1.5)
			(end 1.719 1.499)
			(stroke
				(width 0.15)
				(type solid)
			)
			(fill no)
			(layer "F.Fab")
		)
		(fp_text user "${REFERENCE}"
			(at -2.665 4.45 0)
			(layer "F.Fab")
			(effects
				(font
					(size 0.7 0.7)
					(thickness 0.15)
				)
				(justify left bottom)
			)
		)
		(fp_text user "License: Apache-2.0"
			(at -2.665 5.65 0)
			(layer "F.Fab")
			(effects
				(font
					(size 0.7 0.7)
					(thickness 0.15)
				)
				(justify left bottom)
			)
		)
		(fp_text user "Author: Antmicro"
			(at -2.665 6.85 0)
			(layer "F.Fab")
			(effects
				(font
					(size 0.7 0.7)
					(thickness 0.15)
				)
				(justify left bottom)
			)
		)
		(pad "1" smd roundrect
			(at -1.551 0)
			(size 1.2 2.2)
			(layers "F.Cu" "F.Mask" "F.Paste")
			(roundrect_rratio 0.1)
			(net 47 "+1V05")
			(pintype "passive")
		)
		(pad "2" smd roundrect
			(at 1.55 0)
			(size 1.2 2.2)
			(layers "F.Cu" "F.Mask" "F.Paste")
			(roundrect_rratio 0.1)
			(net 417 "GND")
			(pintype "passive")
		)
	)
	(footprint "antmicro-footprints:TP_SMD_0.75mm"
		(layer "F.Cu")
		(at 223 150.5)
		(property "Reference" "TP14"
			(at 12.93 5.49 90)
			(layer "F.SilkS")
			(hide yes)
			(effects
				(font
					(size 0.7 0.7)
					(thickness 0.15)
				)
				(justify left bottom)
			)
		)
		(property "Value" "TP_0.75mm_SMD"
			(at 0 1.2 0)
			(layer "F.Fab")
			(hide yes)
			(effects
				(font
					(size 0.7 0.7)
					(thickness 0.15)
				)
				(justify left bottom)
			)
		)
		(property "Description" "SMT test point"
			(at 0 0 0)
			(layer "F.Fab")
			(hide yes)
			(effects
				(font
					(size 1.27 1.27)
					(thickness 0.15)
				)
			)
		)
		(property "Author" "Antmicro"
			(at 0 0 0)
			(layer "F.Fab")
			(hide yes)
			(effects
				(font
					(size 1 1)
					(thickness 0.15)
				)
			)
		)
		(property "License" "Apache-2.0"
			(at 0 0 0)
			(layer "F.Fab")
			(hide yes)
			(effects
				(font
					(size 1 1)
					(thickness 0.15)
				)
			)
		)
		(property "MPN" ""
			(at 0 0 0)
			(layer "F.Fab")
			(hide yes)
			(effects
				(font
					(size 1 1)
					(thickness 0.15)
				)
			)
		)
		(property "Manufacturer" ""
			(at 0 0 0)
			(layer "F.Fab")
			(hide yes)
			(effects
				(font
					(size 1 1)
					(thickness 0.15)
				)
			)
		)
		(property "Public" "False"
			(at 0 0 0)
			(layer "F.Fab")
			(hide yes)
			(effects
				(font
					(size 1 1)
					(thickness 0.15)
				)
			)
		)
		(sheetname "/WiFi_Bluetooth/")
		(sheetfile "wifi_bt.kicad_sch")
		(attr exclude_from_pos_files exclude_from_bom)
		(fp_circle
			(center 0 0)
			(end 0.475 0)
			(stroke
				(width 0.05)
				(type default)
			)
			(fill no)
			(layer "F.CrtYd")
		)
		(fp_text user "${REFERENCE}"
			(at -0.4 2.7 0)
			(layer "F.Fab")
			(effects
				(font
					(size 0.7 0.7)
					(thickness 0.15)
				)
				(justify left bottom)
			)
		)
		(fp_text user "License: Apache-2.0"
			(at -0.4 5.101 0)
			(layer "F.Fab")
			(effects
				(font
					(size 0.7 0.7)
					(thickness 0.15)
				)
				(justify left bottom)
			)
		)
		(fp_text user "Author: Antmicro"
			(at -0.4 3.901 0)
			(layer "F.Fab")
			(effects
				(font
					(size 0.7 0.7)
					(thickness 0.15)
				)
				(justify left bottom)
			)
		)
		(pad "1" smd circle
			(at 0 0)
			(size 0.75 0.75)
			(layers "F.Cu" "F.Mask")
			(net 508 "Net-(U26A-BT_PCM_CLK)")
			(pinfunction "1")
			(pintype "passive")
		)
	)
	(footprint "antmicro-footprints:C_0402_1005Metric"
		(layer "F.Cu")
		(at 186.684904 147.897281 -90)
		(descr "Capacitor SMD 0402")
		(tags "capacitor SMD 0402")
		(property "Reference" "C110"
			(at 4.06272 -6.315096 180)
			(layer "F.SilkS")
			(effects
				(font
					(size 0.7 0.7)
					(thickness 0.15)
				)
				(justify right bottom)
			)
		)
		(property "Value" "C_22u_0402"
			(at -1.022927 2.155213 90)
			(layer "F.Fab")
			(hide yes)
			(effects
				(font
					(size 0.7 0.7)
					(thickness 0.15)
				)
				(justify right bottom)
			)
		)
		(property "Datasheet" "https://www.murata.com/products/productdetail?partno=GRM158R60J226ME01%23"
			(at 0 0 270)
			(layer "F.Fab")
			(hide yes)
			(effects
				(font
					(size 1.27 1.27)
					(thickness 0.15)
				)
			)
		)
		(property "Description" "SMD Multilayer Ceramic Capacitor, 22 uF, 4 V, 0402 [1005 Metric], X6S"
			(at 0 0 270)
			(layer "F.Fab")
			(hide yes)
			(effects
				(font
					(size 1.27 1.27)
					(thickness 0.15)
				)
			)
		)
		(property "Author" "Antmicro"
			(at 38.787623 334.582185 0)
			(layer "F.Fab")
			(hide yes)
			(effects
				(font
					(size 1 1)
					(thickness 0.15)
				)
			)
		)
		(property "Dielectric" ""
			(at 38.787623 334.582185 0)
			(layer "F.Fab")
			(hide yes)
			(effects
				(font
					(size 1 1)
					(thickness 0.15)
				)
			)
		)
		(property "License" "Apache-2.0"
			(at 38.787623 334.582185 0)
			(layer "F.Fab")
			(hide yes)
			(effects
				(font
					(size 1 1)
					(thickness 0.15)
				)
			)
		)
		(property "MPN" "GRM158R60J226ME01D"
			(at 38.787623 334.582185 0)
			(layer "F.Fab")
			(hide yes)
			(effects
				(font
					(size 1 1)
					(thickness 0.15)
				)
			)
		)
		(property "Manufacturer" "Murata"
			(at 38.787623 334.582185 0)
			(layer "F.Fab")
			(hide yes)
			(effects
				(font
					(size 1 1)
					(thickness 0.15)
				)
			)
		)
		(property "Public" ""
			(at 38.787623 334.582185 0)
			(layer "F.Fab")
			(hide yes)
			(effects
				(font
					(size 1 1)
					(thickness 0.15)
				)
			)
		)
		(property "Val" "22u"
			(at 38.787623 334.582185 0)
			(layer "F.Fab")
			(hide yes)
			(effects
				(font
					(size 1 1)
					(thickness 0.15)
				)
			)
		)
		(property "Voltage" ""
			(at 38.787623 334.582185 0)
			(layer "F.Fab")
			(hide yes)
			(effects
				(font
					(size 1 1)
					(thickness 0.15)
				)
			)
		)
		(sheetname "/Supply/")
		(sheetfile "supply.kicad_sch")
		(attr smd)
		(fp_rect
			(start -0.925 -0.47)
			(end 0.925 0.47)
			(stroke
				(width 0.05)
				(type default)
			)
			(fill no)
			(layer "F.CrtYd")
		)
		(fp_line
			(start -0.494 0.248)
			(end -0.494 -0.25)
			(stroke
				(width 0.15)
				(type solid)
			)
			(layer "F.Fab")
		)
		(fp_line
			(start 0.504 0.248)
			(end -0.494 0.248)
			(stroke
				(width 0.15)
				(type solid)
			)
			(layer "F.Fab")
		)
		(fp_line
			(start -0.494 -0.25)
			(end 0.504 -0.25)
			(stroke
				(width 0.15)
				(type solid)
			)
			(layer "F.Fab")
		)
		(fp_line
			(start 0.504 -0.25)
			(end 0.504 0.248)
			(stroke
				(width 0.15)
				(type solid)
			)
			(layer "F.Fab")
		)
		(fp_text user "${REFERENCE}"
			(at -0.939 4.599 270)
			(layer "F.Fab")
			(effects
				(font
					(size 0.7 0.7)
					(thickness 0.15)
				)
				(justify left bottom)
			)
		)
		(fp_text user "Author: Antmicro"
			(at -0.939 3.399 270)
			(layer "F.Fab")
			(effects
				(font
					(size 0.7 0.7)
					(thickness 0.15)
				)
				(justify left bottom)
			)
		)
		(fp_text user "License: Apache-2.0"
			(at -0.939 5.799 270)
			(layer "F.Fab")
			(effects
				(font
					(size 0.7 0.7)
					(thickness 0.15)
				)
				(justify left bottom)
			)
		)
		(pad "1" smd roundrect
			(at -0.48 0 270)
			(size 0.59 0.64)
			(layers "F.Cu" "F.Mask" "F.Paste")
			(roundrect_rratio 0.25)
			(net 417 "GND")
			(pintype "passive")
		)
		(pad "2" smd roundrect
			(at 0.48 0 270)
			(size 0.59 0.64)
			(layers "F.Cu" "F.Mask" "F.Paste")
			(roundrect_rratio 0.25)
			(net 522 "/Supply/1V05_REG")
			(pintype "passive")
		)
	)
	(footprint "antmicro-footprints:XSON-8_1x1.95mm_P0.5mm"
		(layer "F.Cu")
		(at 225.45 123.45 90)
		(property "Reference" "U24"
			(at -1.6 2.15 90)
			(layer "F.SilkS")
			(effects
				(font
					(size 0.7 0.7)
					(thickness 0.15)
				)
				(justify left bottom)
			)
		)
		(property "Value" "NTS0102_XSON"
			(at 0 2.2 90)
			(layer "F.Fab")
			(hide yes)
			(effects
				(font
					(size 0.7 0.7)
					(thickness 0.15)
				)
				(justify left bottom)
			)
		)
		(property "Datasheet" "http://www.farnell.com/datasheets/1760723.pdf"
			(at 0 0 90)
			(layer "F.Fab")
			(hide yes)
			(effects
				(font
					(size 1.27 1.27)
					(thickness 0.15)
				)
			)
		)
		(property "Description" "Transceiver, 1.65 V to 3.6 V, XSON-8"
			(at 0 0 90)
			(layer "F.Fab")
			(hide yes)
			(effects
				(font
					(size 1.27 1.27)
					(thickness 0.15)
				)
			)
		)
		(property "Author" "Antmicro"
			(at 348.9 -102 0)
			(layer "F.Fab")
			(hide yes)
			(effects
				(font
					(size 1 1)
					(thickness 0.15)
				)
			)
		)
		(property "License" "Apache-2.0"
			(at 348.9 -102 0)
			(layer "F.Fab")
			(hide yes)
			(effects
				(font
					(size 1 1)
					(thickness 0.15)
				)
			)
		)
		(property "MPN" "NTS0102GT"
			(at 348.9 -102 0)
			(layer "F.Fab")
			(hide yes)
			(effects
				(font
					(size 1 1)
					(thickness 0.15)
				)
			)
		)
		(property "Manufacturer" "NXP"
			(at 348.9 -102 0)
			(layer "F.Fab")
			(hide yes)
			(effects
				(font
					(size 1 1)
					(thickness 0.15)
				)
			)
		)
		(sheetname "/FPGA GPIO/")
		(sheetfile "fpga-gpio.kicad_sch")
		(attr smd)
		(fp_line
			(start -0.5 -1.1)
			(end 0.5 -1.1)
			(stroke
				(width 0.15)
				(type solid)
			)
			(layer "F.SilkS")
		)
		(fp_line
			(start 0.5 1.1)
			(end -0.5 1.1)
			(stroke
				(width 0.15)
				(type solid)
			)
			(layer "F.SilkS")
		)
		(fp_circle
			(center -0.75 -1.1)
			(end -0.701 -1.1)
			(stroke
				(width 0.15)
				(type solid)
			)
			(fill no)
			(layer "F.SilkS")
		)
		(fp_rect
			(start -0.8 -1.2)
			(end 0.8 1.2)
			(stroke
				(width 0.05)
				(type solid)
			)
			(fill no)
			(layer "F.CrtYd")
		)
		(fp_line
			(start 0.5305 -1.001)
			(end 0.5305 1)
			(stroke
				(width 0.15)
				(type solid)
			)
			(layer "F.Fab")
		)
		(fp_line
			(start -0.5305 -1.001)
			(end 0.5305 -1.001)
			(stroke
				(width 0.15)
				(type solid)
			)
			(layer "F.Fab")
		)
		(fp_line
			(start 0.5305 1)
			(end -0.5305 1)
			(stroke
				(width 0.15)
				(type solid)
			)
			(layer "F.Fab")
		)
		(fp_line
			(start -0.5305 1)
			(end -0.5305 -1.001)
			(stroke
				(width 0.15)
				(type solid)
			)
			(layer "F.Fab")
		)
		(fp_text user "${REFERENCE}"
			(at -0.527 5.905 90)
			(layer "F.Fab")
			(effects
				(font
					(size 0.7 0.7)
					(thickness 0.15)
				)
				(justify left bottom)
			)
		)
		(fp_text user "Author: Antmicro"
			(at -0.527 7.105 90)
			(layer "F.Fab")
			(effects
				(font
					(size 0.7 0.7)
					(thickness 0.15)
				)
				(justify left bottom)
			)
		)
		(fp_text user "License: Apache-2.0"
			(at -0.527 8.306 90)
			(layer "F.Fab")
			(effects
				(font
					(size 0.7 0.7)
					(thickness 0.15)
				)
				(justify left bottom)
			)
		)
		(pad "1" smd roundrect
			(at -0.45 -0.75 270)
			(size 0.6 0.3)
			(layers "F.Cu" "F.Mask" "F.Paste")
			(roundrect_rratio 0.25)
			(net 253 "ETH_RESET_n")
			(pinfunction "B_{2}")
			(pintype "bidirectional")
		)
		(pad "2" smd roundrect
			(at -0.45 -0.25 270)
			(size 0.6 0.25)
			(layers "F.Cu" "F.Mask" "F.Paste")
			(roundrect_rratio 0.25)
			(net 417 "GND")
			(pinfunction "GND")
			(pintype "power_in")
		)
		(pad "3" smd roundrect
			(at -0.45 0.25 270)
			(size 0.6 0.25)
			(layers "F.Cu" "F.Mask" "F.Paste")
			(roundrect_rratio 0.25)
			(net 649 "VDD")
			(pinfunction "VCC_{A}")
			(pintype "power_in")
		)
		(pad "4" smd roundrect
			(at -0.45 0.75 270)
			(size 0.6 0.3)
			(layers "F.Cu" "F.Mask" "F.Paste")
			(roundrect_rratio 0.25)
			(net 566 "/FPGA GPIO/PF_ETH_RESET_n")
			(pinfunction "A_{2}")
			(pintype "bidirectional")
		)
		(pad "5" smd roundrect
			(at 0.45 0.75 270)
			(size 0.6 0.3)
			(layers "F.Cu" "F.Mask" "F.Paste")
			(roundrect_rratio 0.25)
			(net 565 "/FPGA GPIO/PF_ETH_PWDN_n")
			(pinfunction "A_{1}")
			(pintype "bidirectional")
		)
		(pad "6" smd roundrect
			(at 0.45 0.25 270)
			(size 0.6 0.25)
			(layers "F.Cu" "F.Mask" "F.Paste")
			(roundrect_rratio 0.25)
			(net 649 "VDD")
			(pinfunction "OE")
			(pintype "input")
		)
		(pad "7" smd roundrect
			(at 0.45 -0.25 270)
			(size 0.6 0.25)
			(layers "F.Cu" "F.Mask" "F.Paste")
			(roundrect_rratio 0.25)
			(net 50 "+3V3")
			(pinfunction "VCC_{B}")
			(pintype "power_in")
		)
		(pad "8" smd roundrect
			(at 0.45 -0.75 270)
			(size 0.6 0.3)
			(layers "F.Cu" "F.Mask" "F.Paste")
			(roundrect_rratio 0.25)
			(net 217 "ETH_PWDN_n")
			(pinfunction "B_{1}")
			(pintype "bidirectional")
		)
	)
	(footprint "antmicro-footprints:R_0402_1005Metric"
		(layer "F.Cu")
		(at 227.16 141.26 90)
		(descr "Resistor SMD 0402")
		(tags "resistor SMD 0402")
		(property "Reference" "R152"
			(at -1.122484 -0.772697 90)
			(layer "F.SilkS")
			(hide yes)
			(effects
				(font
					(size 0.7 0.7)
					(thickness 0.15)
				)
				(justify left bottom)
			)
		)
		(property "Value" "R_0R_0402"
			(at -1.011843 1.772047 90)
			(layer "F.Fab")
			(hide yes)
			(effects
				(font
					(size 0.7 0.7)
					(thickness 0.15)
				)
				(justify left bottom)
			)
		)
		(property "Datasheet" "https://industrial.panasonic.com/cdbs/www-data/pdf/RDA0000/AOA0000C301.pdf"
			(at 0 0 90)
			(layer "F.Fab")
			(hide yes)
			(effects
				(font
					(size 1.27 1.27)
					(thickness 0.15)
				)
			)
		)
		(property "Description" "SMD Chip Resistor, Jumper, 0 ohm, 100 mW, 0402 [1005 Metric], Thick Film, General Purpose"
			(at 0 0 90)
			(layer "F.Fab")
			(hide yes)
			(effects
				(font
					(size 1.27 1.27)
					(thickness 0.15)
				)
			)
		)
		(property "Author" "Antmicro"
			(at 368.42 -85.9 0)
			(layer "F.Fab")
			(hide yes)
			(effects
				(font
					(size 1 1)
					(thickness 0.15)
				)
			)
		)
		(property "Current" "1A"
			(at 368.42 -85.9 0)
			(layer "F.Fab")
			(hide yes)
			(effects
				(font
					(size 1 1)
					(thickness 0.15)
				)
			)
		)
		(property "License" "Apache-2.0"
			(at 368.42 -85.9 0)
			(layer "F.Fab")
			(hide yes)
			(effects
				(font
					(size 1 1)
					(thickness 0.15)
				)
			)
		)
		(property "MPN" "ERJ2GE0R00X"
			(at 368.42 -85.9 0)
			(layer "F.Fab")
			(hide yes)
			(effects
				(font
					(size 1 1)
					(thickness 0.15)
				)
			)
		)
		(property "Manufacturer" "Panasonic"
			(at 368.42 -85.9 0)
			(layer "F.Fab")
			(hide yes)
			(effects
				(font
					(size 1 1)
					(thickness 0.15)
				)
			)
		)
		(property "Public" ""
			(at 368.42 -85.9 0)
			(layer "F.Fab")
			(hide yes)
			(effects
				(font
					(size 1 1)
					(thickness 0.15)
				)
			)
		)
		(property "Tolerance" "~"
			(at 368.42 -85.9 0)
			(layer "F.Fab")
			(hide yes)
			(effects
				(font
					(size 1 1)
					(thickness 0.15)
				)
			)
		)
		(property "Val" "0R"
			(at 368.42 -85.9 0)
			(layer "F.Fab")
			(hide yes)
			(effects
				(font
					(size 1 1)
					(thickness 0.15)
				)
			)
		)
		(sheetname "/WiFi_Bluetooth/")
		(sheetfile "wifi_bt.kicad_sch")
		(attr smd)
		(fp_rect
			(start -0.925 -0.47)
			(end 0.925 0.47)
			(stroke
				(width 0.05)
				(type default)
			)
			(fill no)
			(layer "F.CrtYd")
		)
		(fp_rect
			(start -0.5 -0.25)
			(end 0.5 0.25)
			(stroke
				(width 0.15)
				(type solid)
			)
			(fill no)
			(layer "F.Fab")
		)
		(fp_text user "License: Apache-2.0"
			(at -0.95 5.169 90)
			(layer "F.Fab")
			(effects
				(font
					(size 0.7 0.7)
					(thickness 0.15)
				)
				(justify left bottom)
			)
		)
		(fp_text user "Author: Antmicro"
			(at -0.95 4.169 90)
			(layer "F.Fab")
			(effects
				(font
					(size 0.7 0.7)
					(thickness 0.15)
				)
				(justify left bottom)
			)
		)
		(fp_text user "${REFERENCE}"
			(at -0.95 3.168 90)
			(layer "F.Fab")
			(effects
				(font
					(size 0.7 0.7)
					(thickness 0.15)
				)
				(justify left bottom)
			)
		)
		(pad "1" smd roundrect
			(at -0.48 0 90)
			(size 0.59 0.64)
			(layers "F.Cu" "F.Mask" "F.Paste")
			(roundrect_rratio 0.25)
			(net 232 "Net-(U26A-WL_ANT)")
			(pintype "passive")
		)
		(pad "2" smd roundrect
			(at 0.48 0 90)
			(size 0.59 0.64)
			(layers "F.Cu" "F.Mask" "F.Paste")
			(roundrect_rratio 0.25)
			(net 178 "Net-(J3-Pad1)")
			(pintype "passive")
		)
	)
	(footprint "antmicro-footprints:Oscillator_SMD_ECS_1612MV_1.6x1.2x0.6mm"
		(layer "F.Cu")
		(at 198.3 144.13 90)
		(property "Reference" "Y5"
			(at 0.8 -0.77 180)
			(layer "F.SilkS")
			(effects
				(font
					(size 0.7 0.7)
					(thickness 0.15)
				)
				(justify left bottom)
			)
		)
		(property "Value" "Oscillator_50MHz_ECS_1612MV"
			(at 1.75 1.25 90)
			(layer "F.Fab")
			(hide yes)
			(effects
				(font
					(size 0.7 0.7)
					(thickness 0.15)
				)
				(justify left bottom)
			)
		)
		(property "Datasheet" "https://ecsxtal.com/store/pdf/ECS-1612MV.pdf"
			(at 0 0 90)
			(layer "F.Fab")
			(hide yes)
			(effects
				(font
					(size 1.27 1.27)
					(thickness 0.15)
				)
			)
		)
		(property "Description" "50 MHz XO (Standard) CMOS Oscillator 1.6V ~ 3.63V Standby 4-SMD, No Lead"
			(at 0 0 90)
			(layer "F.Fab")
			(hide yes)
			(effects
				(font
					(size 1.27 1.27)
					(thickness 0.15)
				)
			)
		)
		(property "Author" "Antmicro"
			(at 342.43 -54.17 0)
			(layer "F.Fab")
			(hide yes)
			(effects
				(font
					(size 1 1)
					(thickness 0.15)
				)
			)
		)
		(property "License" "Apache-2.0"
			(at 342.43 -54.17 0)
			(layer "F.Fab")
			(hide yes)
			(effects
				(font
					(size 1 1)
					(thickness 0.15)
				)
			)
		)
		(property "MPN" "ECS-1612MV-500-CN-TR"
			(at 342.43 -54.17 0)
			(layer "F.Fab")
			(hide yes)
			(effects
				(font
					(size 1 1)
					(thickness 0.15)
				)
			)
		)
		(property "Manufacturer" "ECS Inc. International"
			(at 342.43 -54.17 0)
			(layer "F.Fab")
			(hide yes)
			(effects
				(font
					(size 1 1)
					(thickness 0.15)
				)
			)
		)
		(property "Public" ""
			(at 342.43 -54.17 0)
			(layer "F.Fab")
			(hide yes)
			(effects
				(font
					(size 1 1)
					(thickness 0.15)
				)
			)
		)
		(property "Val" "50 MHz"
			(at 342.43 -54.17 0)
			(layer "F.Fab")
			(hide yes)
			(effects
				(font
					(size 1 1)
					(thickness 0.15)
				)
			)
		)
		(sheetname "/FPGA HSIO/")
		(sheetfile "fpga-hsio.kicad_sch")
		(attr smd)
		(fp_line
			(start 0.97 -1.17)
			(end 0.5 -1.17)
			(stroke
				(width 0.15)
				(type solid)
			)
			(layer "F.SilkS")
		)
		(fp_line
			(start -0.97 -1.17)
			(end -0.5 -1.17)
			(stroke
				(width 0.15)
				(type solid)
			)
			(layer "F.SilkS")
		)
		(fp_line
			(start 0.97 -0.7)
			(end 0.97 -1.17)
			(stroke
				(width 0.15)
				(type solid)
			)
			(layer "F.SilkS")
		)
		(fp_line
			(start -0.97 -0.7)
			(end -0.97 -1.17)
			(stroke
				(width 0.15)
				(type solid)
			)
			(layer "F.SilkS")
		)
		(fp_line
			(start 0.97 0.7)
			(end 0.97 1.17)
			(stroke
				(width 0.15)
				(type solid)
			)
			(layer "F.SilkS")
		)
		(fp_line
			(start -0.97 0.7)
			(end -0.97 1.17)
			(stroke
				(width 0.15)
				(type solid)
			)
			(layer "F.SilkS")
		)
		(fp_line
			(start 0.97 1.17)
			(end 0.5 1.17)
			(stroke
				(width 0.15)
				(type solid)
			)
			(layer "F.SilkS")
		)
		(fp_line
			(start -0.97 1.17)
			(end -0.5 1.17)
			(stroke
				(width 0.15)
				(type solid)
			)
			(layer "F.SilkS")
		)
		(fp_circle
			(center -1.05 -0.55)
			(end -1 -0.55)
			(stroke
				(width 0.15)
				(type solid)
			)
			(fill yes)
			(layer "F.SilkS")
		)
		(fp_rect
			(start -0.75 -0.95)
			(end 0.75 0.95)
			(stroke
				(width 0.05)
				(type solid)
			)
			(fill no)
			(layer "F.CrtYd")
		)
		(fp_line
			(start 0.6 -0.8)
			(end 0.6 0.8)
			(stroke
				(width 0.15)
				(type solid)
			)
			(layer "F.Fab")
		)
		(fp_line
			(start -0.6 -0.8)
			(end 0.6 -0.8)
			(stroke
				(width 0.15)
				(type solid)
			)
			(layer "F.Fab")
		)
		(fp_line
			(start 0.6 0.8)
			(end -0.6 0.8)
			(stroke
				(width 0.15)
				(type solid)
			)
			(layer "F.Fab")
		)
		(fp_line
			(start -0.6 0.8)
			(end -0.6 -0.8)
			(stroke
				(width 0.15)
				(type solid)
			)
			(layer "F.Fab")
		)
		(fp_text user "Author: Antmicro"
			(at 1.75 3.45 90)
			(layer "F.Fab")
			(effects
				(font
					(size 0.7 0.7)
					(thickness 0.15)
				)
				(justify left bottom)
			)
		)
		(fp_text user "License: Apache-2.0"
			(at 1.75 2.25 90)
			(layer "F.Fab")
			(effects
				(font
					(size 0.7 0.7)
					(thickness 0.15)
				)
				(justify left bottom)
			)
		)
		(fp_text user "${REFERENCE}"
			(at 1.75 4.65 90)
			(layer "F.Fab")
			(effects
				(font
					(size 0.7 0.7)
					(thickness 0.15)
				)
				(justify left bottom)
			)
		)
		(pad "1" smd rect
			(at -0.4 -0.55 90)
			(size 0.5 0.6)
			(layers "F.Cu" "F.Mask" "F.Paste")
			(net 48 "+1V8")
			(pinfunction "EN")
			(pintype "input")
			(solder_mask_margin 0.102)
		)
		(pad "2" smd rect
			(at -0.4 0.55 90)
			(size 0.5 0.6)
			(layers "F.Cu" "F.Mask" "F.Paste")
			(net 417 "GND")
			(pinfunction "GND")
			(pintype "power_in")
			(solder_mask_margin 0.102)
		)
		(pad "3" smd rect
			(at 0.4 0.55 90)
			(size 0.5 0.6)
			(layers "F.Cu" "F.Mask" "F.Paste")
			(net 336 "/FPGA HSIO/PF_CLK")
			(pinfunction "OUT")
			(pintype "output")
			(solder_mask_margin 0.102)
		)
		(pad "4" smd rect
			(at 0.4 -0.55 90)
			(size 0.5 0.6)
			(layers "F.Cu" "F.Mask" "F.Paste")
			(net 48 "+1V8")
			(pinfunction "VDD")
			(pintype "power_in")
			(solder_mask_margin 0.102)
		)
	)
	(footprint "antmicro-footprints:XSON-8_1x1.95mm_P0.5mm"
		(layer "F.Cu")
		(at 222.35 120.15)
		(property "Reference" "U19"
			(at -0.74 1.16 90)
			(layer "F.SilkS")
			(effects
				(font
					(size 0.7 0.7)
					(thickness 0.15)
				)
				(justify left bottom)
			)
		)
		(property "Value" "NTS0102_XSON"
			(at 0 2.2 0)
			(layer "F.Fab")
			(hide yes)
			(effects
				(font
					(size 0.7 0.7)
					(thickness 0.15)
				)
				(justify left bottom)
			)
		)
		(property "Datasheet" "http://www.farnell.com/datasheets/1760723.pdf"
			(at 0 0 0)
			(layer "F.Fab")
			(hide yes)
			(effects
				(font
					(size 1.27 1.27)
					(thickness 0.15)
				)
			)
		)
		(property "Description" "Transceiver, 1.65 V to 3.6 V, XSON-8"
			(at 0 0 0)
			(layer "F.Fab")
			(hide yes)
			(effects
				(font
					(size 1.27 1.27)
					(thickness 0.15)
				)
			)
		)
		(property "Author" "Antmicro"
			(at 0 0 0)
			(layer "F.Fab")
			(hide yes)
			(effects
				(font
					(size 1 1)
					(thickness 0.15)
				)
			)
		)
		(property "License" "Apache-2.0"
			(at 0 0 0)
			(layer "F.Fab")
			(hide yes)
			(effects
				(font
					(size 1 1)
					(thickness 0.15)
				)
			)
		)
		(property "MPN" "NTS0102GT"
			(at 0 0 0)
			(layer "F.Fab")
			(hide yes)
			(effects
				(font
					(size 1 1)
					(thickness 0.15)
				)
			)
		)
		(property "Manufacturer" "NXP"
			(at 0 0 0)
			(layer "F.Fab")
			(hide yes)
			(effects
				(font
					(size 1 1)
					(thickness 0.15)
				)
			)
		)
		(sheetname "/FPGA GPIO/")
		(sheetfile "fpga-gpio.kicad_sch")
		(attr smd)
		(fp_line
			(start -0.5 -1.1)
			(end 0.5 -1.1)
			(stroke
				(width 0.15)
				(type solid)
			)
			(layer "F.SilkS")
		)
		(fp_line
			(start 0.5 1.1)
			(end -0.5 1.1)
			(stroke
				(width 0.15)
				(type solid)
			)
			(layer "F.SilkS")
		)
		(fp_circle
			(center -0.75 -1.1)
			(end -0.701 -1.1)
			(stroke
				(width 0.15)
				(type solid)
			)
			(fill no)
			(layer "F.SilkS")
		)
		(fp_rect
			(start -0.8 -1.2)
			(end 0.8 1.2)
			(stroke
				(width 0.05)
				(type solid)
			)
			(fill no)
			(layer "F.CrtYd")
		)
		(fp_line
			(start -0.5305 -1.001)
			(end 0.5305 -1.001)
			(stroke
				(width 0.15)
				(type solid)
			)
			(layer "F.Fab")
		)
		(fp_line
			(start -0.5305 1)
			(end -0.5305 -1.001)
			(stroke
				(width 0.15)
				(type solid)
			)
			(layer "F.Fab")
		)
		(fp_line
			(start 0.5305 -1.001)
			(end 0.5305 1)
			(stroke
				(width 0.15)
				(type solid)
			)
			(layer "F.Fab")
		)
		(fp_line
			(start 0.5305 1)
			(end -0.5305 1)
			(stroke
				(width 0.15)
				(type solid)
			)
			(layer "F.Fab")
		)
		(fp_text user "${REFERENCE}"
			(at -0.527 5.905 0)
			(layer "F.Fab")
			(effects
				(font
					(size 0.7 0.7)
					(thickness 0.15)
				)
				(justify left bottom)
			)
		)
		(fp_text user "Author: Antmicro"
			(at -0.527 7.105 0)
			(layer "F.Fab")
			(effects
				(font
					(size 0.7 0.7)
					(thickness 0.15)
				)
				(justify left bottom)
			)
		)
		(fp_text user "License: Apache-2.0"
			(at -0.527 8.306 0)
			(layer "F.Fab")
			(effects
				(font
					(size 0.7 0.7)
					(thickness 0.15)
				)
				(justify left bottom)
			)
		)
		(pad "1" smd roundrect
			(at -0.45 -0.75 180)
			(size 0.6 0.3)
			(layers "F.Cu" "F.Mask" "F.Paste")
			(roundrect_rratio 0.25)
			(net 343 "/Ethernet/ETH.MDIO")
			(pinfunction "B_{2}")
			(pintype "bidirectional")
		)
		(pad "2" smd roundrect
			(at -0.45 -0.25 180)
			(size 0.6 0.25)
			(layers "F.Cu" "F.Mask" "F.Paste")
			(roundrect_rratio 0.25)
			(net 417 "GND")
			(pinfunction "GND")
			(pintype "power_in")
		)
		(pad "3" smd roundrect
			(at -0.45 0.25 180)
			(size 0.6 0.25)
			(layers "F.Cu" "F.Mask" "F.Paste")
			(roundrect_rratio 0.25)
			(net 649 "VDD")
			(pinfunction "VCC_{A}")
			(pintype "power_in")
		)
		(pad "4" smd roundrect
			(at -0.45 0.75 180)
			(size 0.6 0.3)
			(layers "F.Cu" "F.Mask" "F.Paste")
			(roundrect_rratio 0.25)
			(net 349 "/FPGA GPIO/PF_ETH_MDIO")
			(pinfunction "A_{2}")
			(pintype "bidirectional")
		)
		(pad "5" smd roundrect
			(at 0.45 0.75 180)
			(size 0.6 0.3)
			(layers "F.Cu" "F.Mask" "F.Paste")
			(roundrect_rratio 0.25)
			(net 344 "/FPGA GPIO/PF_ETH_MDC")
			(pinfunction "A_{1}")
			(pintype "bidirectional")
		)
		(pad "6" smd roundrect
			(at 0.45 0.25 180)
			(size 0.6 0.25)
			(layers "F.Cu" "F.Mask" "F.Paste")
			(roundrect_rratio 0.25)
			(net 649 "VDD")
			(pinfunction "OE")
			(pintype "input")
		)
		(pad "7" smd roundrect
			(at 0.45 -0.25 180)
			(size 0.6 0.25)
			(layers "F.Cu" "F.Mask" "F.Paste")
			(roundrect_rratio 0.25)
			(net 50 "+3V3")
			(pinfunction "VCC_{B}")
			(pintype "power_in")
		)
		(pad "8" smd roundrect
			(at 0.45 -0.75 180)
			(size 0.6 0.3)
			(layers "F.Cu" "F.Mask" "F.Paste")
			(roundrect_rratio 0.25)
			(net 618 "/Ethernet/ETH.MDC")
			(pinfunction "B_{1}")
			(pintype "bidirectional")
		)
	)
	(footprint "antmicro-footprints:R_0402_1005Metric"
		(layer "F.Cu")
		(at 179.55 138.3175 -90)
		(descr "Resistor SMD 0402")
		(tags "resistor SMD 0402")
		(property "Reference" "R11"
			(at -3.1775 -8 180)
			(layer "F.SilkS")
			(effects
				(font
					(size 0.7 0.7)
					(thickness 0.15)
				)
				(justify right bottom)
			)
		)
		(property "Value" "R_4R7_0402"
			(at -1.011843 1.772047 90)
			(layer "F.Fab")
			(hide yes)
			(effects
				(font
					(size 0.7 0.7)
					(thickness 0.15)
				)
				(justify right bottom)
			)
		)
		(property "Datasheet" "https://www.bourns.com/docs/product-datasheets/cr.pdf"
			(at 0 0 270)
			(layer "F.Fab")
			(hide yes)
			(effects
				(font
					(size 1.27 1.27)
					(thickness 0.15)
				)
			)
		)
		(property "Description" "SMD Chip Resistor, 4.7 ohm, ± 1%, 62.5 mW, 0402 [1005 Metric], Thick Film, General Purpose"
			(at 0 0 270)
			(layer "F.Fab")
			(hide yes)
			(effects
				(font
					(size 1.27 1.27)
					(thickness 0.15)
				)
			)
		)
		(property "Author" "Antmicro"
			(at 41.2325 317.8675 0)
			(layer "F.Fab")
			(hide yes)
			(effects
				(font
					(size 1 1)
					(thickness 0.15)
				)
			)
		)
		(property "License" "Apache-2.0"
			(at 41.2325 317.8675 0)
			(layer "F.Fab")
			(hide yes)
			(effects
				(font
					(size 1 1)
					(thickness 0.15)
				)
			)
		)
		(property "MPN" "CR0402-FX-4R70GLF"
			(at 41.2325 317.8675 0)
			(layer "F.Fab")
			(hide yes)
			(effects
				(font
					(size 1 1)
					(thickness 0.15)
				)
			)
		)
		(property "Manufacturer" "Bourns"
			(at 41.2325 317.8675 0)
			(layer "F.Fab")
			(hide yes)
			(effects
				(font
					(size 1 1)
					(thickness 0.15)
				)
			)
		)
		(property "Public" ""
			(at 41.2325 317.8675 0)
			(layer "F.Fab")
			(hide yes)
			(effects
				(font
					(size 1 1)
					(thickness 0.15)
				)
			)
		)
		(property "Tolerance" "1%"
			(at 41.2325 317.8675 0)
			(layer "F.Fab")
			(hide yes)
			(effects
				(font
					(size 1 1)
					(thickness 0.15)
				)
			)
		)
		(property "Val" "4R7"
			(at 41.2325 317.8675 0)
			(layer "F.Fab")
			(hide yes)
			(effects
				(font
					(size 1 1)
					(thickness 0.15)
				)
			)
		)
		(sheetname "/Supply/")
		(sheetfile "supply.kicad_sch")
		(attr smd)
		(fp_rect
			(start -0.925 -0.47)
			(end 0.925 0.47)
			(stroke
				(width 0.05)
				(type default)
			)
			(fill no)
			(layer "F.CrtYd")
		)
		(fp_rect
			(start -0.5 -0.25)
			(end 0.5 0.25)
			(stroke
				(width 0.15)
				(type solid)
			)
			(fill no)
			(layer "F.Fab")
		)
		(fp_text user "${REFERENCE}"
			(at -0.95 3.168 270)
			(layer "F.Fab")
			(effects
				(font
					(size 0.7 0.7)
					(thickness 0.15)
				)
				(justify left bottom)
			)
		)
		(fp_text user "Author: Antmicro"
			(at -0.95 4.169 270)
			(layer "F.Fab")
			(effects
				(font
					(size 0.7 0.7)
					(thickness 0.15)
				)
				(justify left bottom)
			)
		)
		(fp_text user "License: Apache-2.0"
			(at -0.95 5.169 270)
			(layer "F.Fab")
			(effects
				(font
					(size 0.7 0.7)
					(thickness 0.15)
				)
				(justify left bottom)
			)
		)
		(pad "1" smd roundrect
			(at -0.48 0 270)
			(size 0.59 0.64)
			(layers "F.Cu" "F.Mask" "F.Paste")
			(roundrect_rratio 0.25)
			(net 90 "+5V")
			(pintype "passive")
		)
		(pad "2" smd roundrect
			(at 0.48 0 270)
			(size 0.59 0.64)
			(layers "F.Cu" "F.Mask" "F.Paste")
			(roundrect_rratio 0.25)
			(net 3 "Net-(U7-AVIN)")
			(pintype "passive")
		)
	)
	(footprint "antmicro-footprints:R_0402_1005Metric"
		(layer "F.Cu")
		(at 183.1 121.45)
		(descr "Resistor SMD 0402")
		(tags "resistor SMD 0402")
		(property "Reference" "R91"
			(at 3.14 4.58 90)
			(layer "F.SilkS")
			(effects
				(font
					(size 0.7 0.7)
					(thickness 0.15)
				)
				(justify left bottom)
			)
		)
		(property "Value" "R_0R_0402"
			(at -1.011843 1.772047 0)
			(layer "F.Fab")
			(hide yes)
			(effects
				(font
					(size 0.7 0.7)
					(thickness 0.15)
				)
				(justify left bottom)
			)
		)
		(property "Datasheet" "https://industrial.panasonic.com/cdbs/www-data/pdf/RDA0000/AOA0000C301.pdf"
			(at 0 0 0)
			(layer "F.Fab")
			(hide yes)
			(effects
				(font
					(size 1.27 1.27)
					(thickness 0.15)
				)
			)
		)
		(property "Description" "SMD Chip Resistor, Jumper, 0 ohm, 100 mW, 0402 [1005 Metric], Thick Film, General Purpose"
			(at 0 0 0)
			(layer "F.Fab")
			(hide yes)
			(effects
				(font
					(size 1.27 1.27)
					(thickness 0.15)
				)
			)
		)
		(property "Author" "Antmicro"
			(at 0 0 0)
			(layer "F.Fab")
			(hide yes)
			(effects
				(font
					(size 1 1)
					(thickness 0.15)
				)
			)
		)
		(property "Current" "1A"
			(at 0 0 0)
			(layer "F.Fab")
			(hide yes)
			(effects
				(font
					(size 1 1)
					(thickness 0.15)
				)
			)
		)
		(property "DNP" "DNP"
			(at 0 0 0)
			(layer "F.Fab")
			(hide yes)
			(effects
				(font
					(size 1 1)
					(thickness 0.15)
				)
			)
		)
		(property "License" "Apache-2.0"
			(at 0 0 0)
			(layer "F.Fab")
			(hide yes)
			(effects
				(font
					(size 1 1)
					(thickness 0.15)
				)
			)
		)
		(property "MPN" "ERJ2GE0R00X"
			(at 0 0 0)
			(layer "F.Fab")
			(hide yes)
			(effects
				(font
					(size 1 1)
					(thickness 0.15)
				)
			)
		)
		(property "Manufacturer" "Panasonic"
			(at 0 0 0)
			(layer "F.Fab")
			(hide yes)
			(effects
				(font
					(size 1 1)
					(thickness 0.15)
				)
			)
		)
		(property "Public" ""
			(at 0 0 0)
			(layer "F.Fab")
			(hide yes)
			(effects
				(font
					(size 1 1)
					(thickness 0.15)
				)
			)
		)
		(property "Tolerance" "~"
			(at 0 0 0)
			(layer "F.Fab")
			(hide yes)
			(effects
				(font
					(size 1 1)
					(thickness 0.15)
				)
			)
		)
		(property "Val" "0R"
			(at 0 0 0)
			(layer "F.Fab")
			(hide yes)
			(effects
				(font
					(size 1 1)
					(thickness 0.15)
				)
			)
		)
		(sheetname "/FPGA Config/")
		(sheetfile "fpga-config.kicad_sch")
		(attr smd)
		(fp_rect
			(start -0.925 -0.47)
			(end 0.925 0.47)
			(stroke
				(width 0.05)
				(type default)
			)
			(fill no)
			(layer "F.CrtYd")
		)
		(fp_rect
			(start -0.5 -0.25)
			(end 0.5 0.25)
			(stroke
				(width 0.15)
				(type solid)
			)
			(fill no)
			(layer "F.Fab")
		)
		(fp_text user "Author: Antmicro"
			(at -0.95 4.169 0)
			(layer "F.Fab")
			(effects
				(font
					(size 0.7 0.7)
					(thickness 0.15)
				)
				(justify left bottom)
			)
		)
		(fp_text user "${REFERENCE}"
			(at -0.95 3.168 0)
			(layer "F.Fab")
			(effects
				(font
					(size 0.7 0.7)
					(thickness 0.15)
				)
				(justify left bottom)
			)
		)
		(fp_text user "License: Apache-2.0"
			(at -0.95 5.169 0)
			(layer "F.Fab")
			(effects
				(font
					(size 0.7 0.7)
					(thickness 0.15)
				)
				(justify left bottom)
			)
		)
		(pad "1" smd roundrect
			(at -0.48 0)
			(size 0.59 0.64)
			(layers "F.Cu" "F.Mask" "F.Paste")
			(roundrect_rratio 0.25)
			(net 125 "JTAG_TDO")
			(pintype "passive")
		)
		(pad "2" smd roundrect
			(at 0.48 0)
			(size 0.59 0.64)
			(layers "F.Cu" "F.Mask" "F.Paste")
			(roundrect_rratio 0.25)
			(net 189 "Net-(U1D-TDO)")
			(pintype "passive")
		)
	)
	(footprint "antmicro-footprints:FB_0402_1005Metric"
		(layer "F.Cu")
		(at 208.085 145.8)
		(descr "Ferrite Bead SMD 0402")
		(tags "ferrite bead SMD 0402")
		(property "Reference" "FB6"
			(at -6.135 8.515 90)
			(layer "F.SilkS")
			(effects
				(font
					(size 0.7 0.7)
					(thickness 0.15)
				)
				(justify left bottom)
			)
		)
		(property "Value" "FB_120Z_1.2A_TDK-MPZ_0402"
			(at 0 1.4 0)
			(layer "F.Fab")
			(hide yes)
			(effects
				(font
					(size 0.7 0.7)
					(thickness 0.15)
				)
				(justify left bottom)
			)
		)
		(property "Datasheet" "https://product.tdk.com/en/search/emc/emc/beads/info?part_no=MPZ1005S121CT000"
			(at 0 0 0)
			(layer "F.Fab")
			(hide yes)
			(effects
				(font
					(size 1.27 1.27)
					(thickness 0.15)
				)
			)
		)
		(property "Description" "Ferrite Bead, 0402 [1005 Metric], 120 ohm, 1.2A, MPZ, 0.06 ohm, ± 25%, DC Power line"
			(at 0 0 0)
			(layer "F.Fab")
			(hide yes)
			(effects
				(font
					(size 1.27 1.27)
					(thickness 0.15)
				)
			)
		)
		(property "Author" "Antmicro"
			(at 0 0 0)
			(layer "F.Fab")
			(hide yes)
			(effects
				(font
					(size 1 1)
					(thickness 0.15)
				)
			)
		)
		(property "Current" ""
			(at 0 0 0)
			(layer "F.Fab")
			(hide yes)
			(effects
				(font
					(size 1 1)
					(thickness 0.15)
				)
			)
		)
		(property "License" "Apache-2.0"
			(at 0 0 0)
			(layer "F.Fab")
			(hide yes)
			(effects
				(font
					(size 1 1)
					(thickness 0.15)
				)
			)
		)
		(property "MPN" "MPZ1005S121CT000"
			(at 0 0 0)
			(layer "F.Fab")
			(hide yes)
			(effects
				(font
					(size 1 1)
					(thickness 0.15)
				)
			)
		)
		(property "Manufacturer" "TDK"
			(at 0 0 0)
			(layer "F.Fab")
			(hide yes)
			(effects
				(font
					(size 1 1)
					(thickness 0.15)
				)
			)
		)
		(property "Public" ""
			(at 0 0 0)
			(layer "F.Fab")
			(hide yes)
			(effects
				(font
					(size 1 1)
					(thickness 0.15)
				)
			)
		)
		(property "Val" "120Z/1.2A"
			(at 0 0 0)
			(layer "F.Fab")
			(hide yes)
			(effects
				(font
					(size 1 1)
					(thickness 0.15)
				)
			)
		)
		(sheetname "/MIPI CrossLink/")
		(sheetfile "crosslink.kicad_sch")
		(attr smd)
		(fp_rect
			(start -0.925 -0.47)
			(end 0.925 0.47)
			(stroke
				(width 0.05)
				(type default)
			)
			(fill no)
			(layer "F.CrtYd")
		)
		(fp_rect
			(start -0.5 -0.25)
			(end 0.5 0.25)
			(stroke
				(width 0.15)
				(type solid)
			)
			(fill no)
			(layer "F.Fab")
		)
		(fp_text user "Author: Antmicro"
			(at -0.95 4.169 0)
			(layer "F.Fab")
			(effects
				(font
					(size 0.7 0.7)
					(thickness 0.15)
				)
				(justify left bottom)
			)
		)
		(fp_text user "${REFERENCE}"
			(at -0.95 3.168 0)
			(layer "F.Fab")
			(effects
				(font
					(size 0.7 0.7)
					(thickness 0.15)
				)
				(justify left bottom)
			)
		)
		(fp_text user "License: Apache-2.0"
			(at -0.95 5.169 0)
			(layer "F.Fab")
			(effects
				(font
					(size 0.7 0.7)
					(thickness 0.15)
				)
				(justify left bottom)
			)
		)
		(pad "1" smd roundrect
			(at -0.48 0)
			(size 0.59 0.64)
			(layers "F.Cu" "F.Mask" "F.Paste")
			(roundrect_rratio 0.25)
			(net 185 "/MIPI CrossLink/CL_VCCIO1")
			(pintype "passive")
		)
		(pad "2" smd roundrect
			(at 0.48 0)
			(size 0.59 0.64)
			(layers "F.Cu" "F.Mask" "F.Paste")
			(roundrect_rratio 0.25)
			(net 237 "1V8_CL")
			(pintype "passive")
		)
	)
	(footprint "antmicro-footprints:C_0402_1005Metric"
		(layer "F.Cu")
		(at 218.21 155.115 180)
		(descr "Capacitor SMD 0402")
		(tags "capacitor SMD 0402")
		(property "Reference" "C53"
			(at 2.86 -0.495 0)
			(layer "F.SilkS")
			(effects
				(font
					(size 0.7 0.7)
					(thickness 0.15)
				)
				(justify right bottom)
			)
		)
		(property "Value" "C_100n_0402"
			(at -1.022927 2.155213 0)
			(layer "F.Fab")
			(hide yes)
			(effects
				(font
					(size 0.7 0.7)
					(thickness 0.15)
				)
				(justify right bottom)
			)
		)
		(property "Datasheet" "https://www.murata.com/products/productdetail?partno=GRM155R61H104KE14%23"
			(at 0 0 180)
			(layer "F.Fab")
			(hide yes)
			(effects
				(font
					(size 1.27 1.27)
					(thickness 0.15)
				)
			)
		)
		(property "Description" "SMD Multilayer Ceramic Capacitor, 0.1 µF, 50 V, 0402 [1005 Metric], ± 10%, X5R, GRM Series"
			(at 0 0 180)
			(layer "F.Fab")
			(hide yes)
			(effects
				(font
					(size 1.27 1.27)
					(thickness 0.15)
				)
			)
		)
		(property "Author" "Antmicro"
			(at 436.42 310.23 0)
			(layer "F.Fab")
			(hide yes)
			(effects
				(font
					(size 1 1)
					(thickness 0.15)
				)
			)
		)
		(property "Dielectric" "X5R"
			(at 436.42 310.23 0)
			(layer "F.Fab")
			(hide yes)
			(effects
				(font
					(size 1 1)
					(thickness 0.15)
				)
			)
		)
		(property "License" "Apache-2.0"
			(at 436.42 310.23 0)
			(layer "F.Fab")
			(hide yes)
			(effects
				(font
					(size 1 1)
					(thickness 0.15)
				)
			)
		)
		(property "MPN" "GRM155R61H104KE14D"
			(at 436.42 310.23 0)
			(layer "F.Fab")
			(hide yes)
			(effects
				(font
					(size 1 1)
					(thickness 0.15)
				)
			)
		)
		(property "Manufacturer" "Murata"
			(at 436.42 310.23 0)
			(layer "F.Fab")
			(hide yes)
			(effects
				(font
					(size 1 1)
					(thickness 0.15)
				)
			)
		)
		(property "Public" ""
			(at 436.42 310.23 0)
			(layer "F.Fab")
			(hide yes)
			(effects
				(font
					(size 1 1)
					(thickness 0.15)
				)
			)
		)
		(property "Val" "100n"
			(at 436.42 310.23 0)
			(layer "F.Fab")
			(hide yes)
			(effects
				(font
					(size 1 1)
					(thickness 0.15)
				)
			)
		)
		(property "Voltage" "50V"
			(at 436.42 310.23 0)
			(layer "F.Fab")
			(hide yes)
			(effects
				(font
					(size 1 1)
					(thickness 0.15)
				)
			)
		)
		(sheetname "/PCIe/")
		(sheetfile "pcie.kicad_sch")
		(attr smd)
		(fp_rect
			(start -0.925 -0.47)
			(end 0.925 0.47)
			(stroke
				(width 0.05)
				(type default)
			)
			(fill no)
			(layer "F.CrtYd")
		)
		(fp_line
			(start 0.504 0.248)
			(end -0.494 0.248)
			(stroke
				(width 0.15)
				(type solid)
			)
			(layer "F.Fab")
		)
		(fp_line
			(start 0.504 -0.25)
			(end 0.504 0.248)
			(stroke
				(width 0.15)
				(type solid)
			)
			(layer "F.Fab")
		)
		(fp_line
			(start -0.494 0.248)
			(end -0.494 -0.25)
			(stroke
				(width 0.15)
				(type solid)
			)
			(layer "F.Fab")
		)
		(fp_line
			(start -0.494 -0.25)
			(end 0.504 -0.25)
			(stroke
				(width 0.15)
				(type solid)
			)
			(layer "F.Fab")
		)
		(fp_text user "License: Apache-2.0"
			(at -0.939 5.799 180)
			(layer "F.Fab")
			(effects
				(font
					(size 0.7 0.7)
					(thickness 0.15)
				)
				(justify left bottom)
			)
		)
		(fp_text user "${REFERENCE}"
			(at -0.939 4.599 180)
			(layer "F.Fab")
			(effects
				(font
					(size 0.7 0.7)
					(thickness 0.15)
				)
				(justify left bottom)
			)
		)
		(fp_text user "Author: Antmicro"
			(at -0.939 3.399 180)
			(layer "F.Fab")
			(effects
				(font
					(size 0.7 0.7)
					(thickness 0.15)
				)
				(justify left bottom)
			)
		)
		(pad "1" smd roundrect
			(at -0.48 0 180)
			(size 0.59 0.64)
			(layers "F.Cu" "F.Mask" "F.Paste")
			(roundrect_rratio 0.25)
			(net 314 "Net-(U17-CLK1-)")
			(pintype "passive")
		)
		(pad "2" smd roundrect
			(at 0.48 0 180)
			(size 0.59 0.64)
			(layers "F.Cu" "F.Mask" "F.Paste")
			(roundrect_rratio 0.25)
			(net 4 "/Bottom Connector/PCIE.CLK_N")
			(pintype "passive")
		)
	)
	(footprint "antmicro-footprints:Oscillator_SMD_ECS_2016MV_2x1.6x0.85mm"
		(layer "F.Cu")
		(at 222.2168 117.3457 180)
		(property "Reference" "Y2"
			(at -2.0232 0.0557 90)
			(layer "F.SilkS")
			(effects
				(font
					(size 0.7 0.7)
					(thickness 0.15)
				)
				(justify left bottom)
			)
		)
		(property "Value" "Oscillator_25MHz_ESC_2016MV"
			(at 0 2.2 0)
			(layer "F.Fab")
			(hide yes)
			(effects
				(font
					(size 0.7 0.7)
					(thickness 0.15)
				)
				(justify right bottom)
			)
		)
		(property "Datasheet" "https://ecsxtal.com/store/pdf/ECS-2016MV.pdf"
			(at 0 0 180)
			(layer "F.Fab")
			(hide yes)
			(effects
				(font
					(size 1.27 1.27)
					(thickness 0.15)
				)
			)
		)
		(property "Description" "Oscillator, 25 MHz, HCMOS, SMD, 2mm x 1.6mm, MultiVolt ECS-2016MV Series"
			(at 0 0 180)
			(layer "F.Fab")
			(hide yes)
			(effects
				(font
					(size 1.27 1.27)
					(thickness 0.15)
				)
			)
		)
		(property "Author" "Antmicro"
			(at 444.4336 234.6914 0)
			(layer "F.Fab")
			(hide yes)
			(effects
				(font
					(size 1 1)
					(thickness 0.15)
				)
			)
		)
		(property "License" "Apache-2.0"
			(at 444.4336 234.6914 0)
			(layer "F.Fab")
			(hide yes)
			(effects
				(font
					(size 1 1)
					(thickness 0.15)
				)
			)
		)
		(property "MPN" "ECS-2016MV-250-CN-TR"
			(at 444.4336 234.6914 0)
			(layer "F.Fab")
			(hide yes)
			(effects
				(font
					(size 1 1)
					(thickness 0.15)
				)
			)
		)
		(property "Manufacturer" "ECS Inc. International"
			(at 444.4336 234.6914 0)
			(layer "F.Fab")
			(hide yes)
			(effects
				(font
					(size 1 1)
					(thickness 0.15)
				)
			)
		)
		(property "Public" ""
			(at 444.4336 234.6914 0)
			(layer "F.Fab")
			(hide yes)
			(effects
				(font
					(size 1 1)
					(thickness 0.15)
				)
			)
		)
		(property "Val" "25 MHz"
			(at 444.4336 234.6914 0)
			(layer "F.Fab")
			(hide yes)
			(effects
				(font
					(size 1 1)
					(thickness 0.15)
				)
			)
		)
		(sheetname "/Ethernet/")
		(sheetfile "ethernet.kicad_sch")
		(attr smd)
		(fp_line
			(start 0.95 0.4)
			(end 0.95 -0.4)
			(stroke
				(width 0.15)
				(type solid)
			)
			(layer "F.SilkS")
		)
		(fp_line
			(start -0.4 1.15)
			(end 0.4 1.15)
			(stroke
				(width 0.15)
				(type solid)
			)
			(layer "F.SilkS")
		)
		(fp_line
			(start -0.4 -1.15)
			(end 0.4 -1.15)
			(stroke
				(width 0.15)
				(type solid)
			)
			(layer "F.SilkS")
		)
		(fp_line
			(start -0.95 0.4)
			(end -0.95 -0.4)
			(stroke
				(width 0.15)
				(type solid)
			)
			(layer "F.SilkS")
		)
		(fp_circle
			(center -0.95 -1.15)
			(end -0.9 -1.15)
			(stroke
				(width 0.15)
				(type solid)
			)
			(fill yes)
			(layer "F.SilkS")
		)
		(fp_rect
			(start -1.05 -1.25)
			(end 1.05 1.24)
			(stroke
				(width 0.05)
				(type solid)
			)
			(fill no)
			(layer "F.CrtYd")
		)
		(fp_rect
			(start -0.85 -1.054)
			(end 0.852 1.054)
			(stroke
				(width 0.15)
				(type solid)
			)
			(fill no)
			(layer "F.Fab")
		)
		(fp_text user "${REFERENCE}"
			(at -1.05 3.4 180)
			(layer "F.Fab")
			(effects
				(font
					(size 0.7 0.7)
					(thickness 0.15)
				)
				(justify left bottom)
			)
		)
		(fp_text user "Author: Antmicro"
			(at -1.05 4.6 180)
			(layer "F.Fab")
			(effects
				(font
					(size 0.7 0.7)
					(thickness 0.15)
				)
				(justify left bottom)
			)
		)
		(fp_text user "License: Apache-2.0"
			(at -1.05 5.8 180)
			(layer "F.Fab")
			(effects
				(font
					(size 0.7 0.7)
					(thickness 0.15)
				)
				(justify left bottom)
			)
		)
		(pad "1" smd rect
			(at -0.486 -0.637 180)
			(size 0.6858 0.7874)
			(layers "F.Cu" "F.Mask" "F.Paste")
			(net 50 "+3V3")
			(pinfunction "EN")
			(pintype "input")
		)
		(pad "2" smd rect
			(at -0.486 0.636 180)
			(size 0.6858 0.7874)
			(layers "F.Cu" "F.Mask" "F.Paste")
			(net 417 "GND")
			(pinfunction "GND")
			(pintype "power_in")
		)
		(pad "3" smd rect
			(at 0.487 0.636 180)
			(size 0.6858 0.7874)
			(layers "F.Cu" "F.Mask" "F.Paste")
			(net 13 "/Ethernet/X_I")
			(pinfunction "OUT")
			(pintype "output")
		)
		(pad "4" smd rect
			(at 0.487 -0.637 180)
			(size 0.6858 0.7874)
			(layers "F.Cu" "F.Mask" "F.Paste")
			(net 50 "+3V3")
			(pinfunction "VDD")
			(pintype "power_in")
		)
	)
	(footprint "antmicro-footprints:TP_SMD_0.75mm"
		(layer "F.Cu")
		(at 223.3 138.75)
		(property "Reference" "TP3"
			(at 0 -0.6 0)
			(layer "F.SilkS")
			(hide yes)
			(effects
				(font
					(size 0.7 0.7)
					(thickness 0.15)
				)
				(justify left bottom)
			)
		)
		(property "Value" "TP_0.75mm_SMD"
			(at 0 1.2 0)
			(layer "F.Fab")
			(hide yes)
			(effects
				(font
					(size 0.7 0.7)
					(thickness 0.15)
				)
				(justify left bottom)
			)
		)
		(property "Description" "SMT test point"
			(at 0 0 0)
			(layer "F.Fab")
			(hide yes)
			(effects
				(font
					(size 1.27 1.27)
					(thickness 0.15)
				)
			)
		)
		(property "Author" "Antmicro"
			(at 0 0 0)
			(layer "F.Fab")
			(hide yes)
			(effects
				(font
					(size 1 1)
					(thickness 0.15)
				)
			)
		)
		(property "License" "Apache-2.0"
			(at 0 0 0)
			(layer "F.Fab")
			(hide yes)
			(effects
				(font
					(size 1 1)
					(thickness 0.15)
				)
			)
		)
		(property "MPN" ""
			(at 0 0 0)
			(layer "F.Fab")
			(hide yes)
			(effects
				(font
					(size 1 1)
					(thickness 0.15)
				)
			)
		)
		(property "Manufacturer" ""
			(at 0 0 0)
			(layer "F.Fab")
			(hide yes)
			(effects
				(font
					(size 1 1)
					(thickness 0.15)
				)
			)
		)
		(property "Public" "False"
			(at 0 0 0)
			(layer "F.Fab")
			(hide yes)
			(effects
				(font
					(size 1 1)
					(thickness 0.15)
				)
			)
		)
		(sheetname "/WiFi_Bluetooth/")
		(sheetfile "wifi_bt.kicad_sch")
		(attr exclude_from_pos_files exclude_from_bom)
		(fp_circle
			(center 0 0)
			(end 0.475 0)
			(stroke
				(width 0.05)
				(type default)
			)
			(fill no)
			(layer "F.CrtYd")
		)
		(fp_text user "License: Apache-2.0"
			(at -0.4 5.101 0)
			(layer "F.Fab")
			(effects
				(font
					(size 0.7 0.7)
					(thickness 0.15)
				)
				(justify left bottom)
			)
		)
		(fp_text user "Author: Antmicro"
			(at -0.4 3.901 0)
			(layer "F.Fab")
			(effects
				(font
					(size 0.7 0.7)
					(thickness 0.15)
				)
				(justify left bottom)
			)
		)
		(fp_text user "${REFERENCE}"
			(at -0.4 2.7 0)
			(layer "F.Fab")
			(effects
				(font
					(size 0.7 0.7)
					(thickness 0.15)
				)
				(justify left bottom)
			)
		)
		(pad "1" smd circle
			(at 0 0)
			(size 0.75 0.75)
			(layers "F.Cu" "F.Mask")
			(net 621 "Net-(U26A-RF_SW_CTRL_5)")
			(pinfunction "1")
			(pintype "passive")
		)
	)
	(footprint "antmicro-footprints:LED_0603_1608Metric_G"
		(layer "F.Cu")
		(at 182.8 154.8 180)
		(descr "LED SMD 0603 Green")
		(tags "LED SMD 0603 Green")
		(property "Reference" "D5"
			(at -4.1 -0.025 0)
			(layer "F.SilkS")
			(effects
				(font
					(size 0.7 0.7)
					(thickness 0.15)
				)
				(justify right top)
			)
		)
		(property "Value" "LED_G_0603_LTST-C190GKT"
			(at -0.001 1.599 0)
			(layer "F.Fab")
			(hide yes)
			(effects
				(font
					(size 0.7 0.7)
					(thickness 0.15)
				)
				(justify right top)
			)
		)
		(property "Datasheet" "https://media.digikey.com/pdf/Data%20Sheets/Lite-On%20PDFs/LTST-C190GKT.pdf"
			(at 0 0 0)
			(layer "F.Fab")
			(hide yes)
			(effects
				(font
					(size 1.27 1.27)
					(thickness 0.15)
				)
			)
		)
		(property "Description" "LED, Green, SMD, 0603, 20 mA, 2.1 V, 569 nm"
			(at 0 0 0)
			(layer "F.Fab")
			(hide yes)
			(effects
				(font
					(size 1.27 1.27)
					(thickness 0.15)
				)
			)
		)
		(property "Author" "Antmicro"
			(at 0 0 0)
			(layer "F.Fab")
			(hide yes)
			(effects
				(font
					(size 1 1)
					(thickness 0.15)
				)
			)
		)
		(property "Color" "Green"
			(at 0 0 0)
			(layer "F.Fab")
			(hide yes)
			(effects
				(font
					(size 1 1)
					(thickness 0.15)
				)
			)
		)
		(property "License" "Apache-2.0"
			(at 0 0 0)
			(layer "F.Fab")
			(hide yes)
			(effects
				(font
					(size 1 1)
					(thickness 0.15)
				)
			)
		)
		(property "MPN" "LTST-C190GKT"
			(at 0 0 0)
			(layer "F.Fab")
			(hide yes)
			(effects
				(font
					(size 1 1)
					(thickness 0.15)
				)
			)
		)
		(property "Manufacturer" "Lite-On"
			(at 0 0 0)
			(layer "F.Fab")
			(hide yes)
			(effects
				(font
					(size 1 1)
					(thickness 0.15)
				)
			)
		)
		(property "Public" ""
			(at 0 0 0)
			(layer "F.Fab")
			(hide yes)
			(effects
				(font
					(size 1 1)
					(thickness 0.15)
				)
			)
		)
		(property "VSD_class" "LED"
			(at 0 0 0)
			(layer "F.Fab")
			(hide yes)
			(effects
				(font
					(size 1 1)
					(thickness 0.15)
				)
			)
		)
		(sheetname "/Supply/")
		(sheetfile "supply.kicad_sch")
		(attr smd)
		(fp_line
			(start 0.22 0.35)
			(end -0.22 0.35)
			(stroke
				(width 0.15)
				(type solid)
			)
			(layer "F.SilkS")
		)
		(fp_line
			(start 0.22 -0.35)
			(end -0.22 -0.35)
			(stroke
				(width 0.15)
				(type solid)
			)
			(layer "F.SilkS")
		)
		(fp_line
			(start 0.105328 0.201008)
			(end 0.105328 -0.198992)
			(stroke
				(width 0.1)
				(type solid)
			)
			(layer "F.SilkS")
		)
		(fp_line
			(start 0.105328 0.201008)
			(end -0.094672 0.001008)
			(stroke
				(width 0.1)
				(type solid)
			)
			(layer "F.SilkS")
		)
		(fp_line
			(start 0.105328 0.001008)
			(end 0.24 0.001)
			(stroke
				(width 0.1)
				(type solid)
			)
			(layer "F.SilkS")
		)
		(fp_line
			(start -0.094672 0.201008)
			(end -0.094672 -0.198992)
			(stroke
				(width 0.1)
				(type solid)
			)
			(layer "F.SilkS")
		)
		(fp_line
			(start -0.094672 0.001008)
			(end 0.105328 -0.198992)
			(stroke
				(width 0.1)
				(type solid)
			)
			(layer "F.SilkS")
		)
		(fp_line
			(start -0.094672 0.001008)
			(end -0.24 0.001008)
			(stroke
				(width 0.1)
				(type solid)
			)
			(layer "F.SilkS")
		)
		(fp_line
			(start -1.18 -0.319)
			(end -1.18 0.321)
			(stroke
				(width 0.15)
				(type solid)
			)
			(layer "F.SilkS")
		)
		(fp_rect
			(start 1.25 0.65)
			(end -1.25 -0.65)
			(stroke
				(width 0.05)
				(type solid)
			)
			(fill no)
			(layer "F.CrtYd")
		)
		(fp_line
			(start 0.599 0)
			(end 0.201 0)
			(stroke
				(width 0.15)
				(type solid)
			)
			(layer "F.Fab")
		)
		(fp_line
			(start 0.201 0.2)
			(end 0.201 0)
			(stroke
				(width 0.15)
				(type solid)
			)
			(layer "F.Fab")
		)
		(fp_line
			(start 0.201 0)
			(end 0.201 -0.202)
			(stroke
				(width 0.15)
				(type solid)
			)
			(layer "F.Fab")
		)
		(fp_line
			(start 0.201 -0.202)
			(end -0.101 0)
			(stroke
				(width 0.15)
				(type solid)
			)
			(layer "F.Fab")
		)
		(fp_line
			(start -0.101 0)
			(end 0.201 0.2)
			(stroke
				(width 0.15)
				(type solid)
			)
			(layer "F.Fab")
		)
		(fp_line
			(start -0.199 0.2)
			(end -0.199 0.1)
			(stroke
				(width 0.15)
				(type solid)
			)
			(layer "F.Fab")
		)
		(fp_line
			(start -0.199 0)
			(end -0.597 0)
			(stroke
				(width 0.15)
				(type solid)
			)
			(layer "F.Fab")
		)
		(fp_line
			(start -0.199 -0.202)
			(end -0.199 0.1)
			(stroke
				(width 0.15)
				(type solid)
			)
			(layer "F.Fab")
		)
		(fp_rect
			(start 0.848 0.4)
			(end -0.85 -0.402)
			(stroke
				(width 0.15)
				(type solid)
			)
			(fill no)
			(layer "F.Fab")
		)
		(fp_text user "${REFERENCE}"
			(at -1.4224 5.999 180)
			(layer "F.Fab")
			(effects
				(font
					(size 0.7 0.7)
					(thickness 0.15)
				)
				(justify left bottom)
			)
		)
		(fp_text user "License: Apache-2.0"
			(at -1.4224 3.599 180)
			(layer "F.Fab")
			(effects
				(font
					(size 0.7 0.7)
					(thickness 0.15)
				)
				(justify left bottom)
			)
		)
		(fp_text user "Author: Antmicro"
			(at -1.4224 4.799 180)
			(layer "F.Fab")
			(effects
				(font
					(size 0.7 0.7)
					(thickness 0.15)
				)
				(justify left bottom)
			)
		)
		(pad "1" smd roundrect
			(at -0.7 0)
			(size 0.8 1)
			(layers "F.Cu" "F.Mask" "F.Paste")
			(roundrect_rratio 0.2)
			(net 230 "~{PG}")
			(pinfunction "C")
			(pintype "passive")
		)
		(pad "2" smd roundrect
			(at 0.7 0)
			(size 0.8 1)
			(layers "F.Cu" "F.Mask" "F.Paste")
			(roundrect_rratio 0.2)
			(net 650 "Net-(D5-A)")
			(pinfunction "A")
			(pintype "passive")
		)
	)
	(footprint "antmicro-footprints:LED_1204_3210Metric_RGB_Horizontal"
		(layer "F.Cu")
		(at 228.675 126.749999 90)
		(descr "Footprint based on: https://optoelectronics.liteon.com/upload/download/DS22-2003-047/LTST-S310F2KT.PDF")
		(property "Reference" "D6"
			(at 0 -1.695 90)
			(unlocked yes)
			(layer "F.SilkS")
			(effects
				(font
					(size 0.7 0.7)
					(thickness 0.15)
				)
				(justify left bottom)
			)
		)
		(property "Value" "LED_RGB_1204_LTST-S310F2KT_Horizontal"
			(at 0 2.195 90)
			(unlocked yes)
			(layer "F.Fab")
			(hide yes)
			(effects
				(font
					(size 0.7 0.7)
					(thickness 0.15)
				)
				(justify left bottom)
			)
		)
		(property "Datasheet" "https://optoelectronics.liteon.com/upload/download/DS22-2003-047/LTST-S310F2KT.PDF"
			(at 0 0 90)
			(layer "F.Fab")
			(hide yes)
			(effects
				(font
					(size 0.7 0.7)
					(thickness 0.15)
				)
				(justify left bottom)
			)
		)
		(property "Description" "LED, RGB, SMD, 1204, R 30 mA, G 20 mA, B 20 mA, R 2 V, G 3.5 V, B 3.5 V, Common Anode, Side Look"
			(at 0 0 90)
			(layer "F.Fab")
			(hide yes)
			(effects
				(font
					(size 0.7 0.7)
					(thickness 0.15)
				)
				(justify left bottom)
			)
		)
		(property "MPN" "LTST-S310F2KT"
			(at 0 0 90)
			(unlocked yes)
			(layer "F.Fab")
			(hide yes)
			(effects
				(font
					(size 1 1)
					(thickness 0.15)
				)
			)
		)
		(property "Manufacturer" "Lite-On"
			(at 0 0 90)
			(unlocked yes)
			(layer "F.Fab")
			(hide yes)
			(effects
				(font
					(size 1 1)
					(thickness 0.15)
				)
			)
		)
		(property "Author" "Antmicro"
			(at 0 0 90)
			(unlocked yes)
			(layer "F.Fab")
			(hide yes)
			(effects
				(font
					(size 1 1)
					(thickness 0.15)
				)
			)
		)
		(property "License" "Apache-2.0"
			(at 0 0 90)
			(unlocked yes)
			(layer "F.Fab")
			(hide yes)
			(effects
				(font
					(size 1 1)
					(thickness 0.15)
				)
			)
		)
		(property "Color" "R, G, B"
			(at 0 0 90)
			(unlocked yes)
			(layer "F.Fab")
			(hide yes)
			(effects
				(font
					(size 1 1)
					(thickness 0.15)
				)
			)
		)
		(sheetname "/FPGA GPIO/")
		(sheetfile "fpga-gpio.kicad_sch")
		(attr smd)
		(fp_circle
			(center 1 -0.805)
			(end 1.05 -0.805)
			(stroke
				(width 0.15)
				(type solid)
			)
			(fill yes)
			(layer "F.SilkS")
		)
		(fp_rect
			(start -2.75 -1.145)
			(end 2.75 1.495)
			(stroke
				(width 0.05)
				(type solid)
			)
			(fill no)
			(layer "F.CrtYd")
		)
		(fp_text user "${REFERENCE}"
			(at -2.75 3.495 90)
			(unlocked yes)
			(layer "F.Fab")
			(effects
				(font
					(size 0.7 0.7)
					(thickness 0.15)
				)
				(justify left bottom)
			)
		)
		(fp_text user "Author: Antmicro"
			(at -2.75 5.895 90)
			(layer "F.Fab")
			(effects
				(font
					(size 0.7 0.7)
					(thickness 0.15)
				)
				(justify left bottom)
			)
		)
		(fp_text user "License: Apache-2.0"
			(at -2.75 4.695 90)
			(layer "F.Fab")
			(effects
				(font
					(size 0.7 0.7)
					(thickness 0.15)
				)
				(justify left bottom)
			)
		)
		(pad "1" smd roundrect
			(at 0.4 -0.5 90)
			(size 0.5 0.8)
			(layers "F.Cu" "F.Mask" "F.Paste")
			(roundrect_rratio 0.1)
			(net 385 "Net-(D6-C_{R})")
			(pinfunction "C_{R}")
			(pintype "passive")
		)
		(pad "2" smd roundrect
			(at -0.4 -0.5 90)
			(size 0.5 0.8)
			(layers "F.Cu" "F.Mask" "F.Paste")
			(roundrect_rratio 0.1)
			(net 538 "Net-(D6-C_{G})")
			(pinfunction "C_{G}")
			(pintype "passive")
		)
		(pad "3" smd roundrect
			(at -1.75 0 90)
			(size 1.5 1)
			(layers "F.Cu" "F.Mask" "F.Paste")
			(roundrect_rratio 0.05)
			(net 539 "Net-(D6-C_{B})")
			(pinfunction "C_{B}")
			(pintype "passive")
		)
		(pad "4" smd roundrect
			(at 1.75 0 90)
			(size 1.5 1)
			(layers "F.Cu" "F.Mask" "F.Paste")
			(roundrect_rratio 0.05)
			(net 90 "+5V")
			(pinfunction "A")
			(pintype "passive")
		)
	)
	(footprint "antmicro-footprints:VQFN-14-1EP_3.2x2.5mm_P0.5mm_Layout4x3"
		(layer "F.Cu")
		(at 221.23 153.085 -90)
		(property "Reference" "U17"
			(at 0.465 2.174 90)
			(unlocked yes)
			(layer "F.SilkS")
			(effects
				(font
					(size 0.7 0.7)
					(thickness 0.15)
				)
				(justify left bottom)
			)
		)
		(property "Value" "DSC557-0343FI1"
			(at 0 3.1 270)
			(unlocked yes)
			(layer "F.Fab")
			(hide yes)
			(effects
				(font
					(size 0.7 0.7)
					(thickness 0.15)
				)
				(justify left bottom)
			)
		)
		(property "Datasheet" "https://ww1.microchip.com/downloads/aemDocuments/documents/TCG/ProductDocuments/DataSheets/DSC557-03-04-05-Multiple-Output-MEMS-PCIe-Gen1-2-3-4-Clock-Generators-DS20006691.pdf"
			(at 0 0 90)
			(layer "F.Fab")
			(hide yes)
			(effects
				(font
					(size 1.27 1.27)
					(thickness 0.15)
				)
			)
		)
		(property "Description" "Two output PCIe Clock Generator"
			(at 0 0 90)
			(layer "F.Fab")
			(hide yes)
			(effects
				(font
					(size 1.27 1.27)
					(thickness 0.15)
				)
			)
		)
		(property "Author" "Antmicro"
			(at 68.159 374.329 0)
			(layer "F.Fab")
			(hide yes)
			(effects
				(font
					(size 1 1)
					(thickness 0.15)
				)
			)
		)
		(property "License" "Apache-2.0"
			(at 68.159 374.329 0)
			(layer "F.Fab")
			(hide yes)
			(effects
				(font
					(size 1 1)
					(thickness 0.15)
				)
			)
		)
		(property "MPN" "DSC557-0343FI1"
			(at 68.159 374.329 0)
			(layer "F.Fab")
			(hide yes)
			(effects
				(font
					(size 1 1)
					(thickness 0.15)
				)
			)
		)
		(property "Manufacturer" "Microchip Technology"
			(at 68.159 374.329 0)
			(layer "F.Fab")
			(hide yes)
			(effects
				(font
					(size 1 1)
					(thickness 0.15)
				)
			)
		)
		(property "Val" "100 MHz"
			(at 68.159 374.329 0)
			(layer "F.Fab")
			(hide yes)
			(effects
				(font
					(size 1 1)
					(thickness 0.15)
				)
			)
		)
		(property ki_fp_filters "QFN14_3.2X2.5_MCH QFN14_3.2X2.5_MCH-M QFN14_3.2X2.5_MCH-L")
		(sheetname "/PCIe/")
		(sheetfile "pcie.kicad_sch")
		(attr smd)
		(fp_circle
			(center -1.5 -1.075)
			(end -1.45 -1.075)
			(stroke
				(width 0.15)
				(type solid)
			)
			(fill yes)
			(layer "F.SilkS")
		)
		(fp_rect
			(start -1.746 -2.101)
			(end 1.745 2.1)
			(stroke
				(width 0.05)
				(type solid)
			)
			(fill no)
			(layer "F.CrtYd")
		)
		(fp_line
			(start -1.266 1.677)
			(end 1.269 1.677)
			(stroke
				(width 0.15)
				(type solid)
			)
			(layer "F.Fab")
		)
		(fp_line
			(start -1.266 1.677)
			(end -1.266 -1.067)
			(stroke
				(width 0.15)
				(type solid)
			)
			(layer "F.Fab")
		)
		(fp_line
			(start 1.269 1.677)
			(end 1.269 -1.625)
			(stroke
				(width 0.15)
				(type solid)
			)
			(layer "F.Fab")
		)
		(fp_line
			(start -1.266 -1.067)
			(end -0.758 -1.625)
			(stroke
				(width 0.15)
				(type solid)
			)
			(layer "F.Fab")
		)
		(fp_line
			(start 1.269 -1.625)
			(end -0.758 -1.625)
			(stroke
				(width 0.15)
				(type solid)
			)
			(layer "F.Fab")
		)
		(fp_text user "License: Apache-2.0"
			(at -1.746 7.499 270)
			(layer "F.Fab")
			(effects
				(font
					(size 0.7 0.7)
					(thickness 0.15)
				)
				(justify left bottom)
			)
		)
		(fp_text user "Author: Antmicro"
			(at -1.746 6.299 270)
			(layer "F.Fab")
			(effects
				(font
					(size 0.7 0.7)
					(thickness 0.15)
				)
				(justify left bottom)
			)
		)
		(fp_text user "${REFERENCE}"
			(at -1.746 5.099 270)
			(unlocked yes)
			(layer "F.Fab")
			(effects
				(font
					(size 0.7 0.7)
					(thickness 0.15)
				)
				(justify left bottom)
			)
		)
		(pad "1" smd rect
			(at -1.3 -0.762)
			(size 0.3 0.7)
			(layers "F.Cu" "F.Mask" "F.Paste")
			(net 418 "+2V5")
			(pinfunction "OE")
			(pintype "input")
		)
		(pad "2" smd rect
			(at -1.3 -0.25)
			(size 0.3 0.7)
			(layers "F.Cu" "F.Mask" "F.Paste")
			(net 569 "unconnected-(U17-NC-Pad2)")
			(pinfunction "NC")
			(pintype "no_connect")
		)
		(pad "3" smd rect
			(at -1.3 0.25)
			(size 0.3 0.7)
			(layers "F.Cu" "F.Mask" "F.Paste")
			(net 570 "unconnected-(U17-NC-Pad3)")
			(pinfunction "NC")
			(pintype "no_connect")
		)
		(pad "4" smd rect
			(at -1.3 0.75)
			(size 0.3 0.7)
			(layers "F.Cu" "F.Mask" "F.Paste")
			(net 417 "GND")
			(pinfunction "VSS")
			(pintype "power_in")
		)
		(pad "5" smd rect
			(at -0.5 1.65 270)
			(size 0.3 0.7)
			(layers "F.Cu" "F.Mask" "F.Paste")
			(net 571 "unconnected-(U17-NC-Pad5)")
			(pinfunction "NC")
			(pintype "no_connect")
		)
		(pad "6" smd rect
			(at 0 1.65 270)
			(size 0.3 0.7)
			(layers "F.Cu" "F.Mask" "F.Paste")
			(net 572 "unconnected-(U17-NC-Pad6)")
			(pinfunction "NC")
			(pintype "no_connect")
		)
		(pad "7" smd rect
			(at 0.5 1.65 270)
			(size 0.3 0.7)
			(layers "F.Cu" "F.Mask" "F.Paste")
			(net 573 "unconnected-(U17-NC-Pad7)")
			(pinfunction "NC")
			(pintype "no_connect")
		)
		(pad "8" smd rect
			(at 1.3 0.75 180)
			(size 0.3 0.7)
			(layers "F.Cu" "F.Mask" "F.Paste")
			(net 315 "Net-(U17-CLK1+)")
			(pinfunction "CLK1+")
			(pintype "output")
		)
		(pad "9" smd rect
			(at 1.3 0.25 180)
			(size 0.3 0.7)
			(layers "F.Cu" "F.Mask" "F.Paste")
			(net 314 "Net-(U17-CLK1-)")
			(pinfunction "CLK1-")
			(pintype "output")
		)
		(pad "10" smd rect
			(at 1.3 -0.25 180)
			(size 0.3 0.7)
			(layers "F.Cu" "F.Mask" "F.Paste")
			(net 562 "/PCIe/PF_PCIe_CLK_N")
			(pinfunction "CLK0-")
			(pintype "output")
		)
		(pad "11" smd rect
			(at 1.3 -0.75 180)
			(size 0.3 0.7)
			(layers "F.Cu" "F.Mask" "F.Paste")
			(net 461 "/PCIe/PF_PCIe_CLK_P")
			(pinfunction "CLK0+")
			(pintype "output")
		)
		(pad "12" smd rect
			(at 0.5 -1.65 90)
			(size 0.3 0.7)
			(layers "F.Cu" "F.Mask" "F.Paste")
			(net 418 "+2V5")
			(pinfunction "VDD1")
			(pintype "power_in")
		)
		(pad "13" smd rect
			(at 0 -1.65 90)
			(size 0.3 0.7)
			(layers "F.Cu" "F.Mask" "F.Paste")
			(net 418 "+2V5")
			(pinfunction "VDD0")
			(pintype "power_in")
		)
		(pad "14" smd rect
			(at -0.5 -1.65 90)
			(size 0.3 0.7)
			(layers "F.Cu" "F.Mask" "F.Paste")
			(net 574 "unconnected-(U17-NC-Pad14)")
			(pinfunction "NC")
			(pintype "no_connect")
		)
		(pad "15" smd roundrect
			(at 0.003 0)
			(size 2.1 1.4)
			(layers "F.Cu" "F.Mask" "F.Paste")
			(roundrect_rratio 0)
			(chamfer_ratio 0.2)
			(chamfer top_right)
			(net 417 "GND")
			(pinfunction "EPAD")
			(pintype "unspecified")
		)
	)
	(footprint "antmicro-footprints:R_0402_1005Metric"
		(layer "F.Cu")
		(at 214.185 139.2 180)
		(descr "Resistor SMD 0402")
		(tags "resistor SMD 0402")
		(property "Reference" "R58"
			(at -3.265 -0.41 180)
			(layer "F.SilkS")
			(effects
				(font
					(size 0.7 0.7)
					(thickness 0.15)
				)
				(justify left bottom)
			)
		)
		(property "Value" "R_1k_0402"
			(at -1.011843 1.772047 180)
			(layer "F.Fab")
			(hide yes)
			(effects
				(font
					(size 0.7 0.7)
					(thickness 0.15)
				)
				(justify left bottom)
			)
		)
		(property "Datasheet" "https://www.bourns.com/docs/product-datasheets/cr.pdf"
			(at 0 0 180)
			(layer "F.Fab")
			(hide yes)
			(effects
				(font
					(size 1.27 1.27)
					(thickness 0.15)
				)
			)
		)
		(property "Description" "SMD Chip Resistor, 1 kohm, ± 1%, 63 mW, 0402 [1005 Metric], Thick Film, General Purpose"
			(at 0 0 180)
			(layer "F.Fab")
			(hide yes)
			(effects
				(font
					(size 1.27 1.27)
					(thickness 0.15)
				)
			)
		)
		(property "Author" "Antmicro"
			(at 428.37 278.4 0)
			(layer "F.Fab")
			(hide yes)
			(effects
				(font
					(size 1 1)
					(thickness 0.15)
				)
			)
		)
		(property "DNP" "DNP"
			(at 428.37 278.4 0)
			(layer "F.Fab")
			(hide yes)
			(effects
				(font
					(size 1 1)
					(thickness 0.15)
				)
			)
		)
		(property "License" "Apache-2.0"
			(at 428.37 278.4 0)
			(layer "F.Fab")
			(hide yes)
			(effects
				(font
					(size 1 1)
					(thickness 0.15)
				)
			)
		)
		(property "MPN" "CR0402-FX-1001GLF"
			(at 428.37 278.4 0)
			(layer "F.Fab")
			(hide yes)
			(effects
				(font
					(size 1 1)
					(thickness 0.15)
				)
			)
		)
		(property "Manufacturer" "Bourns"
			(at 428.37 278.4 0)
			(layer "F.Fab")
			(hide yes)
			(effects
				(font
					(size 1 1)
					(thickness 0.15)
				)
			)
		)
		(property "Public" ""
			(at 428.37 278.4 0)
			(layer "F.Fab")
			(hide yes)
			(effects
				(font
					(size 1 1)
					(thickness 0.15)
				)
			)
		)
		(property "Tolerance" "1%"
			(at 428.37 278.4 0)
			(layer "F.Fab")
			(hide yes)
			(effects
				(font
					(size 1 1)
					(thickness 0.15)
				)
			)
		)
		(property "Val" "1k"
			(at 428.37 278.4 0)
			(layer "F.Fab")
			(hide yes)
			(effects
				(font
					(size 1 1)
					(thickness 0.15)
				)
			)
		)
		(sheetname "/USB/")
		(sheetfile "usb.kicad_sch")
		(attr smd dnp)
		(fp_rect
			(start -0.925 -0.47)
			(end 0.925 0.47)
			(stroke
				(width 0.05)
				(type default)
			)
			(fill no)
			(layer "F.CrtYd")
		)
		(fp_rect
			(start -0.5 -0.25)
			(end 0.5 0.25)
			(stroke
				(width 0.15)
				(type solid)
			)
			(fill no)
			(layer "F.Fab")
		)
		(fp_text user "Author: Antmicro"
			(at -0.95 4.169 180)
			(layer "F.Fab")
			(effects
				(font
					(size 0.7 0.7)
					(thickness 0.15)
				)
				(justify left bottom)
			)
		)
		(fp_text user "License: Apache-2.0"
			(at -0.95 5.169 180)
			(layer "F.Fab")
			(effects
				(font
					(size 0.7 0.7)
					(thickness 0.15)
				)
				(justify left bottom)
			)
		)
		(fp_text user "${REFERENCE}"
			(at -0.95 3.168 180)
			(layer "F.Fab")
			(effects
				(font
					(size 0.7 0.7)
					(thickness 0.15)
				)
				(justify left bottom)
			)
		)
		(pad "1" smd roundrect
			(at -0.48 0 180)
			(size 0.59 0.64)
			(layers "F.Cu" "F.Mask" "F.Paste")
			(roundrect_rratio 0.25)
			(net 417 "GND")
			(pintype "passive")
		)
		(pad "2" smd roundrect
			(at 0.48 0 180)
			(size 0.59 0.64)
			(layers "F.Cu" "F.Mask" "F.Paste")
			(roundrect_rratio 0.25)
			(net 221 "VBUS")
			(pintype "passive")
		)
	)
	(footprint "antmicro-footprints:FB_0402_1005Metric"
		(layer "F.Cu")
		(at 208.085 144.825)
		(descr "Ferrite Bead SMD 0402")
		(tags "ferrite bead SMD 0402")
		(property "Reference" "FB3"
			(at -7.11 9.49 90)
			(layer "F.SilkS")
			(effects
				(font
					(size 0.7 0.7)
					(thickness 0.15)
				)
				(justify left bottom)
			)
		)
		(property "Value" "FB_120Z_1.2A_TDK-MPZ_0402"
			(at 0 1.4 0)
			(layer "F.Fab")
			(hide yes)
			(effects
				(font
					(size 0.7 0.7)
					(thickness 0.15)
				)
				(justify left bottom)
			)
		)
		(property "Datasheet" "https://product.tdk.com/en/search/emc/emc/beads/info?part_no=MPZ1005S121CT000"
			(at 0 0 0)
			(layer "F.Fab")
			(hide yes)
			(effects
				(font
					(size 1.27 1.27)
					(thickness 0.15)
				)
			)
		)
		(property "Description" "Ferrite Bead, 0402 [1005 Metric], 120 ohm, 1.2A, MPZ, 0.06 ohm, ± 25%, DC Power line"
			(at 0 0 0)
			(layer "F.Fab")
			(hide yes)
			(effects
				(font
					(size 1.27 1.27)
					(thickness 0.15)
				)
			)
		)
		(property "Author" "Antmicro"
			(at 0 0 0)
			(layer "F.Fab")
			(hide yes)
			(effects
				(font
					(size 1 1)
					(thickness 0.15)
				)
			)
		)
		(property "Current" ""
			(at 0 0 0)
			(layer "F.Fab")
			(hide yes)
			(effects
				(font
					(size 1 1)
					(thickness 0.15)
				)
			)
		)
		(property "License" "Apache-2.0"
			(at 0 0 0)
			(layer "F.Fab")
			(hide yes)
			(effects
				(font
					(size 1 1)
					(thickness 0.15)
				)
			)
		)
		(property "MPN" "MPZ1005S121CT000"
			(at 0 0 0)
			(layer "F.Fab")
			(hide yes)
			(effects
				(font
					(size 1 1)
					(thickness 0.15)
				)
			)
		)
		(property "Manufacturer" "TDK"
			(at 0 0 0)
			(layer "F.Fab")
			(hide yes)
			(effects
				(font
					(size 1 1)
					(thickness 0.15)
				)
			)
		)
		(property "Public" ""
			(at 0 0 0)
			(layer "F.Fab")
			(hide yes)
			(effects
				(font
					(size 1 1)
					(thickness 0.15)
				)
			)
		)
		(property "Val" "120Z/1.2A"
			(at 0 0 0)
			(layer "F.Fab")
			(hide yes)
			(effects
				(font
					(size 1 1)
					(thickness 0.15)
				)
			)
		)
		(sheetname "/MIPI CrossLink/")
		(sheetfile "crosslink.kicad_sch")
		(attr smd)
		(fp_rect
			(start -0.925 -0.47)
			(end 0.925 0.47)
			(stroke
				(width 0.05)
				(type default)
			)
			(fill no)
			(layer "F.CrtYd")
		)
		(fp_rect
			(start -0.5 -0.25)
			(end 0.5 0.25)
			(stroke
				(width 0.15)
				(type solid)
			)
			(fill no)
			(layer "F.Fab")
		)
		(fp_text user "License: Apache-2.0"
			(at -0.95 5.169 0)
			(layer "F.Fab")
			(effects
				(font
					(size 0.7 0.7)
					(thickness 0.15)
				)
				(justify left bottom)
			)
		)
		(fp_text user "Author: Antmicro"
			(at -0.95 4.169 0)
			(layer "F.Fab")
			(effects
				(font
					(size 0.7 0.7)
					(thickness 0.15)
				)
				(justify left bottom)
			)
		)
		(fp_text user "${REFERENCE}"
			(at -0.95 3.168 0)
			(layer "F.Fab")
			(effects
				(font
					(size 0.7 0.7)
					(thickness 0.15)
				)
				(justify left bottom)
			)
		)
		(pad "1" smd roundrect
			(at -0.48 0)
			(size 0.59 0.64)
			(layers "F.Cu" "F.Mask" "F.Paste")
			(roundrect_rratio 0.25)
			(net 180 "/MIPI CrossLink/CL_VCCGPLL")
			(pintype "passive")
		)
		(pad "2" smd roundrect
			(at 0.48 0)
			(size 0.59 0.64)
			(layers "F.Cu" "F.Mask" "F.Paste")
			(roundrect_rratio 0.25)
			(net 96 "+1V2")
			(pintype "passive")
		)
	)
	(footprint "antmicro-footprints:R_0402_1005Metric"
		(layer "F.Cu")
		(at 197.802486 117.687335)
		(descr "Resistor SMD 0402")
		(tags "resistor SMD 0402")
		(property "Reference" "R15"
			(at -2.362486 -0.697335 0)
			(layer "F.SilkS")
			(effects
				(font
					(size 0.7 0.7)
					(thickness 0.15)
				)
				(justify left bottom)
			)
		)
		(property "Value" "R_10k_0402"
			(at -1.011843 1.772047 0)
			(layer "F.Fab")
			(hide yes)
			(effects
				(font
					(size 0.7 0.7)
					(thickness 0.15)
				)
				(justify left bottom)
			)
		)
		(property "Datasheet" "https://www.bourns.com/docs/product-datasheets/cr.pdf"
			(at 0 0 0)
			(layer "F.Fab")
			(hide yes)
			(effects
				(font
					(size 1.27 1.27)
					(thickness 0.15)
				)
			)
		)
		(property "Description" "SMD Chip Resistor, 10 kohm, ± 1%, 62.5 mW, 0402 [1005 Metric], Thick Film, General Purpose"
			(at 0 0 0)
			(layer "F.Fab")
			(hide yes)
			(effects
				(font
					(size 1.27 1.27)
					(thickness 0.15)
				)
			)
		)
		(property "Author" "Antmicro"
			(at 0 0 0)
			(layer "F.Fab")
			(hide yes)
			(effects
				(font
					(size 1 1)
					(thickness 0.15)
				)
			)
		)
		(property "DNP" "DNP"
			(at 0 0 0)
			(layer "F.Fab")
			(hide yes)
			(effects
				(font
					(size 1 1)
					(thickness 0.15)
				)
			)
		)
		(property "License" "Apache-2.0"
			(at 0 0 0)
			(layer "F.Fab")
			(hide yes)
			(effects
				(font
					(size 1 1)
					(thickness 0.15)
				)
			)
		)
		(property "MPN" "CR0402-FX-1002GLF"
			(at 0 0 0)
			(layer "F.Fab")
			(hide yes)
			(effects
				(font
					(size 1 1)
					(thickness 0.15)
				)
			)
		)
		(property "Manufacturer" "Bourns"
			(at 0 0 0)
			(layer "F.Fab")
			(hide yes)
			(effects
				(font
					(size 1 1)
					(thickness 0.15)
				)
			)
		)
		(property "Public" ""
			(at 0 0 0)
			(layer "F.Fab")
			(hide yes)
			(effects
				(font
					(size 1 1)
					(thickness 0.15)
				)
			)
		)
		(property "Tolerance" "1%"
			(at 0 0 0)
			(layer "F.Fab")
			(hide yes)
			(effects
				(font
					(size 1 1)
					(thickness 0.15)
				)
			)
		)
		(property "Val" "10k"
			(at 0 0 0)
			(layer "F.Fab")
			(hide yes)
			(effects
				(font
					(size 1 1)
					(thickness 0.15)
				)
			)
		)
		(sheetname "/Top Connector/")
		(sheetfile "top-connector.kicad_sch")
		(attr smd dnp)
		(fp_rect
			(start -0.925 -0.47)
			(end 0.925 0.47)
			(stroke
				(width 0.05)
				(type default)
			)
			(fill no)
			(layer "F.CrtYd")
		)
		(fp_rect
			(start -0.5 -0.25)
			(end 0.5 0.25)
			(stroke
				(width 0.15)
				(type solid)
			)
			(fill no)
			(layer "F.Fab")
		)
		(fp_text user "License: Apache-2.0"
			(at -0.95 5.169 0)
			(layer "F.Fab")
			(effects
				(font
					(size 0.7 0.7)
					(thickness 0.15)
				)
				(justify left bottom)
			)
		)
		(fp_text user "Author: Antmicro"
			(at -0.95 4.169 0)
			(layer "F.Fab")
			(effects
				(font
					(size 0.7 0.7)
					(thickness 0.15)
				)
				(justify left bottom)
			)
		)
		(fp_text user "${REFERENCE}"
			(at -0.95 3.168 0)
			(layer "F.Fab")
			(effects
				(font
					(size 0.7 0.7)
					(thickness 0.15)
				)
				(justify left bottom)
			)
		)
		(pad "1" smd roundrect
			(at -0.48 0)
			(size 0.59 0.64)
			(layers "F.Cu" "F.Mask" "F.Paste")
			(roundrect_rratio 0.25)
			(net 221 "VBUS")
			(pintype "passive")
		)
		(pad "2" smd roundrect
			(at 0.48 0)
			(size 0.59 0.64)
			(layers "F.Cu" "F.Mask" "F.Paste")
			(roundrect_rratio 0.25)
			(net 245 "Net-(J1-Pad50)")
			(pintype "passive")
		)
	)
	(footprint "antmicro-footprints:D_0402_1005Metric"
		(layer "F.Cu")
		(at 210.200425 153.723639 90)
		(property "Reference" "D2"
			(at -1.546361 1.319575 90)
			(layer "F.SilkS")
			(effects
				(font
					(size 0.7 0.7)
					(thickness 0.15)
				)
				(justify left bottom)
			)
		)
		(property "Value" "AXGD10402KR"
			(at -2.54 2.54 90)
			(layer "F.Fab")
			(hide yes)
			(effects
				(font
					(size 0.7 0.7)
					(thickness 0.15)
				)
				(justify left bottom)
			)
		)
		(property "Datasheet" "https://www.littelfuse.com/media?resourcetype=datasheets&itemid=020b2bf2-064c-4ff1-a898-b4ec805b2fea&filename=littelfuse-xtremeguard-axgd-datasheet"
			(at 0 0 90)
			(layer "F.Fab")
			(hide yes)
			(effects
				(font
					(size 1.27 1.27)
					(thickness 0.15)
				)
			)
		)
		(property "Description" "Bidirectional TVS, 30 kV,  0402, 24 V, 0.04 pF"
			(at 0 0 90)
			(layer "F.Fab")
			(hide yes)
			(effects
				(font
					(size 1.27 1.27)
					(thickness 0.15)
				)
			)
		)
		(property "Author" "Antmicro"
			(at 363.924064 -56.476786 0)
			(layer "F.Fab")
			(hide yes)
			(effects
				(font
					(size 1 1)
					(thickness 0.15)
				)
			)
		)
		(property "License" "Apache-2.0"
			(at 363.924064 -56.476786 0)
			(layer "F.Fab")
			(hide yes)
			(effects
				(font
					(size 1 1)
					(thickness 0.15)
				)
			)
		)
		(property "MPN" "AXGD10402KR"
			(at 363.924064 -56.476786 0)
			(layer "F.Fab")
			(hide yes)
			(effects
				(font
					(size 1 1)
					(thickness 0.15)
				)
			)
		)
		(property "Manufacturer" "Littelfuse"
			(at 363.924064 -56.476786 0)
			(layer "F.Fab")
			(hide yes)
			(effects
				(font
					(size 1 1)
					(thickness 0.15)
				)
			)
		)
		(property "Public" ""
			(at 363.924064 -56.476786 0)
			(layer "F.Fab")
			(hide yes)
			(effects
				(font
					(size 1 1)
					(thickness 0.15)
				)
			)
		)
		(sheetname "/USB/")
		(sheetfile "usb.kicad_sch")
		(attr smd)
		(fp_line
			(start 0.1 -0.255)
			(end -0.1 -0.255)
			(stroke
				(width 0.15)
				(type solid)
			)
			(layer "F.SilkS")
		)
		(fp_line
			(start -0.875 -0.25)
			(end -0.875 0.25)
			(stroke
				(width 0.15)
				(type solid)
			)
			(layer "F.SilkS")
		)
		(fp_line
			(start -0.1 0.255)
			(end 0.1 0.255)
			(stroke
				(width 0.15)
				(type solid)
			)
			(layer "F.SilkS")
		)
		(fp_rect
			(start -0.925 -0.47)
			(end 0.925 0.47)
			(stroke
				(width 0.05)
				(type default)
			)
			(fill no)
			(layer "F.CrtYd")
		)
		(fp_line
			(start 0.51 -0.255)
			(end 0.51 0.255)
			(stroke
				(width 0.15)
				(type solid)
			)
			(layer "F.Fab")
		)
		(fp_line
			(start -0.51 -0.255)
			(end 0.51 -0.255)
			(stroke
				(width 0.15)
				(type solid)
			)
			(layer "F.Fab")
		)
		(fp_line
			(start -0.2 -0.25)
			(end -0.5 0.05)
			(stroke
				(width 0.15)
				(type solid)
			)
			(layer "F.Fab")
		)
		(fp_line
			(start 0.51 0.255)
			(end -0.51 0.255)
			(stroke
				(width 0.15)
				(type solid)
			)
			(layer "F.Fab")
		)
		(fp_line
			(start -0.51 0.255)
			(end -0.51 -0.255)
			(stroke
				(width 0.15)
				(type solid)
			)
			(layer "F.Fab")
		)
		(fp_text user "Author: Antmicro"
			(at -2.54 6.94 90)
			(layer "F.Fab")
			(effects
				(font
					(size 0.7 0.7)
					(thickness 0.15)
				)
				(justify left bottom)
			)
		)
		(fp_text user "License: Apache-2.0"
			(at -2.54 5.74 90)
			(layer "F.Fab")
			(effects
				(font
					(size 0.7 0.7)
					(thickness 0.15)
				)
				(justify left bottom)
			)
		)
		(fp_text user "${REFERENCE}"
			(at -2.54 4.54 90)
			(layer "F.Fab")
			(effects
				(font
					(size 0.7 0.7)
					(thickness 0.15)
				)
				(justify left bottom)
			)
		)
		(pad "1" smd roundrect
			(at -0.48 0 90)
			(size 0.59 0.64)
			(layers "F.Cu" "F.Mask" "F.Paste")
			(roundrect_rratio 0.25)
			(net 417 "GND")
			(pinfunction "C")
			(pintype "passive")
		)
		(pad "2" smd roundrect
			(at 0.48 0 90)
			(size 0.59 0.64)
			(layers "F.Cu" "F.Mask" "F.Paste")
			(roundrect_rratio 0.25)
			(net 15 "/Bottom Connector/CONN.D_N")
			(pinfunction "A")
			(pintype "passive")
		)
	)
	(footprint "antmicro-footprints:TP_SMD_0.75mm"
		(layer "F.Cu")
		(at 190.35 147.28)
		(property "Reference" "TP17"
			(at 0 -0.6 0)
			(layer "F.SilkS")
			(hide yes)
			(effects
				(font
					(size 0.7 0.7)
					(thickness 0.15)
				)
				(justify left bottom)
			)
		)
		(property "Value" "TP_0.75mm_SMD"
			(at 0 1.2 0)
			(layer "F.Fab")
			(hide yes)
			(effects
				(font
					(size 0.7 0.7)
					(thickness 0.15)
				)
				(justify left bottom)
			)
		)
		(property "Description" "SMT test point"
			(at 0 0 0)
			(layer "F.Fab")
			(hide yes)
			(effects
				(font
					(size 1.27 1.27)
					(thickness 0.15)
				)
			)
		)
		(property "Author" "Antmicro"
			(at 0 0 0)
			(layer "F.Fab")
			(hide yes)
			(effects
				(font
					(size 1 1)
					(thickness 0.15)
				)
			)
		)
		(property "License" "Apache-2.0"
			(at 0 0 0)
			(layer "F.Fab")
			(hide yes)
			(effects
				(font
					(size 1 1)
					(thickness 0.15)
				)
			)
		)
		(property "MPN" ""
			(at 0 0 0)
			(layer "F.Fab")
			(hide yes)
			(effects
				(font
					(size 1 1)
					(thickness 0.15)
				)
			)
		)
		(property "Manufacturer" ""
			(at 0 0 0)
			(layer "F.Fab")
			(hide yes)
			(effects
				(font
					(size 1 1)
					(thickness 0.15)
				)
			)
		)
		(property "Public" "False"
			(at 0 0 0)
			(layer "F.Fab")
			(hide yes)
			(effects
				(font
					(size 1 1)
					(thickness 0.15)
				)
			)
		)
		(sheetname "/HDMI/")
		(sheetfile "hdmi.kicad_sch")
		(attr exclude_from_pos_files exclude_from_bom)
		(fp_circle
			(center 0 0)
			(end 0.475 0)
			(stroke
				(width 0.05)
				(type default)
			)
			(fill no)
			(layer "F.CrtYd")
		)
		(fp_text user "License: Apache-2.0"
			(at -0.4 5.101 0)
			(layer "F.Fab")
			(effects
				(font
					(size 0.7 0.7)
					(thickness 0.15)
				)
				(justify left bottom)
			)
		)
		(fp_text user "Author: Antmicro"
			(at -0.4 3.901 0)
			(layer "F.Fab")
			(effects
				(font
					(size 0.7 0.7)
					(thickness 0.15)
				)
				(justify left bottom)
			)
		)
		(fp_text user "${REFERENCE}"
			(at -0.4 2.7 0)
			(layer "F.Fab")
			(effects
				(font
					(size 0.7 0.7)
					(thickness 0.15)
				)
				(justify left bottom)
			)
		)
		(pad "1" smd circle
			(at 0 0)
			(size 0.75 0.75)
			(layers "F.Cu" "F.Mask")
			(net 555 "Net-(U15-OC_S0)")
			(pinfunction "1")
			(pintype "passive")
		)
	)
	(footprint "antmicro-footprints:TP_SMD_0.75mm"
		(layer "F.Cu")
		(at 228.47 149.03 90)
		(property "Reference" "TP16"
			(at -3.68 9.76 180)
			(layer "F.SilkS")
			(hide yes)
			(effects
				(font
					(size 0.7 0.7)
					(thickness 0.15)
				)
				(justify left bottom)
			)
		)
		(property "Value" "TP_0.75mm_SMD"
			(at 0 1.2 90)
			(layer "F.Fab")
			(hide yes)
			(effects
				(font
					(size 0.7 0.7)
					(thickness 0.15)
				)
				(justify left bottom)
			)
		)
		(property "Description" "SMT test point"
			(at 0 0 90)
			(layer "F.Fab")
			(hide yes)
			(effects
				(font
					(size 1.27 1.27)
					(thickness 0.15)
				)
			)
		)
		(property "Author" "Antmicro"
			(at 377.5 -79.44 0)
			(layer "F.Fab")
			(hide yes)
			(effects
				(font
					(size 1 1)
					(thickness 0.15)
				)
			)
		)
		(property "License" "Apache-2.0"
			(at 377.5 -79.44 0)
			(layer "F.Fab")
			(hide yes)
			(effects
				(font
					(size 1 1)
					(thickness 0.15)
				)
			)
		)
		(property "MPN" ""
			(at 377.5 -79.44 0)
			(layer "F.Fab")
			(hide yes)
			(effects
				(font
					(size 1 1)
					(thickness 0.15)
				)
			)
		)
		(property "Manufacturer" ""
			(at 377.5 -79.44 0)
			(layer "F.Fab")
			(hide yes)
			(effects
				(font
					(size 1 1)
					(thickness 0.15)
				)
			)
		)
		(property "Public" "False"
			(at 377.5 -79.44 0)
			(layer "F.Fab")
			(hide yes)
			(effects
				(font
					(size 1 1)
					(thickness 0.15)
				)
			)
		)
		(sheetname "/WiFi_Bluetooth/")
		(sheetfile "wifi_bt.kicad_sch")
		(attr exclude_from_pos_files exclude_from_bom)
		(fp_circle
			(center 0 0)
			(end 0.475 0)
			(stroke
				(width 0.05)
				(type default)
			)
			(fill no)
			(layer "F.CrtYd")
		)
		(fp_text user "Author: Antmicro"
			(at -0.4 3.901 90)
			(layer "F.Fab")
			(effects
				(font
					(size 0.7 0.7)
					(thickness 0.15)
				)
				(justify left bottom)
			)
		)
		(fp_text user "${REFERENCE}"
			(at -0.4 2.7 90)
			(layer "F.Fab")
			(effects
				(font
					(size 0.7 0.7)
					(thickness 0.15)
				)
				(justify left bottom)
			)
		)
		(fp_text user "License: Apache-2.0"
			(at -0.4 5.101 90)
			(layer "F.Fab")
			(effects
				(font
					(size 0.7 0.7)
					(thickness 0.15)
				)
				(justify left bottom)
			)
		)
		(pad "1" smd circle
			(at 0 0 90)
			(size 0.75 0.75)
			(layers "F.Cu" "F.Mask")
			(net 521 "Net-(U26A-BT_PCM_OUT)")
			(pinfunction "1")
			(pintype "passive")
		)
	)
	(footprint "antmicro-footprints:Fiducial_1mm_Mask2mm"
		(layer "F.Cu")
		(at 175.76 120.865)
		(descr "Circular Fiducial, 1mm bare copper, 3mm soldermask opening")
		(tags "fiducial")
		(property "Reference" "FD1"
			(at 0 -1.4 0)
			(layer "F.SilkS")
			(hide yes)
			(effects
				(font
					(size 0.7 0.7)
					(thickness 0.15)
				)
				(justify left bottom)
			)
		)
		(property "Value" "Fiducial_1mm_Mask2mm"
			(at 0 2.2 0)
			(layer "F.Fab")
			(hide yes)
			(effects
				(font
					(size 0.7 0.7)
					(thickness 0.15)
				)
				(justify left bottom)
			)
		)
		(property "Description" "Fiducial mask "
			(at 0 0 0)
			(layer "F.Fab")
			(hide yes)
			(effects
				(font
					(size 1.27 1.27)
					(thickness 0.15)
				)
			)
		)
		(property "Author" "Antmicro"
			(at 0 0 0)
			(layer "F.Fab")
			(hide yes)
			(effects
				(font
					(size 1 1)
					(thickness 0.15)
				)
			)
		)
		(property "License" "Apache-2.0"
			(at 0 0 0)
			(layer "F.Fab")
			(hide yes)
			(effects
				(font
					(size 1 1)
					(thickness 0.15)
				)
			)
		)
		(property "exclude_from_bom" ""
			(at 0 0 0)
			(layer "F.Fab")
			(hide yes)
			(effects
				(font
					(size 1 1)
					(thickness 0.15)
				)
			)
		)
		(sheetfile "polarfire-som.kicad_sch")
		(attr board_only exclude_from_pos_files exclude_from_bom)
		(fp_circle
			(center 0 0)
			(end 1.24 0)
			(stroke
				(width 0.05)
				(type solid)
			)
			(fill no)
			(layer "F.CrtYd")
		)
		(fp_circle
			(center 0 0)
			(end 0.999 0)
			(stroke
				(width 0.15)
				(type solid)
			)
			(fill no)
			(layer "F.Fab")
		)
		(fp_text user "License: Apache-2.0"
			(at -1.25 7.003 0)
			(layer "F.Fab")
			(effects
				(font
					(size 0.7 0.7)
					(thickness 0.15)
				)
				(justify left bottom)
			)
		)
		(fp_text user "Author: Antmicro"
			(at -1.25 5.803 0)
			(layer "F.Fab")
			(effects
				(font
					(size 0.7 0.7)
					(thickness 0.15)
				)
				(justify left bottom)
			)
		)
		(fp_text user "${REFERENCE}"
			(at -1.25 4.603 0)
			(layer "F.Fab")
			(effects
				(font
					(size 0.7 0.7)
					(thickness 0.15)
				)
				(justify left bottom)
			)
		)
		(pad "" smd circle
			(at 0 0)
			(size 1 1)
			(layers "F.Cu" "F.Mask")
			(solder_mask_margin 0.5)
			(clearance 0.5)
		)
	)
	(footprint "antmicro-footprints:BGA-196-153_11.5x13mm_Layout14x14_P0.5x0.5mm"
		(layer "F.Cu")
		(at 214.6935 131.7)
		(property "Reference" "U2"
			(at -5.9435 -5.1 90)
			(layer "F.SilkS")
			(effects
				(font
					(size 0.7 0.7)
					(thickness 0.15)
				)
				(justify left bottom)
			)
		)
		(property "Value" "SDINBDG4-8G"
			(at 0 7.6 0)
			(layer "F.Fab")
			(hide yes)
			(effects
				(font
					(size 0.7 0.7)
					(thickness 0.15)
				)
				(justify left bottom)
			)
		)
		(property "Datasheet" "https://www.infineon.com/dgdl/Infineon-AN98491_Recommended_PCB_Routing_Guidelines_for_a_Infineon_e.MMC_Memory_Device-ApplicationNotes-v05_00-EN.pdf?fileId=8ac78c8c7d718a49017d71baea97084d"
			(at 0 0 0)
			(layer "F.Fab")
			(hide yes)
			(effects
				(font
					(size 1.27 1.27)
					(thickness 0.15)
				)
			)
		)
		(property "Description" "NAND Flash Serial e-MMC 64G-bit SanDisk iNAND 7250 Industrial emmc"
			(at 0 0 0)
			(layer "F.Fab")
			(hide yes)
			(effects
				(font
					(size 1.27 1.27)
					(thickness 0.15)
				)
			)
		)
		(property "Author" "Antmicro"
			(at 0 0 0)
			(layer "F.Fab")
			(hide yes)
			(effects
				(font
					(size 1 1)
					(thickness 0.15)
				)
			)
		)
		(property "License" "Apache-2.0"
			(at 0 0 0)
			(layer "F.Fab")
			(hide yes)
			(effects
				(font
					(size 1 1)
					(thickness 0.15)
				)
			)
		)
		(property "MPN" "SDINBDG4-8G"
			(at 0 0 0)
			(layer "F.Fab")
			(hide yes)
			(effects
				(font
					(size 1 1)
					(thickness 0.15)
				)
			)
		)
		(property "Manufacturer" "SanDisk"
			(at 0 0 0)
			(layer "F.Fab")
			(hide yes)
			(effects
				(font
					(size 1 1)
					(thickness 0.15)
				)
			)
		)
		(property "VSD_class" "eMMC"
			(at 0 0 0)
			(layer "F.Fab")
			(hide yes)
			(effects
				(font
					(size 1 1)
					(thickness 0.15)
				)
			)
		)
		(sheetname "/Memory/")
		(sheetfile "memory.kicad_sch")
		(attr smd)
		(fp_line
			(start -5.75 -6.5)
			(end -5.75 -6.375)
			(stroke
				(width 0.15)
				(type solid)
			)
			(layer "F.SilkS")
		)
		(fp_line
			(start -5.75 -6.375)
			(end -5.75 -6.25)
			(stroke
				(width 0.15)
				(type solid)
			)
			(layer "F.SilkS")
		)
		(fp_line
			(start -5.75 -6.25)
			(end -5.75 -6.125)
			(stroke
				(width 0.15)
				(type solid)
			)
			(layer "F.SilkS")
		)
		(fp_line
			(start -5.75 -6.125)
			(end -5.75 -6)
			(stroke
				(width 0.15)
				(type solid)
			)
			(layer "F.SilkS")
		)
		(fp_line
			(start -5.75 -6)
			(end -5.75 -5.875)
			(stroke
				(width 0.15)
				(type solid)
			)
			(layer "F.SilkS")
		)
		(fp_line
			(start -5.75 -5.875)
			(end -5.75 6.498)
			(stroke
				(width 0.15)
				(type solid)
			)
			(layer "F.SilkS")
		)
		(fp_line
			(start -5.75 -5.875)
			(end -5.125 -6.5)
			(stroke
				(width 0.15)
				(type solid)
			)
			(layer "F.SilkS")
		)
		(fp_line
			(start -5.75 6.498)
			(end 5.748 6.498)
			(stroke
				(width 0.15)
				(type solid)
			)
			(layer "F.SilkS")
		)
		(fp_line
			(start -5.625 -6.5)
			(end -5.75 -6.5)
			(stroke
				(width 0.15)
				(type solid)
			)
			(layer "F.SilkS")
		)
		(fp_line
			(start -5.5 -6.5)
			(end -5.625 -6.5)
			(stroke
				(width 0.15)
				(type solid)
			)
			(layer "F.SilkS")
		)
		(fp_line
			(start -5.375 -6.5)
			(end -5.5 -6.5)
			(stroke
				(width 0.15)
				(type solid)
			)
			(layer "F.SilkS")
		)
		(fp_line
			(start -5.25 -6.5)
			(end -5.375 -6.5)
			(stroke
				(width 0.15)
				(type solid)
			)
			(layer "F.SilkS")
		)
		(fp_line
			(start -5.125 -6.5)
			(end -5.25 -6.5)
			(stroke
				(width 0.15)
				(type solid)
			)
			(layer "F.SilkS")
		)
		(fp_line
			(start 5.748 -6.5)
			(end -5.125 -6.5)
			(stroke
				(width 0.15)
				(type solid)
			)
			(layer "F.SilkS")
		)
		(fp_line
			(start 5.748 6.498)
			(end 5.748 -6.5)
			(stroke
				(width 0.15)
				(type solid)
			)
			(layer "F.SilkS")
		)
		(fp_circle
			(center -6 -6.75)
			(end -5.952 -6.75)
			(stroke
				(width 0.15)
				(type solid)
			)
			(fill yes)
			(layer "F.SilkS")
		)
		(fp_rect
			(start -6 -6.7)
			(end 6 6.7)
			(stroke
				(width 0.05)
				(type solid)
			)
			(fill no)
			(layer "F.CrtYd")
		)
		(fp_text user "${REFERENCE}"
			(at -6.05 9.247 0)
			(layer "F.Fab")
			(effects
				(font
					(size 0.7 0.7)
					(thickness 0.15)
				)
				(justify left bottom)
			)
		)
		(fp_text user "Author: Antmicro"
			(at -6.05 11.647 0)
			(layer "F.Fab")
			(effects
				(font
					(size 0.7 0.7)
					(thickness 0.15)
				)
				(justify left bottom)
			)
		)
		(fp_text user "License: Apache-2.0"
			(at -6.05 10.448 0)
			(layer "F.Fab")
			(effects
				(font
					(size 0.7 0.7)
					(thickness 0.15)
				)
				(justify left bottom)
			)
		)
		(pad "A1" smd circle
			(at -3.25 -3.25)
			(size 0.245 0.245)
			(layers "F.Cu" "F.Mask" "F.Paste")
			(net 699 "unconnected-(U2B-NC-PadA1)")
			(pinfunction "NC")
			(pintype "free")
		)
		(pad "A2" smd circle
			(at -2.75 -3.25)
			(size 0.245 0.245)
			(layers "F.Cu" "F.Mask" "F.Paste")
			(net 663 "unconnected-(U2B-NC-PadA2)")
			(pinfunction "NC")
			(pintype "free")
		)
		(pad "A3" smd circle
			(at -2.25 -3.25)
			(size 0.245 0.245)
			(layers "F.Cu" "F.Mask" "F.Paste")
			(net 208 "/FPGA MSSIO/EMMC.DAT0")
			(pinfunction "DAT0")
			(pintype "bidirectional")
		)
		(pad "A4" smd circle
			(at -1.75 -3.25)
			(size 0.245 0.245)
			(layers "F.Cu" "F.Mask" "F.Paste")
			(net 243 "/FPGA MSSIO/EMMC.DAT1")
			(pinfunction "DAT1")
			(pintype "bidirectional")
		)
		(pad "A5" smd circle
			(at -1.25 -3.25)
			(size 0.245 0.245)
			(layers "F.Cu" "F.Mask" "F.Paste")
			(net 248 "/FPGA MSSIO/EMMC.DAT2")
			(pinfunction "DAT2")
			(pintype "bidirectional")
		)
		(pad "A6" smd circle
			(at -0.75 -3.25)
			(size 0.245 0.245)
			(layers "F.Cu" "F.Mask" "F.Paste")
			(net 417 "GND")
			(pinfunction "VSS")
			(pintype "power_in")
		)
		(pad "A7" smd circle
			(at -0.25 -3.25)
			(size 0.245 0.245)
			(layers "F.Cu" "F.Mask" "F.Paste")
			(net 709 "unconnected-(U2A-RFU-PadA7)")
			(pinfunction "RFU")
			(pintype "no_connect")
		)
		(pad "A8" smd circle
			(at 0.247 -3.25)
			(size 0.245 0.245)
			(layers "F.Cu" "F.Mask" "F.Paste")
			(net 758 "unconnected-(U2B-NC-PadA8)")
			(pinfunction "NC")
			(pintype "free")
		)
		(pad "A9" smd circle
			(at 0.747 -3.25)
			(size 0.245 0.245)
			(layers "F.Cu" "F.Mask" "F.Paste")
			(net 716 "unconnected-(U2B-NC-PadA9)")
			(pinfunction "NC")
			(pintype "free")
		)
		(pad "A10" smd circle
			(at 1.249 -3.25)
			(size 0.245 0.245)
			(layers "F.Cu" "F.Mask" "F.Paste")
			(net 710 "unconnected-(U2B-NC-PadA10)")
			(pinfunction "NC")
			(pintype "free")
		)
		(pad "A11" smd circle
			(at 1.749 -3.25)
			(size 0.245 0.245)
			(layers "F.Cu" "F.Mask" "F.Paste")
			(net 742 "unconnected-(U2B-NC-PadA11)")
			(pinfunction "NC")
			(pintype "free")
		)
		(pad "A12" smd circle
			(at 2.249 -3.25)
			(size 0.245 0.245)
			(layers "F.Cu" "F.Mask" "F.Paste")
			(net 690 "unconnected-(U2B-NC-PadA12)")
			(pinfunction "NC")
			(pintype "free")
		)
		(pad "A13" smd circle
			(at 2.749 -3.25)
			(size 0.245 0.245)
			(layers "F.Cu" "F.Mask" "F.Paste")
			(net 670 "unconnected-(U2B-NC-PadA13)")
			(pinfunction "NC")
			(pintype "free")
		)
		(pad "A14" smd circle
			(at 3.249 -3.25)
			(size 0.245 0.245)
			(layers "F.Cu" "F.Mask" "F.Paste")
			(net 734 "unconnected-(U2B-NC-PadA14)")
			(pinfunction "NC")
			(pintype "free")
		)
		(pad "B1" smd circle
			(at -3.25 -2.75)
			(size 0.245 0.245)
			(layers "F.Cu" "F.Mask" "F.Paste")
			(net 746 "unconnected-(U2B-NC-PadB1)")
			(pinfunction "NC")
			(pintype "free")
		)
		(pad "B2" smd circle
			(at -2.75 -2.75)
			(size 0.245 0.245)
			(layers "F.Cu" "F.Mask" "F.Paste")
			(net 207 "/FPGA MSSIO/EMMC.DAT3")
			(pinfunction "DAT3")
			(pintype "bidirectional")
		)
		(pad "B3" smd circle
			(at -2.25 -2.75)
			(size 0.245 0.245)
			(layers "F.Cu" "F.Mask" "F.Paste")
			(net 250 "/FPGA MSSIO/EMMC.DAT4")
			(pinfunction "DAT4")
			(pintype "bidirectional")
		)
		(pad "B4" smd circle
			(at -1.75 -2.75)
			(size 0.245 0.245)
			(layers "F.Cu" "F.Mask" "F.Paste")
			(net 213 "/FPGA MSSIO/EMMC.DAT5")
			(pinfunction "DAT5")
			(pintype "bidirectional")
		)
		(pad "B5" smd circle
			(at -1.25 -2.75)
			(size 0.245 0.245)
			(layers "F.Cu" "F.Mask" "F.Paste")
			(net 249 "/FPGA MSSIO/EMMC.DAT6")
			(pinfunction "DAT6")
			(pintype "bidirectional")
		)
		(pad "B6" smd circle
			(at -0.75 -2.75)
			(size 0.245 0.245)
			(layers "F.Cu" "F.Mask" "F.Paste")
			(net 214 "/FPGA MSSIO/EMMC.DAT7")
			(pinfunction "DAT7")
			(pintype "bidirectional")
		)
		(pad "B7" smd circle
			(at -0.25 -2.75)
			(size 0.245 0.245)
			(layers "F.Cu" "F.Mask" "F.Paste")
			(net 685 "unconnected-(U2B-NC-PadB7)")
			(pinfunction "NC")
			(pintype "free")
		)
		(pad "B8" smd circle
			(at 0.247 -2.75)
			(size 0.245 0.245)
			(layers "F.Cu" "F.Mask" "F.Paste")
			(net 661 "unconnected-(U2B-NC-PadB8)")
			(pinfunction "NC")
			(pintype "free")
		)
		(pad "B9" smd circle
			(at 0.747 -2.75)
			(size 0.245 0.245)
			(layers "F.Cu" "F.Mask" "F.Paste")
			(net 671 "unconnected-(U2B-NC-PadB9)")
			(pinfunction "NC")
			(pintype "free")
		)
		(pad "B10" smd circle
			(at 1.249 -2.75)
			(size 0.245 0.245)
			(layers "F.Cu" "F.Mask" "F.Paste")
			(net 692 "unconnected-(U2B-NC-PadB10)")
			(pinfunction "NC")
			(pintype "free")
		)
		(pad "B11" smd circle
			(at 1.749 -2.75)
			(size 0.245 0.245)
			(layers "F.Cu" "F.Mask" "F.Paste")
			(net 684 "unconnected-(U2B-NC-PadB11)")
			(pinfunction "NC")
			(pintype "free")
		)
		(pad "B12" smd circle
			(at 2.249 -2.75)
			(size 0.245 0.245)
			(layers "F.Cu" "F.Mask" "F.Paste")
			(net 688 "unconnected-(U2B-NC-PadB12)")
			(pinfunction "NC")
			(pintype "free")
		)
		(pad "B13" smd circle
			(at 2.749 -2.75)
			(size 0.245 0.245)
			(layers "F.Cu" "F.Mask" "F.Paste")
			(net 759 "unconnected-(U2B-NC-PadB13)")
			(pinfunction "NC")
			(pintype "free")
		)
		(pad "B14" smd circle
			(at 3.249 -2.75)
			(size 0.245 0.245)
			(layers "F.Cu" "F.Mask" "F.Paste")
			(net 705 "unconnected-(U2B-NC-PadB14)")
			(pinfunction "NC")
			(pintype "free")
		)
		(pad "C1" smd circle
			(at -3.25 -2.25)
			(size 0.245 0.245)
			(layers "F.Cu" "F.Mask" "F.Paste")
			(net 713 "unconnected-(U2B-NC-PadC1)")
			(pinfunction "NC")
			(pintype "free")
		)
		(pad "C2" smd circle
			(at -2.75 -2.25)
			(size 0.245 0.245)
			(layers "F.Cu" "F.Mask" "F.Paste")
			(net 52 "/Memory/eMMC_VDDI")
			(pinfunction "VDDI")
			(pintype "passive")
		)
		(pad "C3" smd circle
			(at -2.25 -2.25)
			(size 0.245 0.245)
			(layers "F.Cu" "F.Mask" "F.Paste")
			(net 582 "unconnected-(U2B-NC-PadC3)")
			(pinfunction "NC")
			(pintype "free")
		)
		(pad "C4" smd circle
			(at -1.75 -2.25)
			(size 0.245 0.245)
			(layers "F.Cu" "F.Mask" "F.Paste")
			(net 417 "GND")
			(pinfunction "VSSQ")
			(pintype "power_in")
		)
		(pad "C5" smd circle
			(at -1.25 -2.25)
			(size 0.245 0.245)
			(layers "F.Cu" "F.Mask" "F.Paste")
			(net 665 "unconnected-(U2B-NC-PadC5)")
			(pinfunction "NC")
			(pintype "free")
		)
		(pad "C6" smd circle
			(at -0.75 -2.25)
			(size 0.245 0.245)
			(layers "F.Cu" "F.Mask" "F.Paste")
			(net 137 "SD_VDD")
			(pinfunction "VCCQ")
			(pintype "power_in")
		)
		(pad "C7" smd circle
			(at -0.25 -2.25)
			(size 0.245 0.245)
			(layers "F.Cu" "F.Mask" "F.Paste")
			(net 770 "unconnected-(U2B-NC-PadC7)")
			(pinfunction "NC")
			(pintype "free")
		)
		(pad "C8" smd circle
			(at 0.247 -2.25)
			(size 0.245 0.245)
			(layers "F.Cu" "F.Mask" "F.Paste")
			(net 659 "unconnected-(U2B-NC-PadC8)")
			(pinfunction "NC")
			(pintype "free")
		)
		(pad "C9" smd circle
			(at 0.747 -2.25)
			(size 0.245 0.245)
			(layers "F.Cu" "F.Mask" "F.Paste")
			(net 771 "unconnected-(U2B-NC-PadC9)")
			(pinfunction "NC")
			(pintype "free")
		)
		(pad "C10" smd circle
			(at 1.249 -2.25)
			(size 0.245 0.245)
			(layers "F.Cu" "F.Mask" "F.Paste")
			(net 730 "unconnected-(U2B-NC-PadC10)")
			(pinfunction "NC")
			(pintype "free")
		)
		(pad "C11" smd circle
			(at 1.749 -2.25)
			(size 0.245 0.245)
			(layers "F.Cu" "F.Mask" "F.Paste")
			(net 729 "unconnected-(U2B-NC-PadC11)")
			(pinfunction "NC")
			(pintype "free")
		)
		(pad "C12" smd circle
			(at 2.249 -2.25)
			(size 0.245 0.245)
			(layers "F.Cu" "F.Mask" "F.Paste")
			(net 474 "unconnected-(U2B-NC-PadC12)")
			(pinfunction "NC")
			(pintype "free")
		)
		(pad "C13" smd circle
			(at 2.749 -2.25)
			(size 0.245 0.245)
			(layers "F.Cu" "F.Mask" "F.Paste")
			(net 738 "unconnected-(U2B-NC-PadC13)")
			(pinfunction "NC")
			(pintype "free")
		)
		(pad "C14" smd circle
			(at 3.249 -2.25)
			(size 0.245 0.245)
			(layers "F.Cu" "F.Mask" "F.Paste")
			(net 762 "unconnected-(U2B-NC-PadC14)")
			(pinfunction "NC")
			(pintype "free")
		)
		(pad "D1" smd circle
			(at -3.25 -1.75)
			(size 0.245 0.245)
			(layers "F.Cu" "F.Mask" "F.Paste")
			(net 701 "unconnected-(U2B-NC-PadD1)")
			(pinfunction "NC")
			(pintype "free")
		)
		(pad "D2" smd circle
			(at -2.75 -1.75)
			(size 0.245 0.245)
			(layers "F.Cu" "F.Mask" "F.Paste")
			(net 664 "unconnected-(U2B-NC-PadD2)")
			(pinfunction "NC")
			(pintype "free")
		)
		(pad "D3" smd circle
			(at -2.25 -1.75)
			(size 0.245 0.245)
			(layers "F.Cu" "F.Mask" "F.Paste")
			(net 678 "unconnected-(U2B-NC-PadD3)")
			(pinfunction "NC")
			(pintype "free")
		)
		(pad "D4" smd circle
			(at -1.75 -1.75)
			(size 0.245 0.245)
			(layers "F.Cu" "F.Mask" "F.Paste")
			(net 723 "unconnected-(U2B-NC-PadD4)")
			(pinfunction "NC")
			(pintype "free")
		)
		(pad "D12" smd circle
			(at 2.249 -1.75)
			(size 0.245 0.245)
			(layers "F.Cu" "F.Mask" "F.Paste")
			(net 689 "unconnected-(U2B-NC-PadD12)")
			(pinfunction "NC")
			(pintype "free")
		)
		(pad "D13" smd circle
			(at 2.749 -1.75)
			(size 0.245 0.245)
			(layers "F.Cu" "F.Mask" "F.Paste")
			(net 737 "unconnected-(U2B-NC-PadD13)")
			(pinfunction "NC")
			(pintype "free")
		)
		(pad "D14" smd circle
			(at 3.249 -1.75)
			(size 0.245 0.245)
			(layers "F.Cu" "F.Mask" "F.Paste")
			(net 766 "unconnected-(U2B-NC-PadD14)")
			(pinfunction "NC")
			(pintype "free")
		)
		(pad "E1" smd circle
			(at -3.25 -1.25)
			(size 0.245 0.245)
			(layers "F.Cu" "F.Mask" "F.Paste")
			(net 741 "unconnected-(U2B-NC-PadE1)")
			(pinfunction "NC")
			(pintype "free")
		)
		(pad "E2" smd circle
			(at -2.75 -1.25)
			(size 0.245 0.245)
			(layers "F.Cu" "F.Mask" "F.Paste")
			(net 700 "unconnected-(U2B-NC-PadE2)")
			(pinfunction "NC")
			(pintype "free")
		)
		(pad "E3" smd circle
			(at -2.25 -1.25)
			(size 0.245 0.245)
			(layers "F.Cu" "F.Mask" "F.Paste")
			(net 669 "unconnected-(U2B-NC-PadE3)")
			(pinfunction "NC")
			(pintype "free")
		)
		(pad "E5" smd circle
			(at -1.25 -1.25)
			(size 0.245 0.245)
			(layers "F.Cu" "F.Mask" "F.Paste")
			(net 743 "unconnected-(U2A-RFU-PadE5)")
			(pinfunction "RFU")
			(pintype "no_connect")
		)
		(pad "E6" smd circle
			(at -0.75 -1.25)
			(size 0.245 0.245)
			(layers "F.Cu" "F.Mask" "F.Paste")
			(net 50 "+3V3")
			(pinfunction "VCC")
			(pintype "power_in")
		)
		(pad "E7" smd circle
			(at -0.25 -1.25)
			(size 0.245 0.245)
			(layers "F.Cu" "F.Mask" "F.Paste")
			(net 417 "GND")
			(pinfunction "VSS")
			(pintype "passive")
		)
		(pad "E8" smd circle
			(at 0.247 -1.25)
			(size 0.245 0.245)
			(layers "F.Cu" "F.Mask" "F.Paste")
			(net 765 "unconnected-(U2A-RFU-PadE8)")
			(pinfunction "RFU")
			(pintype "no_connect")
		)
		(pad "E9" smd circle
			(at 0.747 -1.25)
			(size 0.245 0.245)
			(layers "F.Cu" "F.Mask" "F.Paste")
			(net 475 "unconnected-(U2A-VSF-PadE9)")
			(pinfunction "VSF")
			(pintype "no_connect")
		)
		(pad "E10" smd circle
			(at 1.249 -1.25)
			(size 0.245 0.245)
			(layers "F.Cu" "F.Mask" "F.Paste")
			(net 673 "unconnected-(U2A-VSF-PadE10)")
			(pinfunction "VSF")
			(pintype "no_connect")
		)
		(pad "E12" smd circle
			(at 2.249 -1.25)
			(size 0.245 0.245)
			(layers "F.Cu" "F.Mask" "F.Paste")
			(net 745 "unconnected-(U2B-NC-PadE12)")
			(pinfunction "NC")
			(pintype "free")
		)
		(pad "E13" smd circle
			(at 2.749 -1.25)
			(size 0.245 0.245)
			(layers "F.Cu" "F.Mask" "F.Paste")
			(net 674 "unconnected-(U2B-NC-PadE13)")
			(pinfunction "NC")
			(pintype "free")
		)
		(pad "E14" smd circle
			(at 3.249 -1.25)
			(size 0.245 0.245)
			(layers "F.Cu" "F.Mask" "F.Paste")
			(net 733 "unconnected-(U2B-NC-PadE14)")
			(pinfunction "NC")
			(pintype "free")
		)
		(pad "F1" smd circle
			(at -3.25 -0.75)
			(size 0.245 0.245)
			(layers "F.Cu" "F.Mask" "F.Paste")
			(net 756 "unconnected-(U2B-NC-PadF1)")
			(pinfunction "NC")
			(pintype "free")
		)
		(pad "F2" smd circle
			(at -2.75 -0.75)
			(size 0.245 0.245)
			(layers "F.Cu" "F.Mask" "F.Paste")
			(net 698 "unconnected-(U2B-NC-PadF2)")
			(pinfunction "NC")
			(pintype "free")
		)
		(pad "F3" smd circle
			(at -2.25 -0.75)
			(size 0.245 0.245)
			(layers "F.Cu" "F.Mask" "F.Paste")
			(net 675 "unconnected-(U2B-NC-PadF3)")
			(pinfunction "NC")
			(pintype "free")
		)
		(pad "F5" smd circle
			(at -1.25 -0.75)
			(size 0.245 0.245)
			(layers "F.Cu" "F.Mask" "F.Paste")
			(net 50 "+3V3")
			(pinfunction "VCC")
			(pintype "passive")
		)
		(pad "F10" smd circle
			(at 1.249 -0.75)
			(size 0.245 0.245)
			(layers "F.Cu" "F.Mask" "F.Paste")
			(net 753 "unconnected-(U2A-VSF-PadF10)")
			(pinfunction "VSF")
			(pintype "no_connect")
		)
		(pad "F12" smd circle
			(at 2.249 -0.75)
			(size 0.245 0.245)
			(layers "F.Cu" "F.Mask" "F.Paste")
			(net 694 "unconnected-(U2B-NC-PadF12)")
			(pinfunction "NC")
			(pintype "free")
		)
		(pad "F13" smd circle
			(at 2.749 -0.75)
			(size 0.245 0.245)
			(layers "F.Cu" "F.Mask" "F.Paste")
			(net 763 "unconnected-(U2B-NC-PadF13)")
			(pinfunction "NC")
			(pintype "free")
		)
		(pad "F14" smd circle
			(at 3.249 -0.75)
			(size 0.245 0.245)
			(layers "F.Cu" "F.Mask" "F.Paste")
			(net 722 "unconnected-(U2B-NC-PadF14)")
			(pinfunction "NC")
			(pintype "free")
		)
		(pad "G1" smd circle
			(at -3.25 -0.25)
			(size 0.245 0.245)
			(layers "F.Cu" "F.Mask" "F.Paste")
			(net 666 "unconnected-(U2B-NC-PadG1)")
			(pinfunction "NC")
			(pintype "free")
		)
		(pad "G2" smd circle
			(at -2.75 -0.25)
			(size 0.245 0.245)
			(layers "F.Cu" "F.Mask" "F.Paste")
			(net 660 "unconnected-(U2B-NC-PadG2)")
			(pinfunction "NC")
			(pintype "free")
		)
		(pad "G3" smd circle
			(at -2.25 -0.25)
			(size 0.245 0.245)
			(layers "F.Cu" "F.Mask" "F.Paste")
			(net 695 "unconnected-(U2A-RFU-PadG3)")
			(pinfunction "RFU")
			(pintype "no_connect")
		)
		(pad "G5" smd circle
			(at -1.25 -0.25)
			(size 0.245 0.245)
			(layers "F.Cu" "F.Mask" "F.Paste")
			(net 417 "GND")
			(pinfunction "VSS")
			(pintype "passive")
		)
		(pad "G10" smd circle
			(at 1.249 -0.25)
			(size 0.245 0.245)
			(layers "F.Cu" "F.Mask" "F.Paste")
			(net 736 "unconnected-(U2A-RFU-PadG10)")
			(pinfunction "RFU")
			(pintype "no_connect")
		)
		(pad "G12" smd circle
			(at 2.249 -0.25)
			(size 0.245 0.245)
			(layers "F.Cu" "F.Mask" "F.Paste")
			(net 668 "unconnected-(U2B-NC-PadG12)")
			(pinfunction "NC")
			(pintype "free")
		)
		(pad "G13" smd circle
			(at 2.749 -0.25)
			(size 0.245 0.245)
			(layers "F.Cu" "F.Mask" "F.Paste")
			(net 714 "unconnected-(U2B-NC-PadG13)")
			(pinfunction "NC")
			(pintype "free")
		)
		(pad "G14" smd circle
			(at 3.249 -0.25)
			(size 0.245 0.245)
			(layers "F.Cu" "F.Mask" "F.Paste")
			(net 711 "unconnected-(U2B-NC-PadG14)")
			(pinfunction "NC")
			(pintype "free")
		)
		(pad "H1" smd circle
			(at -3.25 0.247)
			(size 0.245 0.245)
			(layers "F.Cu" "F.Mask" "F.Paste")
			(net 715 "unconnected-(U2B-NC-PadH1)")
			(pinfunction "NC")
			(pintype "free")
		)
		(pad "H2" smd circle
			(at -2.75 0.247)
			(size 0.245 0.245)
			(layers "F.Cu" "F.Mask" "F.Paste")
			(net 676 "unconnected-(U2B-NC-PadH2)")
			(pinfunction "NC")
			(pintype "free")
		)
		(pad "H3" smd circle
			(at -2.25 0.247)
			(size 0.245 0.245)
			(layers "F.Cu" "F.Mask" "F.Paste")
			(net 731 "unconnected-(U2B-NC-PadH3)")
			(pinfunction "NC")
			(pintype "free")
		)
		(pad "H5" smd circle
			(at -1.25 0.247)
			(size 0.245 0.245)
			(layers "F.Cu" "F.Mask" "F.Paste")
			(net 390 "/FPGA MSSIO/EMMC.STRB")
			(pinfunction "RCLK")
			(pintype "output")
		)
		(pad "H10" smd circle
			(at 1.249 0.247)
			(size 0.245 0.245)
			(layers "F.Cu" "F.Mask" "F.Paste")
			(net 417 "GND")
			(pinfunction "VSS")
			(pintype "passive")
		)
		(pad "H12" smd circle
			(at 2.249 0.247)
			(size 0.245 0.245)
			(layers "F.Cu" "F.Mask" "F.Paste")
			(net 719 "unconnected-(U2B-NC-PadH12)")
			(pinfunction "NC")
			(pintype "free")
		)
		(pad "H13" smd circle
			(at 2.749 0.247)
			(size 0.245 0.245)
			(layers "F.Cu" "F.Mask" "F.Paste")
			(net 680 "unconnected-(U2B-NC-PadH13)")
			(pinfunction "NC")
			(pintype "free")
		)
		(pad "H14" smd circle
			(at 3.249 0.247)
			(size 0.245 0.245)
			(layers "F.Cu" "F.Mask" "F.Paste")
			(net 768 "unconnected-(U2B-NC-PadH14)")
			(pinfunction "NC")
			(pintype "free")
		)
		(pad "J1" smd circle
			(at -3.25 0.747)
			(size 0.245 0.245)
			(layers "F.Cu" "F.Mask" "F.Paste")
			(net 757 "unconnected-(U2B-NC-PadJ1)")
			(pinfunction "NC")
			(pintype "free")
		)
		(pad "J2" smd circle
			(at -2.75 0.747)
			(size 0.245 0.245)
			(layers "F.Cu" "F.Mask" "F.Paste")
			(net 708 "unconnected-(U2B-NC-PadJ2)")
			(pinfunction "NC")
			(pintype "free")
		)
		(pad "J3" smd circle
			(at -2.25 0.747)
			(size 0.245 0.245)
			(layers "F.Cu" "F.Mask" "F.Paste")
			(net 749 "unconnected-(U2B-NC-PadJ3)")
			(pinfunction "NC")
			(pintype "free")
		)
		(pad "J5" smd circle
			(at -1.25 0.747)
			(size 0.245 0.245)
			(layers "F.Cu" "F.Mask" "F.Paste")
			(net 417 "GND")
			(pinfunction "VSS")
			(pintype "passive")
		)
		(pad "J10" smd circle
			(at 1.249 0.747)
			(size 0.245 0.245)
			(layers "F.Cu" "F.Mask" "F.Paste")
			(net 50 "+3V3")
			(pinfunction "VCC")
			(pintype "passive")
		)
		(pad "J12" smd circle
			(at 2.249 0.747)
			(size 0.245 0.245)
			(layers "F.Cu" "F.Mask" "F.Paste")
			(net 764 "unconnected-(U2B-NC-PadJ12)")
			(pinfunction "NC")
			(pintype "free")
		)
		(pad "J13" smd circle
			(at 2.749 0.747)
			(size 0.245 0.245)
			(layers "F.Cu" "F.Mask" "F.Paste")
			(net 750 "unconnected-(U2B-NC-PadJ13)")
			(pinfunction "NC")
			(pintype "free")
		)
		(pad "J14" smd circle
			(at 3.249 0.747)
			(size 0.245 0.245)
			(layers "F.Cu" "F.Mask" "F.Paste")
			(net 718 "unconnected-(U2B-NC-PadJ14)")
			(pinfunction "NC")
			(pintype "free")
		)
		(pad "K1" smd circle
			(at -3.25 1.249)
			(size 0.245 0.245)
			(layers "F.Cu" "F.Mask" "F.Paste")
			(net 677 "unconnected-(U2B-NC-PadK1)")
			(pinfunction "NC")
			(pintype "free")
		)
		(pad "K2" smd circle
			(at -2.75 1.249)
			(size 0.245 0.245)
			(layers "F.Cu" "F.Mask" "F.Paste")
			(net 662 "unconnected-(U2B-NC-PadK2)")
			(pinfunction "NC")
			(pintype "free")
		)
		(pad "K3" smd circle
			(at -2.25 1.249)
			(size 0.245 0.245)
			(layers "F.Cu" "F.Mask" "F.Paste")
			(net 686 "unconnected-(U2B-NC-PadK3)")
			(pinfunction "NC")
			(pintype "free")
		)
		(pad "K5" smd circle
			(at -1.25 1.249)
			(size 0.245 0.245)
			(layers "F.Cu" "F.Mask" "F.Paste")
			(net 387 "/FPGA MSSIO/EMMC.RST_n")
			(pinfunction "RST_N")
			(pintype "input")
		)
		(pad "K6" smd circle
			(at -0.75 1.249)
			(size 0.245 0.245)
			(layers "F.Cu" "F.Mask" "F.Paste")
			(net 748 "unconnected-(U2A-RFU-PadK6)")
			(pinfunction "RFU")
			(pintype "no_connect")
		)
		(pad "K7" smd circle
			(at -0.25 1.249)
			(size 0.245 0.245)
			(layers "F.Cu" "F.Mask" "F.Paste")
			(net 657 "unconnected-(U2A-RFU-PadK7)")
			(pinfunction "RFU")
			(pintype "no_connect")
		)
		(pad "K8" smd circle
			(at 0.247 1.249)
			(size 0.245 0.245)
			(layers "F.Cu" "F.Mask" "F.Paste")
			(net 417 "GND")
			(pinfunction "VSS")
			(pintype "passive")
		)
		(pad "K9" smd circle
			(at 0.747 1.249)
			(size 0.245 0.245)
			(layers "F.Cu" "F.Mask" "F.Paste")
			(net 50 "+3V3")
			(pinfunction "VCC")
			(pintype "passive")
		)
		(pad "K10" smd circle
			(at 1.249 1.249)
			(size 0.245 0.245)
			(layers "F.Cu" "F.Mask" "F.Paste")
			(net 712 "unconnected-(U2A-RFU-PadK10)")
			(pinfunction "RFU")
			(pintype "no_connect")
		)
		(pad "K12" smd circle
			(at 2.249 1.249)
			(size 0.245 0.245)
			(layers "F.Cu" "F.Mask" "F.Paste")
			(net 767 "unconnected-(U2B-NC-PadK12)")
			(pinfunction "NC")
			(pintype "free")
		)
		(pad "K13" smd circle
			(at 2.749 1.249)
			(size 0.245 0.245)
			(layers "F.Cu" "F.Mask" "F.Paste")
			(net 754 "unconnected-(U2B-NC-PadK13)")
			(pinfunction "NC")
			(pintype "free")
		)
		(pad "K14" smd circle
			(at 3.249 1.249)
			(size 0.245 0.245)
			(layers "F.Cu" "F.Mask" "F.Paste")
			(net 724 "unconnected-(U2B-NC-PadK14)")
			(pinfunction "NC")
			(pintype "free")
		)
		(pad "L1" smd circle
			(at -3.25 1.749)
			(size 0.245 0.245)
			(layers "F.Cu" "F.Mask" "F.Paste")
			(net 727 "unconnected-(U2B-NC-PadL1)")
			(pinfunction "NC")
			(pintype "free")
		)
		(pad "L2" smd circle
			(at -2.75 1.749)
			(size 0.245 0.245)
			(layers "F.Cu" "F.Mask" "F.Paste")
			(net 702 "unconnected-(U2B-NC-PadL2)")
			(pinfunction "NC")
			(pintype "free")
		)
		(pad "L3" smd circle
			(at -2.25 1.749)
			(size 0.245 0.245)
			(layers "F.Cu" "F.Mask" "F.Paste")
			(net 696 "unconnected-(U2B-NC-PadL3)")
			(pinfunction "NC")
			(pintype "free")
		)
		(pad "L12" smd circle
			(at 2.249 1.749)
			(size 0.245 0.245)
			(layers "F.Cu" "F.Mask" "F.Paste")
			(net 751 "unconnected-(U2B-NC-PadL12)")
			(pinfunction "NC")
			(pintype "free")
		)
		(pad "L13" smd circle
			(at 2.749 1.749)
			(size 0.245 0.245)
			(layers "F.Cu" "F.Mask" "F.Paste")
			(net 726 "unconnected-(U2B-NC-PadL13)")
			(pinfunction "NC")
			(pintype "free")
		)
		(pad "L14" smd circle
			(at 3.249 1.749)
			(size 0.245 0.245)
			(layers "F.Cu" "F.Mask" "F.Paste")
			(net 683 "unconnected-(U2B-NC-PadL14)")
			(pinfunction "NC")
			(pintype "free")
		)
		(pad "M1" smd circle
			(at -3.25 2.249)
			(size 0.245 0.245)
			(layers "F.Cu" "F.Mask" "F.Paste")
			(net 703 "unconnected-(U2B-NC-PadM1)")
			(pinfunction "NC")
			(pintype "free")
		)
		(pad "M2" smd circle
			(at -2.75 2.249)
			(size 0.245 0.245)
			(layers "F.Cu" "F.Mask" "F.Paste")
			(net 667 "unconnected-(U2B-NC-PadM2)")
			(pinfunction "NC")
			(pintype "free")
		)
		(pad "M3" smd circle
			(at -2.25 2.249)
			(size 0.245 0.245)
			(layers "F.Cu" "F.Mask" "F.Paste")
			(net 720 "unconnected-(U2B-NC-PadM3)")
			(pinfunction "NC")
			(pintype "free")
		)
		(pad "M4" smd circle
			(at -1.75 2.249)
			(size 0.245 0.245)
			(layers "F.Cu" "F.Mask" "F.Paste")
			(net 137 "SD_VDD")
			(pinfunction "VCCQ")
			(pintype "passive")
		)
		(pad "M5" smd circle
			(at -1.25 2.249)
			(size 0.245 0.245)
			(layers "F.Cu" "F.Mask" "F.Paste")
			(net 391 "/FPGA MSSIO/EMMC.CMD")
			(pinfunction "CMD")
			(pintype "bidirectional")
		)
		(pad "M6" smd circle
			(at -0.75 2.249)
			(size 0.245 0.245)
			(layers "F.Cu" "F.Mask" "F.Paste")
			(net 264 "/FPGA MSSIO/EMMC.CLK")
			(pinfunction "CLK")
			(pintype "input")
		)
		(pad "M7" smd circle
			(at -0.25 2.249)
			(size 0.245 0.245)
			(layers "F.Cu" "F.Mask" "F.Paste")
			(net 476 "unconnected-(U2B-NC-PadM7)")
			(pinfunction "NC")
			(pintype "free")
		)
		(pad "M8" smd circle
			(at 0.247 2.249)
			(size 0.245 0.245)
			(layers "F.Cu" "F.Mask" "F.Paste")
			(net 707 "unconnected-(U2B-NC-PadM8)")
			(pinfunction "NC")
			(pintype "free")
		)
		(pad "M9" smd circle
			(at 0.747 2.249)
			(size 0.245 0.245)
			(layers "F.Cu" "F.Mask" "F.Paste")
			(net 682 "unconnected-(U2B-NC-PadM9)")
			(pinfunction "NC")
			(pintype "free")
		)
		(pad "M10" smd circle
			(at 1.249 2.249)
			(size 0.245 0.245)
			(layers "F.Cu" "F.Mask" "F.Paste")
			(net 755 "unconnected-(U2B-NC-PadM10)")
			(pinfunction "NC")
			(pintype "free")
		)
		(pad "M11" smd circle
			(at 1.749 2.249)
			(size 0.245 0.245)
			(layers "F.Cu" "F.Mask" "F.Paste")
			(net 681 "unconnected-(U2B-NC-PadM11)")
			(pinfunction "NC")
			(pintype "free")
		)
		(pad "M12" smd circle
			(at 2.249 2.249)
			(size 0.245 0.245)
			(layers "F.Cu" "F.Mask" "F.Paste")
			(net 760 "unconnected-(U2B-NC-PadM12)")
			(pinfunction "NC")
			(pintype "free")
		)
		(pad "M13" smd circle
			(at 2.749 2.249)
			(size 0.245 0.245)
			(layers "F.Cu" "F.Mask" "F.Paste")
			(net 693 "unconnected-(U2B-NC-PadM13)")
			(pinfunction "NC")
			(pintype "free")
		)
		(pad "M14" smd circle
			(at 3.249 2.249)
			(size 0.245 0.245)
			(layers "F.Cu" "F.Mask" "F.Paste")
			(net 761 "unconnected-(U2B-NC-PadM14)")
			(pinfunction "NC")
			(pintype "free")
		)
		(pad "N1" smd circle
			(at -3.25 2.749)
			(size 0.245 0.245)
			(layers "F.Cu" "F.Mask" "F.Paste")
			(net 672 "unconnected-(U2B-NC-PadN1)")
			(pinfunction "NC")
			(pintype "free")
		)
		(pad "N2" smd circle
			(at -2.75 2.749)
			(size 0.245 0.245)
			(layers "F.Cu" "F.Mask" "F.Paste")
			(net 417 "GND")
			(pinfunction "VSSQ")
			(pintype "passive")
		)
		(pad "N3" smd circle
			(at -2.25 2.749)
			(size 0.245 0.245)
			(layers "F.Cu" "F.Mask" "F.Paste")
			(net 721 "unconnected-(U2B-NC-PadN3)")
			(pinfunction "NC")
			(pintype "free")
		)
		(pad "N4" smd circle
			(at -1.75 2.749)
			(size 0.245 0.245)
			(layers "F.Cu" "F.Mask" "F.Paste")
			(net 137 "SD_VDD")
			(pinfunction "VCCQ")
			(pintype "passive")
		)
		(pad "N5" smd circle
			(at -1.25 2.749)
			(size 0.245 0.245)
			(layers "F.Cu" "F.Mask" "F.Paste")
			(net 417 "GND")
			(pinfunction "VSSQ")
			(pintype "passive")
		)
		(pad "N6" smd circle
			(at -0.75 2.749)
			(size 0.245 0.245)
			(layers "F.Cu" "F.Mask" "F.Paste")
			(net 691 "unconnected-(U2B-NC-PadN6)")
			(pinfunction "NC")
			(pintype "free")
		)
		(pad "N7" smd circle
			(at -0.25 2.749)
			(size 0.245 0.245)
			(layers "F.Cu" "F.Mask" "F.Paste")
			(net 687 "unconnected-(U2B-NC-PadN7)")
			(pinfunction "NC")
			(pintype "free")
		)
		(pad "N8" smd circle
			(at 0.247 2.749)
			(size 0.245 0.245)
			(layers "F.Cu" "F.Mask" "F.Paste")
			(net 739 "unconnected-(U2B-NC-PadN8)")
			(pinfunction "NC")
			(pintype "free")
		)
		(pad "N9" smd circle
			(at 0.747 2.749)
			(size 0.245 0.245)
			(layers "F.Cu" "F.Mask" "F.Paste")
			(net 769 "unconnected-(U2B-NC-PadN9)")
			(pinfunction "NC")
			(pintype "free")
		)
		(pad "N10" smd circle
			(at 1.249 2.749)
			(size 0.245 0.245)
			(layers "F.Cu" "F.Mask" "F.Paste")
			(net 735 "unconnected-(U2B-NC-PadN10)")
			(pinfunction "NC")
			(pintype "free")
		)
		(pad "N11" smd circle
			(at 1.749 2.749)
			(size 0.245 0.245)
			(layers "F.Cu" "F.Mask" "F.Paste")
			(net 679 "unconnected-(U2B-NC-PadN11)")
			(pinfunction "NC")
			(pintype "free")
		)
		(pad "N12" smd circle
			(at 2.249 2.749)
			(size 0.245 0.245)
			(layers "F.Cu" "F.Mask" "F.Paste")
			(net 740 "unconnected-(U2B-NC-PadN12)")
			(pinfunction "NC")
			(pintype "free")
		)
		(pad "N13" smd circle
			(at 2.749 2.749)
			(size 0.245 0.245)
			(layers "F.Cu" "F.Mask" "F.Paste")
			(net 717 "unconnected-(U2B-NC-PadN13)")
			(pinfunction "NC")
			(pintype "free")
		)
		(pad "N14" smd circle
			(at 3.249 2.749)
			(size 0.245 0.245)
			(layers "F.Cu" "F.Mask" "F.Paste")
			(net 732 "unconnected-(U2B-NC-PadN14)")
			(pinfunction "NC")
			(pintype "free")
		)
		(pad "P1" smd circle
			(at -3.25 3.249)
			(size 0.245 0.245)
			(layers "F.Cu" "F.Mask" "F.Paste")
			(net 697 "unconnected-(U2B-NC-PadP1)")
			(pinfunction "NC")
			(pintype "free")
		)
		(pad "P2" smd circle
			(at -2.75 3.249)
			(size 0.245 0.245)
			(layers "F.Cu" "F.Mask" "F.Paste")
			(net 473 "unconnected-(U2B-NC-PadP2)")
			(pinfunction "NC")
			(pintype "free")
		)
		(pad "P3" smd circle
			(at -2.25 3.249)
			(size 0.245 0.245)
			(layers "F.Cu" "F.Mask" "F.Paste")
			(net 137 "SD_VDD")
			(pinfunction "VCCQ")
			(pintype "passive")
		)
		(pad "P4" smd circle
			(at -1.75 3.249)
			(size 0.245 0.245)
			(layers "F.Cu" "F.Mask" "F.Paste")
			(net 417 "GND")
			(pinfunction "VSSQ")
			(pintype "passive")
		)
		(pad "P5" smd circle
			(at -1.25 3.249)
			(size 0.245 0.245)
			(layers "F.Cu" "F.Mask" "F.Paste")
			(net 137 "SD_VDD")
			(pinfunction "VCCQ")
			(pintype "passive")
		)
		(pad "P6" smd circle
			(at -0.75 3.249)
			(size 0.245 0.245)
			(layers "F.Cu" "F.Mask" "F.Paste")
			(net 417 "GND")
			(pinfunction "VSSQ")
			(pintype "passive")
		)
		(pad "P7" smd circle
			(at -0.25 3.249)
			(size 0.245 0.245)
			(layers "F.Cu" "F.Mask" "F.Paste")
			(net 725 "unconnected-(U2A-RFU-PadP7)")
			(pinfunction "RFU")
			(pintype "no_connect")
		)
		(pad "P8" smd circle
			(at 0.247 3.249)
			(size 0.245 0.245)
			(layers "F.Cu" "F.Mask" "F.Paste")
			(net 706 "unconnected-(U2B-NC-PadP8)")
			(pinfunction "NC")
			(pintype "free")
		)
		(pad "P9" smd circle
			(at 0.747 3.249)
			(size 0.245 0.245)
			(layers "F.Cu" "F.Mask" "F.Paste")
			(net 704 "unconnected-(U2B-NC-PadP9)")
			(pinfunction "NC")
			(pintype "free")
		)
		(pad "P10" smd circle
			(at 1.249 3.249)
			(size 0.245 0.245)
			(layers "F.Cu" "F.Mask" "F.Paste")
			(net 728 "unconnected-(U2A-RFU-PadP10)")
			(pinfunction "RFU")
			(pintype "no_connect")
		)
		(pad "P11" smd circle
			(at 1.749 3.249)
			(size 0.245 0.245)
			(layers "F.Cu" "F.Mask" "F.Paste")
			(net 744 "unconnected-(U2B-NC-PadP11)")
			(pinfunction "NC")
			(pintype "free")
		)
		(pad "P12" smd circle
			(at 2.249 3.249)
			(size 0.245 0.245)
			(layers "F.Cu" "F.Mask" "F.Paste")
			(net 658 "unconnected-(U2B-NC-PadP12)")
			(pinfunction "NC")
			(pintype "free")
		)
		(pad "P13" smd circle
			(at 2.749 3.249)
			(size 0.245 0.245)
			(layers "F.Cu" "F.Mask" "F.Paste")
			(net 747 "unconnected-(U2B-NC-PadP13)")
			(pinfunction "NC")
			(pintype "free")
		)
		(pad "P14" smd circle
			(at 3.249 3.249)
			(size 0.245 0.245)
			(layers "F.Cu" "F.Mask" "F.Paste")
			(net 752 "unconnected-(U2B-NC-PadP14)")
			(pinfunction "NC")
			(pintype "free")
		)
	)
	(footprint "antmicro-footprints:TP_SMD_0.75mm"
		(layer "F.Cu")
		(at 198.31 146.86)
		(property "Reference" "TP18"
			(at 0 -0.6 0)
			(layer "F.SilkS")
			(hide yes)
			(effects
				(font
					(size 0.7 0.7)
					(thickness 0.15)
				)
				(justify left bottom)
			)
		)
		(property "Value" "TP_0.75mm_SMD"
			(at 0 1.2 0)
			(layer "F.Fab")
			(hide yes)
			(effects
				(font
					(size 0.7 0.7)
					(thickness 0.15)
				)
				(justify left bottom)
			)
		)
		(property "Description" "SMT test point"
			(at 0 0 0)
			(layer "F.Fab")
			(hide yes)
			(effects
				(font
					(size 1.27 1.27)
					(thickness 0.15)
				)
			)
		)
		(property "Author" "Antmicro"
			(at 0 0 0)
			(layer "F.Fab")
			(hide yes)
			(effects
				(font
					(size 1 1)
					(thickness 0.15)
				)
			)
		)
		(property "License" "Apache-2.0"
			(at 0 0 0)
			(layer "F.Fab")
			(hide yes)
			(effects
				(font
					(size 1 1)
					(thickness 0.15)
				)
			)
		)
		(property "MPN" ""
			(at 0 0 0)
			(layer "F.Fab")
			(hide yes)
			(effects
				(font
					(size 1 1)
					(thickness 0.15)
				)
			)
		)
		(property "Manufacturer" ""
			(at 0 0 0)
			(layer "F.Fab")
			(hide yes)
			(effects
				(font
					(size 1 1)
					(thickness 0.15)
				)
			)
		)
		(property "Public" "False"
			(at 0 0 0)
			(layer "F.Fab")
			(hide yes)
			(effects
				(font
					(size 1 1)
					(thickness 0.15)
				)
			)
		)
		(sheetname "/HDMI/")
		(sheetfile "hdmi.kicad_sch")
		(attr exclude_from_pos_files exclude_from_bom)
		(fp_circle
			(center 0 0)
			(end 0.475 0)
			(stroke
				(width 0.05)
				(type default)
			)
			(fill no)
			(layer "F.CrtYd")
		)
		(fp_text user "${REFERENCE}"
			(at -0.4 2.7 0)
			(layer "F.Fab")
			(effects
				(font
					(size 0.7 0.7)
					(thickness 0.15)
				)
				(justify left bottom)
			)
		)
		(fp_text user "License: Apache-2.0"
			(at -0.4 5.101 0)
			(layer "F.Fab")
			(effects
				(font
					(size 0.7 0.7)
					(thickness 0.15)
				)
				(justify left bottom)
			)
		)
		(fp_text user "Author: Antmicro"
			(at -0.4 3.901 0)
			(layer "F.Fab")
			(effects
				(font
					(size 0.7 0.7)
					(thickness 0.15)
				)
				(justify left bottom)
			)
		)
		(pad "1" smd circle
			(at 0 0)
			(size 0.75 0.75)
			(layers "F.Cu" "F.Mask")
			(net 556 "Net-(U15-OEB)")
			(pinfunction "1")
			(pintype "passive")
		)
	)
	(footprint "antmicro-footprints:C_0402_1005Metric"
		(layer "F.Cu")
		(at 181.734404 153.229531)
		(descr "Capacitor SMD 0402")
		(tags "capacitor SMD 0402")
		(property "Reference" "C96"
			(at -1.814404 2.490469 45)
			(layer "F.SilkS")
			(effects
				(font
					(size 0.7 0.7)
					(thickness 0.15)
				)
				(justify left bottom)
			)
		)
		(property "Value" "C_22n_0402"
			(at -1.022927 2.155213 0)
			(layer "F.Fab")
			(hide yes)
			(effects
				(font
					(size 0.7 0.7)
					(thickness 0.15)
				)
				(justify left bottom)
			)
		)
		(property "Datasheet" "https://www.murata.com/products/productdetail?partno=GCM155R71H223MA55%23"
			(at 0 0 0)
			(layer "F.Fab")
			(hide yes)
			(effects
				(font
					(size 1.27 1.27)
					(thickness 0.15)
				)
			)
		)
		(property "Description" "SMD Multilayer Ceramic Capacitors, 0.022 µF, 50 V, 20%, 0402 [1005 Metric], X7R"
			(at 0 0 0)
			(layer "F.Fab")
			(hide yes)
			(effects
				(font
					(size 1.27 1.27)
					(thickness 0.15)
				)
			)
		)
		(property "Author" "Antmicro"
			(at 0 0 0)
			(layer "F.Fab")
			(hide yes)
			(effects
				(font
					(size 1 1)
					(thickness 0.15)
				)
			)
		)
		(property "Dielectric" ""
			(at 0 0 0)
			(layer "F.Fab")
			(hide yes)
			(effects
				(font
					(size 1 1)
					(thickness 0.15)
				)
			)
		)
		(property "License" "Apache-2.0"
			(at 0 0 0)
			(layer "F.Fab")
			(hide yes)
			(effects
				(font
					(size 1 1)
					(thickness 0.15)
				)
			)
		)
		(property "MPN" "GCM155R71H223MA55D"
			(at 0 0 0)
			(layer "F.Fab")
			(hide yes)
			(effects
				(font
					(size 1 1)
					(thickness 0.15)
				)
			)
		)
		(property "Manufacturer" "Murata"
			(at 0 0 0)
			(layer "F.Fab")
			(hide yes)
			(effects
				(font
					(size 1 1)
					(thickness 0.15)
				)
			)
		)
		(property "Public" ""
			(at 0 0 0)
			(layer "F.Fab")
			(hide yes)
			(effects
				(font
					(size 1 1)
					(thickness 0.15)
				)
			)
		)
		(property "Val" "22n"
			(at 0 0 0)
			(layer "F.Fab")
			(hide yes)
			(effects
				(font
					(size 1 1)
					(thickness 0.15)
				)
			)
		)
		(property "Voltage" ""
			(at 0 0 0)
			(layer "F.Fab")
			(hide yes)
			(effects
				(font
					(size 1 1)
					(thickness 0.15)
				)
			)
		)
		(sheetname "/Supply/")
		(sheetfile "supply.kicad_sch")
		(attr smd)
		(fp_rect
			(start -0.925 -0.47)
			(end 0.925 0.47)
			(stroke
				(width 0.05)
				(type default)
			)
			(fill no)
			(layer "F.CrtYd")
		)
		(fp_line
			(start -0.494 -0.25)
			(end 0.504 -0.25)
			(stroke
				(width 0.15)
				(type solid)
			)
			(layer "F.Fab")
		)
		(fp_line
			(start -0.494 0.248)
			(end -0.494 -0.25)
			(stroke
				(width 0.15)
				(type solid)
			)
			(layer "F.Fab")
		)
		(fp_line
			(start 0.504 -0.25)
			(end 0.504 0.248)
			(stroke
				(width 0.15)
				(type solid)
			)
			(layer "F.Fab")
		)
		(fp_line
			(start 0.504 0.248)
			(end -0.494 0.248)
			(stroke
				(width 0.15)
				(type solid)
			)
			(layer "F.Fab")
		)
		(fp_text user "Author: Antmicro"
			(at -0.939 3.399 0)
			(layer "F.Fab")
			(effects
				(font
					(size 0.7 0.7)
					(thickness 0.15)
				)
				(justify left bottom)
			)
		)
		(fp_text user "${REFERENCE}"
			(at -0.939 4.599 0)
			(layer "F.Fab")
			(effects
				(font
					(size 0.7 0.7)
					(thickness 0.15)
				)
				(justify left bottom)
			)
		)
		(fp_text user "License: Apache-2.0"
			(at -0.939 5.799 0)
			(layer "F.Fab")
			(effects
				(font
					(size 0.7 0.7)
					(thickness 0.15)
				)
				(justify left bottom)
			)
		)
		(pad "1" smd roundrect
			(at -0.48 0)
			(size 0.59 0.64)
			(layers "F.Cu" "F.Mask" "F.Paste")
			(roundrect_rratio 0.25)
			(net 417 "GND")
			(pintype "passive")
		)
		(pad "2" smd roundrect
			(at 0.48 0)
			(size 0.59 0.64)
			(layers "F.Cu" "F.Mask" "F.Paste")
			(roundrect_rratio 0.25)
			(net 228 "/Supply/1V05_SS")
			(pintype "passive")
		)
	)
	(footprint "antmicro-footprints:QFN-26_3.5x4.5x1mm_P0.45mm"
		(layer "F.Cu")
		(at 180.125 141.9425)
		(property "Reference" "U7"
			(at -2.585 3.5575 0)
			(unlocked yes)
			(layer "F.SilkS")
			(effects
				(font
					(size 0.7 0.7)
					(thickness 0.15)
				)
				(justify left bottom)
			)
		)
		(property "Value" "MP5424GRM"
			(at 0 3.7 0)
			(unlocked yes)
			(layer "F.Fab")
			(hide yes)
			(effects
				(font
					(size 0.7 0.7)
					(thickness 0.15)
				)
				(justify left bottom)
			)
		)
		(property "Datasheet" "https://www.monolithicpower.com/en/documentview/productdocument/index/version/2/document_type/Datasheet/lang/en/sku/MP5424GRM/document_id/10311/"
			(at 0 0 0)
			(layer "F.Fab")
			(hide yes)
			(effects
				(font
					(size 1.27 1.27)
					(thickness 0.15)
				)
			)
		)
		(property "Description" "5V PMIC with Four 4.5A/2.5A/4.5A/2A Buck Converters, 3 LDOs, 1 Load Switch and Flexible System Settings via I2C and MTP"
			(at 0 0 0)
			(layer "F.Fab")
			(hide yes)
			(effects
				(font
					(size 1.27 1.27)
					(thickness 0.15)
				)
			)
		)
		(property "Author" "Antmicro"
			(at 0 0 0)
			(layer "F.Fab")
			(hide yes)
			(effects
				(font
					(size 1 1)
					(thickness 0.15)
				)
			)
		)
		(property "License" "Apache-2.0"
			(at 0 0 0)
			(layer "F.Fab")
			(hide yes)
			(effects
				(font
					(size 1 1)
					(thickness 0.15)
				)
			)
		)
		(property "MPN" "MP5424GRM-0000-Z"
			(at 0 0 0)
			(layer "F.Fab")
			(hide yes)
			(effects
				(font
					(size 1 1)
					(thickness 0.15)
				)
			)
		)
		(property "Manufacturer" "Monolithic Power Systems"
			(at 0 0 0)
			(layer "F.Fab")
			(hide yes)
			(effects
				(font
					(size 1 1)
					(thickness 0.15)
				)
			)
		)
		(sheetname "/Supply/")
		(sheetfile "supply.kicad_sch")
		(attr smd)
		(fp_line
			(start -1.8 -2.3)
			(end -1.405 -2.3)
			(stroke
				(width 0.15)
				(type solid)
			)
			(layer "F.SilkS")
		)
		(fp_line
			(start -1.8 2.1)
			(end -1.8 2.3)
			(stroke
				(width 0.15)
				(type solid)
			)
			(layer "F.SilkS")
		)
		(fp_line
			(start -1.407 2.3)
			(end -1.8 2.3)
			(stroke
				(width 0.15)
				(type solid)
			)
			(layer "F.SilkS")
		)
		(fp_line
			(start 1.407 -2.3)
			(end 1.8 -2.3)
			(stroke
				(width 0.15)
				(type solid)
			)
			(layer "F.SilkS")
		)
		(fp_line
			(start 1.8 -2.1)
			(end 1.8 -2.3)
			(stroke
				(width 0.15)
				(type solid)
			)
			(layer "F.SilkS")
		)
		(fp_line
			(start 1.8 2.3)
			(end 1.407 2.3)
			(stroke
				(width 0.15)
				(type solid)
			)
			(layer "F.SilkS")
		)
		(fp_line
			(start 1.8 2.3)
			(end 1.8 2.1)
			(stroke
				(width 0.15)
				(type solid)
			)
			(layer "F.SilkS")
		)
		(fp_circle
			(center -2 -2.15)
			(end -1.95 -2.15)
			(stroke
				(width 0.15)
				(type solid)
			)
			(fill yes)
			(layer "F.SilkS")
		)
		(fp_rect
			(start -2.1 -2.6)
			(end 2.1 2.6)
			(stroke
				(width 0.05)
				(type solid)
			)
			(fill no)
			(layer "F.CrtYd")
		)
		(fp_line
			(start -1.803 -2.304)
			(end -1.803 2.294)
			(stroke
				(width 0.15)
				(type solid)
			)
			(layer "F.Fab")
		)
		(fp_line
			(start -1.803 -1.034)
			(end -0.533 -2.304)
			(stroke
				(width 0.15)
				(type solid)
			)
			(layer "F.Fab")
		)
		(fp_line
			(start -1.803 2.294)
			(end 1.803 2.294)
			(stroke
				(width 0.15)
				(type solid)
			)
			(layer "F.Fab")
		)
		(fp_line
			(start 1.803 -2.304)
			(end -1.803 -2.304)
			(stroke
				(width 0.15)
				(type solid)
			)
			(layer "F.Fab")
		)
		(fp_line
			(start 1.803 2.294)
			(end 1.803 -2.304)
			(stroke
				(width 0.15)
				(type solid)
			)
			(layer "F.Fab")
		)
		(fp_text user "${REFERENCE}"
			(at -2.65 9.595 0)
			(unlocked yes)
			(layer "F.Fab")
			(effects
				(font
					(size 0.7 0.7)
					(thickness 0.15)
				)
				(justify left bottom)
			)
		)
		(fp_text user "Author: Antmicro"
			(at -2.65 8.395 0)
			(layer "F.Fab")
			(effects
				(font
					(size 0.7 0.7)
					(thickness 0.15)
				)
				(justify left bottom)
			)
		)
		(fp_text user "License: Apache-2.0"
			(at -2.65 7.195 0)
			(layer "F.Fab")
			(effects
				(font
					(size 0.7 0.7)
					(thickness 0.15)
				)
				(justify left bottom)
			)
		)
		(pad "1" smd rect
			(at -1.61 -1.855)
			(size 0.875 0.2)
			(layers "F.Cu" "F.Mask" "F.Paste")
			(net 209 "/Supply/SENSE1_P")
			(pinfunction "FB1")
			(pintype "input")
		)
		(pad "1" smd roundrect
			(at -1.29 -1.905 90)
			(size 0.3 0.525)
			(layers "F.Cu" "F.Mask" "F.Paste")
			(roundrect_rratio 0)
			(chamfer_ratio 0.5)
			(chamfer bottom_left)
			(net 209 "/Supply/SENSE1_P")
			(pinfunction "FB1")
			(pintype "input")
		)
		(pad "1" smd rect
			(at -1.125 -2.23 90)
			(size 0.65 0.2)
			(layers "F.Cu" "F.Mask" "F.Paste")
			(net 209 "/Supply/SENSE1_P")
			(pinfunction "FB1")
			(pintype "input")
		)
		(pad "2" smd rect
			(at -1.6 -1.405)
			(size 0.9 0.2)
			(layers "F.Cu" "F.Mask" "F.Paste")
			(net 187 "/Supply/PWRON")
			(pinfunction "PWRON")
			(pintype "input")
		)
		(pad "3" smd rect
			(at -1.4 -0.955)
			(size 1.3 0.2)
			(layers "F.Cu" "F.Mask" "F.Paste")
			(net 90 "+5V")
			(pinfunction "VIN1")
			(pintype "power_in")
		)
		(pad "4" smd rect
			(at -1.4 -0.505)
			(size 1.3 0.2)
			(layers "F.Cu" "F.Mask" "F.Paste")
			(net 168 "Net-(U7-SW1)")
			(pinfunction "SW1")
			(pintype "power_out")
		)
		(pad "5" smd rect
			(at -1.4 -0.005)
			(size 1.3 0.3)
			(layers "F.Cu" "F.Mask" "F.Paste")
			(net 417 "GND")
			(pinfunction "GND")
			(pintype "power_in")
		)
		(pad "6" smd rect
			(at -1.4 0.495)
			(size 1.3 0.2)
			(layers "F.Cu" "F.Mask" "F.Paste")
			(net 181 "Net-(U7-SW3)")
			(pinfunction "SW3")
			(pintype "power_out")
		)
		(pad "7" smd rect
			(at -1.4 0.945)
			(size 1.3 0.2)
			(layers "F.Cu" "F.Mask" "F.Paste")
			(net 90 "+5V")
			(pinfunction "VIN3")
			(pintype "power_in")
		)
		(pad "8" smd rect
			(at -1.6 1.395)
			(size 0.9 0.2)
			(layers "F.Cu" "F.Mask" "F.Paste")
			(net 406 "/Supply/SENSE2_P")
			(pinfunction "FB3")
			(pintype "input")
		)
		(pad "9" smd rect
			(at -1.54 1.845)
			(size 1.025 0.2)
			(layers "F.Cu" "F.Mask" "F.Paste")
			(net 656 "/Supply/PG")
			(pinfunction "RSTO")
			(pintype "input")
		)
		(pad "9" smd rect
			(at -1.29 1.895 90)
			(size 0.3 0.525)
			(layers "F.Cu" "F.Mask" "F.Paste")
			(net 656 "/Supply/PG")
			(pinfunction "RSTO")
			(pintype "input")
		)
		(pad "9" smd rect
			(at -1.125 2.145 90)
			(size 0.8 0.2)
			(layers "F.Cu" "F.Mask" "F.Paste")
			(net 656 "/Supply/PG")
			(pinfunction "RSTO")
			(pintype "input")
		)
		(pad "10" smd rect
			(at -0.675 2.095 90)
			(size 0.9 0.2)
			(layers "F.Cu" "F.Mask" "F.Paste")
			(net 92 "/FPGA MSSIO/SUPPLY.SCL")
			(pinfunction "SCL")
			(pintype "input")
		)
		(pad "11" smd rect
			(at -0.225 2.095 90)
			(size 0.9 0.2)
			(layers "F.Cu" "F.Mask" "F.Paste")
			(net 100 "/FPGA MSSIO/SUPPLY.SDA")
			(pinfunction "SDA")
			(pintype "bidirectional")
		)
		(pad "12" smd rect
			(at 0.225 2.095 90)
			(size 0.9 0.2)
			(layers "F.Cu" "F.Mask" "F.Paste")
			(net 633 "Net-(U7-OUT4)")
			(pinfunction "OUT4")
			(pintype "power_out")
		)
		(pad "13" smd rect
			(at 0.675 2.095 90)
			(size 0.9 0.2)
			(layers "F.Cu" "F.Mask" "F.Paste")
			(net 90 "+5V")
			(pinfunction "VIN5")
			(pintype "power_in")
		)
		(pad "14" smd rect
			(at 1.125 2.145 90)
			(size 0.8 0.2)
			(layers "F.Cu" "F.Mask" "F.Paste")
			(net 634 "Net-(U7-OUT5)")
			(pinfunction "OUT5")
			(pintype "power_out")
		)
		(pad "14" smd rect
			(at 1.29 1.895 90)
			(size 0.3 0.525)
			(layers "F.Cu" "F.Mask" "F.Paste")
			(net 634 "Net-(U7-OUT5)")
			(pinfunction "OUT5")
			(pintype "power_out")
		)
		(pad "14" smd rect
			(at 1.54 1.845)
			(size 1.025 0.2)
			(layers "F.Cu" "F.Mask" "F.Paste")
			(net 634 "Net-(U7-OUT5)")
			(pinfunction "OUT5")
			(pintype "power_out")
		)
		(pad "15" smd rect
			(at 1.6 1.395)
			(size 0.9 0.2)
			(layers "F.Cu" "F.Mask" "F.Paste")
			(net 409 "/Supply/SENSE4_P")
			(pinfunction "FB4")
			(pintype "input")
		)
		(pad "16" smd rect
			(at 1.4 0.945)
			(size 1.3 0.2)
			(layers "F.Cu" "F.Mask" "F.Paste")
			(net 90 "+5V")
			(pinfunction "VIN4")
			(pintype "power_in")
		)
		(pad "17" smd rect
			(at 1.4 0.495)
			(size 1.3 0.2)
			(layers "F.Cu" "F.Mask" "F.Paste")
			(net 184 "Net-(U7-SW4)")
			(pinfunction "SW4")
			(pintype "power_out")
		)
		(pad "18" smd rect
			(at 1.4 -0.005)
			(size 1.3 0.3)
			(layers "F.Cu" "F.Mask" "F.Paste")
			(net 417 "GND")
			(pinfunction "GND")
			(pintype "passive")
		)
		(pad "19" smd rect
			(at 1.4 -0.505)
			(size 1.3 0.2)
			(layers "F.Cu" "F.Mask" "F.Paste")
			(net 175 "Net-(U7-SW2)")
			(pinfunction "SW2")
			(pintype "power_out")
		)
		(pad "20" smd rect
			(at 1.4 -0.955)
			(size 1.3 0.2)
			(layers "F.Cu" "F.Mask" "F.Paste")
			(net 90 "+5V")
			(pinfunction "VIN2")
			(pintype "power_in")
		)
		(pad "21" smd rect
			(at 1.6 -1.405)
			(size 0.9 0.2)
			(layers "F.Cu" "F.Mask" "F.Paste")
			(net 272 "/Supply/SENSE3_P")
			(pinfunction "FB2")
			(pintype "input")
		)
		(pad "22" smd rect
			(at 1.125 -2.155 90)
			(size 0.8 0.2)
			(layers "F.Cu" "F.Mask" "F.Paste")
			(net 632 "Net-(U7-OUT2)")
			(pinfunction "OUT2")
			(pintype "power_out")
		)
		(pad "22" smd rect
			(at 1.29 -1.905 90)
			(size 0.3 0.525)
			(layers "F.Cu" "F.Mask" "F.Paste")
			(net 632 "Net-(U7-OUT2)")
			(pinfunction "OUT2")
			(pintype "power_out")
		)
		(pad "22" smd rect
			(at 1.54 -1.855)
			(size 1.025 0.2)
			(layers "F.Cu" "F.Mask" "F.Paste")
			(net 632 "Net-(U7-OUT2)")
			(pinfunction "OUT2")
			(pintype "power_out")
		)
		(pad "23" smd rect
			(at 0.675 -2.105 90)
			(size 0.9 0.2)
			(layers "F.Cu" "F.Mask" "F.Paste")
			(net 90 "+5V")
			(pinfunction "LSWI")
			(pintype "power_in")
		)
		(pad "24" smd rect
			(at 0.225 -2.105 90)
			(size 0.9 0.2)
			(layers "F.Cu" "F.Mask" "F.Paste")
			(net 229 "unconnected-(U7-LSWO-Pad24)")
			(pinfunction "LSWO")
			(pintype "power_out+no_connect")
		)
		(pad "25" smd rect
			(at -0.225 -2.105 90)
			(size 0.9 0.2)
			(layers "F.Cu" "F.Mask" "F.Paste")
			(net 417 "GND")
			(pinfunction "AGND")
			(pintype "power_in")
		)
		(pad "26" smd rect
			(at -0.675 -2.105 90)
			(size 0.9 0.2)
			(layers "F.Cu" "F.Mask" "F.Paste")
			(net 3 "Net-(U7-AVIN)")
			(pinfunction "AVIN")
			(pintype "input")
		)
	)
	(footprint "antmicro-footprints:BGA-200_10.0x14.5mm_Layout12x22_P0.80x0.65mm"
		(layer "F.Cu")
		(at 180 129.6)
		(descr "BGA-200, 14.5x10.0mm, 200 Ball, 12x22 Layout, 0.8x0.65mm Pitch, http://www.issi.com/WW/pdf/43-46LQ32256A-AL.pdf")
		(tags "BGA 200 0.8x0.65")
		(property "Reference" "U12"
			(at 6.26 1.53 270)
			(layer "F.SilkS")
			(effects
				(font
					(size 0.7 0.7)
					(thickness 0.15)
				)
				(justify left bottom)
			)
		)
		(property "Value" "MT53D512M32D2_WFBGA"
			(at -5.5 9 0)
			(layer "F.Fab")
			(hide yes)
			(effects
				(font
					(size 0.7 0.7)
					(thickness 0.15)
				)
				(justify left bottom)
			)
		)
		(property "Datasheet" "https://eu.mouser.com/datasheet/2/671/200b_z11m_non_auto_lpddr4_lpddr4x-3077547.pdf"
			(at 0 0 0)
			(layer "F.Fab")
			(hide yes)
			(effects
				(font
					(size 1.27 1.27)
					(thickness 0.15)
				)
			)
		)
		(property "Description" "LPDDR4 DRAM, 1GX32"
			(at 0 0 0)
			(layer "F.Fab")
			(hide yes)
			(effects
				(font
					(size 1.27 1.27)
					(thickness 0.15)
				)
			)
		)
		(property "Author" "Antmicro"
			(at 0 0 0)
			(layer "F.Fab")
			(hide yes)
			(effects
				(font
					(size 1 1)
					(thickness 0.15)
				)
			)
		)
		(property "License" "Apache-2.0"
			(at 0 0 0)
			(layer "F.Fab")
			(hide yes)
			(effects
				(font
					(size 1 1)
					(thickness 0.15)
				)
			)
		)
		(property "MPN" "MT53D512M32D2DS-053 WT:D TR"
			(at 0 0 0)
			(layer "F.Fab")
			(hide yes)
			(effects
				(font
					(size 1 1)
					(thickness 0.15)
				)
			)
		)
		(property "Manufacturer" "Micron Technology"
			(at 0 0 0)
			(layer "F.Fab")
			(hide yes)
			(effects
				(font
					(size 1 1)
					(thickness 0.15)
				)
			)
		)
		(property "VSD_class" "LPDDR4"
			(at 0 0 0)
			(layer "F.Fab")
			(hide yes)
			(effects
				(font
					(size 1 1)
					(thickness 0.15)
				)
			)
		)
		(property ki_fp_filters "WFBGA200_10X14p5_DS_MRN WFBGA200_10X14p5_DS_MRN-M WFBGA200_10X14p5_DS_MRN-L")
		(sheetname "/LPDDR4/")
		(sheetfile "lpddr.kicad_sch")
		(attr smd)
		(fp_line
			(start -5.106 7.352)
			(end -5.106 -6.369)
			(stroke
				(width 0.15)
				(type solid)
			)
			(layer "F.SilkS")
		)
		(fp_line
			(start -4.106 -7.369)
			(end 5.115 -7.369)
			(stroke
				(width 0.15)
				(type solid)
			)
			(layer "F.SilkS")
		)
		(fp_line
			(start 5.115 -7.369)
			(end 5.115 7.352)
			(stroke
				(width 0.15)
				(type solid)
			)
			(layer "F.SilkS")
		)
		(fp_line
			(start 5.115 7.352)
			(end -5.106 7.352)
			(stroke
				(width 0.15)
				(type solid)
			)
			(layer "F.SilkS")
		)
		(fp_circle
			(center -5.1 -7.35)
			(end -5.05 -7.35)
			(stroke
				(width 0.15)
				(type solid)
			)
			(fill yes)
			(layer "F.SilkS")
		)
		(fp_rect
			(start -5.25 -7.5)
			(end 5.248 7.499)
			(stroke
				(width 0.05)
				(type solid)
			)
			(fill no)
			(layer "F.CrtYd")
		)
		(fp_line
			(start -4.996 -6.258)
			(end -3.996 -7.258)
			(stroke
				(width 0.15)
				(type solid)
			)
			(layer "F.Fab")
		)
		(fp_line
			(start -4.996 7.241)
			(end -4.996 -6.258)
			(stroke
				(width 0.15)
				(type solid)
			)
			(layer "F.Fab")
		)
		(fp_line
			(start -3.996 -7.258)
			(end 5.004 -7.258)
			(stroke
				(width 0.15)
				(type solid)
			)
			(layer "F.Fab")
		)
		(fp_line
			(start 5.004 -7.258)
			(end 5.004 7.241)
			(stroke
				(width 0.15)
				(type solid)
			)
			(layer "F.Fab")
		)
		(fp_line
			(start 5.004 7.241)
			(end -4.996 7.241)
			(stroke
				(width 0.15)
				(type solid)
			)
			(layer "F.Fab")
		)
		(fp_text user "License: Apache-2.0"
			(at -5.5 12.75 0)
			(layer "F.Fab")
			(effects
				(font
					(size 0.7 0.7)
					(thickness 0.15)
				)
				(justify left bottom)
			)
		)
		(fp_text user "Author: Antmicro"
			(at -5.5 11.5 0)
			(layer "F.Fab")
			(effects
				(font
					(size 0.7 0.7)
					(thickness 0.15)
				)
				(justify left bottom)
			)
		)
		(fp_text user "${REFERENCE}"
			(at -5.5 10.25 0)
			(layer "F.Fab")
			(effects
				(font
					(size 0.7 0.7)
					(thickness 0.15)
				)
				(justify left bottom)
			)
		)
		(pad "A1" smd circle
			(at -4.396 -6.834)
			(size 0.27 0.27)
			(layers "F.Cu" "F.Mask" "F.Paste")
			(net 478 "unconnected-(U12A-DNU-PadA1)")
			(pinfunction "DNU")
			(pintype "no_connect")
		)
		(pad "A2" smd circle
			(at -3.596 -6.834)
			(size 0.27 0.27)
			(layers "F.Cu" "F.Mask" "F.Paste")
			(net 479 "unconnected-(U12A-DNU-PadA2)")
			(pinfunction "DNU")
			(pintype "no_connect")
		)
		(pad "A3" smd circle
			(at -2.795 -6.834)
			(size 0.27 0.27)
			(layers "F.Cu" "F.Mask" "F.Paste")
			(net 417 "GND")
			(pinfunction "VSS")
			(pintype "power_out")
		)
		(pad "A4" smd circle
			(at -1.996 -6.834)
			(size 0.27 0.27)
			(layers "F.Cu" "F.Mask" "F.Paste")
			(net 2 "+1V1")
			(pinfunction "VDD2")
			(pintype "power_in")
		)
		(pad "A5" smd circle
			(at -1.196 -6.834)
			(size 0.27 0.27)
			(layers "F.Cu" "F.Mask" "F.Paste")
			(net 271 "Net-(U12A-ZQ0)")
			(pinfunction "ZQ0")
			(pintype "unspecified")
		)
		(pad "A8" smd circle
			(at 1.205 -6.834)
			(size 0.27 0.27)
			(layers "F.Cu" "F.Mask" "F.Paste")
			(net 480 "unconnected-(U12B-NC-PadA8)")
			(pinfunction "NC")
			(pintype "no_connect")
		)
		(pad "A9" smd circle
			(at 2.004 -6.834)
			(size 0.27 0.27)
			(layers "F.Cu" "F.Mask" "F.Paste")
			(net 2 "+1V1")
			(pinfunction "VDD2")
			(pintype "passive")
		)
		(pad "A10" smd circle
			(at 2.805 -6.834)
			(size 0.27 0.27)
			(layers "F.Cu" "F.Mask" "F.Paste")
			(net 417 "GND")
			(pinfunction "VSS")
			(pintype "power_out")
		)
		(pad "A11" smd circle
			(at 3.604 -6.834)
			(size 0.27 0.27)
			(layers "F.Cu" "F.Mask" "F.Paste")
			(net 481 "unconnected-(U12B-DNU-PadA11)")
			(pinfunction "DNU")
			(pintype "no_connect")
		)
		(pad "A12" smd circle
			(at 4.405 -6.834)
			(size 0.27 0.27)
			(layers "F.Cu" "F.Mask" "F.Paste")
			(net 482 "unconnected-(U12B-DNU-PadA12)")
			(pinfunction "DNU")
			(pintype "no_connect")
		)
		(pad "AA1" smd circle
			(at -4.396 6.166)
			(size 0.27 0.27)
			(layers "F.Cu" "F.Mask" "F.Paste")
			(net 483 "unconnected-(U12B-DNU-PadAA1)")
			(pinfunction "DNU")
			(pintype "no_connect")
		)
		(pad "AA2" smd circle
			(at -3.596 6.166)
			(size 0.27 0.27)
			(layers "F.Cu" "F.Mask" "F.Paste")
			(net 613 "/FPGA MSS/LPDDR4.DQ16")
			(pinfunction "DQ0_B")
			(pintype "bidirectional")
		)
		(pad "AA3" smd circle
			(at -2.795 6.166)
			(size 0.27 0.27)
			(layers "F.Cu" "F.Mask" "F.Paste")
			(net 2 "+1V1")
			(pinfunction "VDDQ")
			(pintype "passive")
		)
		(pad "AA4" smd circle
			(at -1.996 6.166)
			(size 0.27 0.27)
			(layers "F.Cu" "F.Mask" "F.Paste")
			(net 606 "/FPGA MSS/LPDDR4.DQ23")
			(pinfunction "DQ7_B")
			(pintype "bidirectional")
		)
		(pad "AA5" smd circle
			(at -1.196 6.166)
			(size 0.27 0.27)
			(layers "F.Cu" "F.Mask" "F.Paste")
			(net 2 "+1V1")
			(pinfunction "VDDQ")
			(pintype "passive")
		)
		(pad "AA8" smd circle
			(at 1.205 6.166)
			(size 0.27 0.27)
			(layers "F.Cu" "F.Mask" "F.Paste")
			(net 2 "+1V1")
			(pinfunction "VDDQ")
			(pintype "passive")
		)
		(pad "AA9" smd circle
			(at 2.004 6.166)
			(size 0.27 0.27)
			(layers "F.Cu" "F.Mask" "F.Paste")
			(net 567 "/FPGA MSS/LPDDR4.DQ31")
			(pinfunction "DQ15_B")
			(pintype "bidirectional")
		)
		(pad "AA10" smd circle
			(at 2.805 6.166)
			(size 0.27 0.27)
			(layers "F.Cu" "F.Mask" "F.Paste")
			(net 2 "+1V1")
			(pinfunction "VDDQ")
			(pintype "power_in")
		)
		(pad "AA11" smd circle
			(at 3.604 6.166)
			(size 0.27 0.27)
			(layers "F.Cu" "F.Mask" "F.Paste")
			(net 594 "/FPGA MSS/LPDDR4.DQ24")
			(pinfunction "DQ8_B")
			(pintype "bidirectional")
		)
		(pad "AA12" smd circle
			(at 4.405 6.166)
			(size 0.27 0.27)
			(layers "F.Cu" "F.Mask" "F.Paste")
			(net 484 "unconnected-(U12B-DNU-PadAA12)")
			(pinfunction "DNU")
			(pintype "no_connect")
		)
		(pad "AB1" smd circle
			(at -4.396 6.817)
			(size 0.27 0.27)
			(layers "F.Cu" "F.Mask" "F.Paste")
			(net 485 "unconnected-(U12B-DNU-PadAB1)")
			(pinfunction "DNU")
			(pintype "no_connect")
		)
		(pad "AB2" smd circle
			(at -3.596 6.817)
			(size 0.27 0.27)
			(layers "F.Cu" "F.Mask" "F.Paste")
			(net 486 "unconnected-(U12B-DNU-PadAB2)")
			(pinfunction "DNU")
			(pintype "no_connect")
		)
		(pad "AB3" smd circle
			(at -2.795 6.817)
			(size 0.27 0.27)
			(layers "F.Cu" "F.Mask" "F.Paste")
			(net 417 "GND")
			(pinfunction "VSS")
			(pintype "passive")
		)
		(pad "AB4" smd circle
			(at -1.996 6.817)
			(size 0.27 0.27)
			(layers "F.Cu" "F.Mask" "F.Paste")
			(net 2 "+1V1")
			(pinfunction "VDD2")
			(pintype "power_in")
		)
		(pad "AB5" smd circle
			(at -1.196 6.817)
			(size 0.27 0.27)
			(layers "F.Cu" "F.Mask" "F.Paste")
			(net 417 "GND")
			(pinfunction "VSS")
			(pintype "passive")
		)
		(pad "AB8" smd circle
			(at 1.205 6.817)
			(size 0.27 0.27)
			(layers "F.Cu" "F.Mask" "F.Paste")
			(net 417 "GND")
			(pinfunction "VSS")
			(pintype "passive")
		)
		(pad "AB9" smd circle
			(at 2.004 6.817)
			(size 0.27 0.27)
			(layers "F.Cu" "F.Mask" "F.Paste")
			(net 2 "+1V1")
			(pinfunction "VDD2")
			(pintype "passive")
		)
		(pad "AB10" smd circle
			(at 2.805 6.817)
			(size 0.27 0.27)
			(layers "F.Cu" "F.Mask" "F.Paste")
			(net 417 "GND")
			(pinfunction "VSS")
			(pintype "passive")
		)
		(pad "AB11" smd circle
			(at 3.604 6.817)
			(size 0.27 0.27)
			(layers "F.Cu" "F.Mask" "F.Paste")
			(net 487 "unconnected-(U12B-DNU-PadAB11)")
			(pinfunction "DNU")
			(pintype "no_connect")
		)
		(pad "AB12" smd circle
			(at 4.405 6.817)
			(size 0.27 0.27)
			(layers "F.Cu" "F.Mask" "F.Paste")
			(net 488 "unconnected-(U12B-DNU-PadAB12)")
			(pinfunction "DNU")
			(pintype "no_connect")
		)
		(pad "B1" smd circle
			(at -4.396 -6.183)
			(size 0.27 0.27)
			(layers "F.Cu" "F.Mask" "F.Paste")
			(net 489 "unconnected-(U12A-DNU-PadB1)")
			(pinfunction "DNU")
			(pintype "no_connect")
		)
		(pad "B2" smd circle
			(at -3.596 -6.183)
			(size 0.27 0.27)
			(layers "F.Cu" "F.Mask" "F.Paste")
			(net 608 "/FPGA MSS/LPDDR4.DQ0")
			(pinfunction "DQ0_A")
			(pintype "bidirectional")
		)
		(pad "B3" smd circle
			(at -2.795 -6.183)
			(size 0.27 0.27)
			(layers "F.Cu" "F.Mask" "F.Paste")
			(net 2 "+1V1")
			(pinfunction "VDDQ")
			(pintype "power_in")
		)
		(pad "B4" smd circle
			(at -1.996 -6.183)
			(size 0.27 0.27)
			(layers "F.Cu" "F.Mask" "F.Paste")
			(net 319 "/FPGA MSS/LPDDR4.DQ7")
			(pinfunction "DQ7_A")
			(pintype "bidirectional")
		)
		(pad "B5" smd circle
			(at -1.196 -6.183)
			(size 0.27 0.27)
			(layers "F.Cu" "F.Mask" "F.Paste")
			(net 2 "+1V1")
			(pinfunction "VDDQ")
			(pintype "passive")
		)
		(pad "B8" smd circle
			(at 1.205 -6.183)
			(size 0.27 0.27)
			(layers "F.Cu" "F.Mask" "F.Paste")
			(net 2 "+1V1")
			(pinfunction "VDDQ")
			(pintype "passive")
		)
		(pad "B9" smd circle
			(at 2.004 -6.183)
			(size 0.27 0.27)
			(layers "F.Cu" "F.Mask" "F.Paste")
			(net 311 "/FPGA MSS/LPDDR4.DQ15")
			(pinfunction "DQ15_A")
			(pintype "bidirectional")
		)
		(pad "B10" smd circle
			(at 2.805 -6.183)
			(size 0.27 0.27)
			(layers "F.Cu" "F.Mask" "F.Paste")
			(net 2 "+1V1")
			(pinfunction "VDDQ")
			(pintype "passive")
		)
		(pad "B11" smd circle
			(at 3.604 -6.183)
			(size 0.27 0.27)
			(layers "F.Cu" "F.Mask" "F.Paste")
			(net 604 "/FPGA MSS/LPDDR4.DQ8")
			(pinfunction "DQ8_A")
			(pintype "bidirectional")
		)
		(pad "B12" smd circle
			(at 4.405 -6.183)
			(size 0.27 0.27)
			(layers "F.Cu" "F.Mask" "F.Paste")
			(net 490 "unconnected-(U12B-DNU-PadB12)")
			(pinfunction "DNU")
			(pintype "no_connect")
		)
		(pad "C1" smd circle
			(at -4.396 -5.534)
			(size 0.27 0.27)
			(layers "F.Cu" "F.Mask" "F.Paste")
			(net 417 "GND")
			(pinfunction "VSS")
			(pintype "passive")
		)
		(pad "C2" smd circle
			(at -3.596 -5.534)
			(size 0.27 0.27)
			(layers "F.Cu" "F.Mask" "F.Paste")
			(net 609 "/FPGA MSS/LPDDR4.DQ1")
			(pinfunction "DQ1_A")
			(pintype "bidirectional")
		)
		(pad "C3" smd circle
			(at -2.795 -5.534)
			(size 0.27 0.27)
			(layers "F.Cu" "F.Mask" "F.Paste")
			(net 320 "/FPGA MSS/LPDDR4.DMI0")
			(pinfunction "DMI0_A")
			(pintype "bidirectional")
		)
		(pad "C4" smd circle
			(at -1.996 -5.534)
			(size 0.27 0.27)
			(layers "F.Cu" "F.Mask" "F.Paste")
			(net 316 "/FPGA MSS/LPDDR4.DQ6")
			(pinfunction "DQ6_A")
			(pintype "bidirectional")
		)
		(pad "C5" smd circle
			(at -1.196 -5.534)
			(size 0.27 0.27)
			(layers "F.Cu" "F.Mask" "F.Paste")
			(net 417 "GND")
			(pinfunction "VSS")
			(pintype "passive")
		)
		(pad "C8" smd circle
			(at 1.205 -5.534)
			(size 0.27 0.27)
			(layers "F.Cu" "F.Mask" "F.Paste")
			(net 417 "GND")
			(pinfunction "VSS")
			(pintype "passive")
		)
		(pad "C9" smd circle
			(at 2.004 -5.534)
			(size 0.27 0.27)
			(layers "F.Cu" "F.Mask" "F.Paste")
			(net 612 "/FPGA MSS/LPDDR4.DQ14")
			(pinfunction "DQ14_A")
			(pintype "bidirectional")
		)
		(pad "C10" smd circle
			(at 2.805 -5.534)
			(size 0.27 0.27)
			(layers "F.Cu" "F.Mask" "F.Paste")
			(net 310 "/FPGA MSS/LPDDR4.DMI1")
			(pinfunction "DMI1_A")
			(pintype "bidirectional")
		)
		(pad "C11" smd circle
			(at 3.604 -5.534)
			(size 0.27 0.27)
			(layers "F.Cu" "F.Mask" "F.Paste")
			(net 603 "/FPGA MSS/LPDDR4.DQ9")
			(pinfunction "DQ9_A")
			(pintype "bidirectional")
		)
		(pad "C12" smd circle
			(at 4.405 -5.534)
			(size 0.27 0.27)
			(layers "F.Cu" "F.Mask" "F.Paste")
			(net 417 "GND")
			(pinfunction "VSS")
			(pintype "passive")
		)
		(pad "D1" smd circle
			(at -4.396 -4.883)
			(size 0.27 0.27)
			(layers "F.Cu" "F.Mask" "F.Paste")
			(net 2 "+1V1")
			(pinfunction "VDDQ")
			(pintype "passive")
		)
		(pad "D2" smd circle
			(at -3.596 -4.883)
			(size 0.27 0.27)
			(layers "F.Cu" "F.Mask" "F.Paste")
			(net 417 "GND")
			(pinfunction "VSS")
			(pintype "passive")
		)
		(pad "D3" smd circle
			(at -2.795 -4.883)
			(size 0.27 0.27)
			(layers "F.Cu" "F.Mask" "F.Paste")
			(net 306 "/FPGA MSS/LPDDR4.DQS0_P")
			(pinfunction "DQS0_t_A")
			(pintype "bidirectional")
		)
		(pad "D4" smd circle
			(at -1.996 -4.883)
			(size 0.27 0.27)
			(layers "F.Cu" "F.Mask" "F.Paste")
			(net 417 "GND")
			(pinfunction "VSS")
			(pintype "passive")
		)
		(pad "D5" smd circle
			(at -1.196 -4.883)
			(size 0.27 0.27)
			(layers "F.Cu" "F.Mask" "F.Paste")
			(net 2 "+1V1")
			(pinfunction "VDDQ")
			(pintype "passive")
		)
		(pad "D8" smd circle
			(at 1.205 -4.883)
			(size 0.27 0.27)
			(layers "F.Cu" "F.Mask" "F.Paste")
			(net 2 "+1V1")
			(pinfunction "VDDQ")
			(pintype "passive")
		)
		(pad "D9" smd circle
			(at 2.004 -4.883)
			(size 0.27 0.27)
			(layers "F.Cu" "F.Mask" "F.Paste")
			(net 417 "GND")
			(pinfunction "VSS")
			(pintype "passive")
		)
		(pad "D10" smd circle
			(at 2.805 -4.883)
			(size 0.27 0.27)
			(layers "F.Cu" "F.Mask" "F.Paste")
			(net 611 "/FPGA MSS/LPDDR4.DQS1_P")
			(pinfunction "DQS1_t_A")
			(pintype "bidirectional")
		)
		(pad "D11" smd circle
			(at 3.604 -4.883)
			(size 0.27 0.27)
			(layers "F.Cu" "F.Mask" "F.Paste")
			(net 417 "GND")
			(pinfunction "VSS")
			(pintype "passive")
		)
		(pad "D12" smd circle
			(at 4.405 -4.883)
			(size 0.27 0.27)
			(layers "F.Cu" "F.Mask" "F.Paste")
			(net 2 "+1V1")
			(pinfunction "VDDQ")
			(pintype "passive")
		)
		(pad "E1" smd circle
			(at -4.396 -4.233)
			(size 0.27 0.27)
			(layers "F.Cu" "F.Mask" "F.Paste")
			(net 417 "GND")
			(pinfunction "VSS")
			(pintype "passive")
		)
		(pad "E2" smd circle
			(at -3.596 -4.233)
			(size 0.27 0.27)
			(layers "F.Cu" "F.Mask" "F.Paste")
			(net 607 "/FPGA MSS/LPDDR4.DQ2")
			(pinfunction "DQ2_A")
			(pintype "bidirectional")
		)
		(pad "E3" smd circle
			(at -2.795 -4.233)
			(size 0.27 0.27)
			(layers "F.Cu" "F.Mask" "F.Paste")
			(net 307 "/FPGA MSS/LPDDR4.DQS0_N")
			(pinfunction "DQS0_c_A")
			(pintype "bidirectional")
		)
		(pad "E4" smd circle
			(at -1.996 -4.233)
			(size 0.27 0.27)
			(layers "F.Cu" "F.Mask" "F.Paste")
			(net 308 "/FPGA MSS/LPDDR4.DQ5")
			(pinfunction "DQ5_A")
			(pintype "bidirectional")
		)
		(pad "E5" smd circle
			(at -1.196 -4.233)
			(size 0.27 0.27)
			(layers "F.Cu" "F.Mask" "F.Paste")
			(net 417 "GND")
			(pinfunction "VSS")
			(pintype "passive")
		)
		(pad "E8" smd circle
			(at 1.205 -4.233)
			(size 0.27 0.27)
			(layers "F.Cu" "F.Mask" "F.Paste")
			(net 417 "GND")
			(pinfunction "VSS")
			(pintype "passive")
		)
		(pad "E9" smd circle
			(at 2.004 -4.233)
			(size 0.27 0.27)
			(layers "F.Cu" "F.Mask" "F.Paste")
			(net 323 "/FPGA MSS/LPDDR4.DQ13")
			(pinfunction "DQ13_A")
			(pintype "bidirectional")
		)
		(pad "E10" smd circle
			(at 2.805 -4.233)
			(size 0.27 0.27)
			(layers "F.Cu" "F.Mask" "F.Paste")
			(net 602 "/FPGA MSS/LPDDR4.DQS1_N")
			(pinfunction "DQS1_c_A")
			(pintype "bidirectional")
		)
		(pad "E11" smd circle
			(at 3.604 -4.233)
			(size 0.27 0.27)
			(layers "F.Cu" "F.Mask" "F.Paste")
			(net 321 "/FPGA MSS/LPDDR4.DQ10")
			(pinfunction "DQ10_A")
			(pintype "bidirectional")
		)
		(pad "E12" smd circle
			(at 4.405 -4.233)
			(size 0.27 0.27)
			(layers "F.Cu" "F.Mask" "F.Paste")
			(net 417 "GND")
			(pinfunction "VSS")
			(pintype "passive")
		)
		(pad "F1" smd circle
			(at -4.396 -3.584)
			(size 0.27 0.27)
			(layers "F.Cu" "F.Mask" "F.Paste")
			(net 48 "+1V8")
			(pinfunction "VDD1")
			(pintype "power_in")
		)
		(pad "F2" smd circle
			(at -3.596 -3.584)
			(size 0.27 0.27)
			(layers "F.Cu" "F.Mask" "F.Paste")
			(net 305 "/FPGA MSS/LPDDR4.DQ3")
			(pinfunction "DQ3_A")
			(pintype "bidirectional")
		)
		(pad "F3" smd circle
			(at -2.795 -3.584)
			(size 0.27 0.27)
			(layers "F.Cu" "F.Mask" "F.Paste")
			(net 2 "+1V1")
			(pinfunction "VDDQ")
			(pintype "passive")
		)
		(pad "F4" smd circle
			(at -1.996 -3.584)
			(size 0.27 0.27)
			(layers "F.Cu" "F.Mask" "F.Paste")
			(net 610 "/FPGA MSS/LPDDR4.DQ4")
			(pinfunction "DQ4_A")
			(pintype "bidirectional")
		)
		(pad "F5" smd circle
			(at -1.196 -3.584)
			(size 0.27 0.27)
			(layers "F.Cu" "F.Mask" "F.Paste")
			(net 2 "+1V1")
			(pinfunction "VDD2")
			(pintype "passive")
		)
		(pad "F8" smd circle
			(at 1.205 -3.584)
			(size 0.27 0.27)
			(layers "F.Cu" "F.Mask" "F.Paste")
			(net 2 "+1V1")
			(pinfunction "VDD2")
			(pintype "passive")
		)
		(pad "F9" smd circle
			(at 2.004 -3.584)
			(size 0.27 0.27)
			(layers "F.Cu" "F.Mask" "F.Paste")
			(net 322 "/FPGA MSS/LPDDR4.DQ12")
			(pinfunction "DQ12_A")
			(pintype "bidirectional")
		)
		(pad "F10" smd circle
			(at 2.805 -3.584)
			(size 0.27 0.27)
			(layers "F.Cu" "F.Mask" "F.Paste")
			(net 2 "+1V1")
			(pinfunction "VDDQ")
			(pintype "passive")
		)
		(pad "F11" smd circle
			(at 3.604 -3.584)
			(size 0.27 0.27)
			(layers "F.Cu" "F.Mask" "F.Paste")
			(net 309 "/FPGA MSS/LPDDR4.DQ11")
			(pinfunction "DQ11_A")
			(pintype "bidirectional")
		)
		(pad "F12" smd circle
			(at 4.405 -3.584)
			(size 0.27 0.27)
			(layers "F.Cu" "F.Mask" "F.Paste")
			(net 48 "+1V8")
			(pinfunction "VDD1")
			(pintype "power_in")
		)
		(pad "G1" smd circle
			(at -4.396 -2.934)
			(size 0.27 0.27)
			(layers "F.Cu" "F.Mask" "F.Paste")
			(net 417 "GND")
			(pinfunction "VSS")
			(pintype "passive")
		)
		(pad "G2" smd circle
			(at -3.596 -2.934)
			(size 0.27 0.27)
			(layers "F.Cu" "F.Mask" "F.Paste")
			(net 393 "/FPGA MSS/LPDDR4.ODT_CA_A")
			(pinfunction "ODT_CA_A")
			(pintype "input")
		)
		(pad "G3" smd circle
			(at -2.795 -2.934)
			(size 0.27 0.27)
			(layers "F.Cu" "F.Mask" "F.Paste")
			(net 417 "GND")
			(pinfunction "VSS")
			(pintype "passive")
		)
		(pad "G4" smd circle
			(at -1.996 -2.934)
			(size 0.27 0.27)
			(layers "F.Cu" "F.Mask" "F.Paste")
			(net 48 "+1V8")
			(pinfunction "VDD1")
			(pintype "passive")
		)
		(pad "G5" smd circle
			(at -1.196 -2.934)
			(size 0.27 0.27)
			(layers "F.Cu" "F.Mask" "F.Paste")
			(net 417 "GND")
			(pinfunction "VSS")
			(pintype "passive")
		)
		(pad "G8" smd circle
			(at 1.205 -2.934)
			(size 0.27 0.27)
			(layers "F.Cu" "F.Mask" "F.Paste")
			(net 417 "GND")
			(pinfunction "VSS")
			(pintype "passive")
		)
		(pad "G9" smd circle
			(at 2.004 -2.934)
			(size 0.27 0.27)
			(layers "F.Cu" "F.Mask" "F.Paste")
			(net 48 "+1V8")
			(pinfunction "VDD1")
			(pintype "passive")
		)
		(pad "G10" smd circle
			(at 2.805 -2.934)
			(size 0.27 0.27)
			(layers "F.Cu" "F.Mask" "F.Paste")
			(net 417 "GND")
			(pinfunction "VSS")
			(pintype "passive")
		)
		(pad "G11" smd circle
			(at 3.604 -2.934)
			(size 0.27 0.27)
			(layers "F.Cu" "F.Mask" "F.Paste")
			(net 491 "unconnected-(U12B-NC-PadG11)")
			(pinfunction "NC")
			(pintype "no_connect")
		)
		(pad "G12" smd circle
			(at 4.405 -2.934)
			(size 0.27 0.27)
			(layers "F.Cu" "F.Mask" "F.Paste")
			(net 417 "GND")
			(pinfunction "VSS")
			(pintype "passive")
		)
		(pad "H1" smd circle
			(at -4.396 -2.283)
			(size 0.27 0.27)
			(layers "F.Cu" "F.Mask" "F.Paste")
			(net 2 "+1V1")
			(pinfunction "VDD2")
			(pintype "passive")
		)
		(pad "H2" smd circle
			(at -3.596 -2.283)
			(size 0.27 0.27)
			(layers "F.Cu" "F.Mask" "F.Paste")
			(net 587 "/FPGA MSS/LPDDR4.CA0_A")
			(pinfunction "CA0_A")
			(pintype "input")
		)
		(pad "H3" smd circle
			(at -2.795 -2.283)
			(size 0.27 0.27)
			(layers "F.Cu" "F.Mask" "F.Paste")
			(net 492 "unconnected-(U12A-NC-PadH3)")
			(pinfunction "NC")
			(pintype "no_connect")
		)
		(pad "H4" smd circle
			(at -1.996 -2.283)
			(size 0.27 0.27)
			(layers "F.Cu" "F.Mask" "F.Paste")
			(net 395 "/FPGA MSS/LPDDR4.CS0_A")
			(pinfunction "CS0_A")
			(pintype "input")
		)
		(pad "H5" smd circle
			(at -1.196 -2.283)
			(size 0.27 0.27)
			(layers "F.Cu" "F.Mask" "F.Paste")
			(net 2 "+1V1")
			(pinfunction "VDD2")
			(pintype "passive")
		)
		(pad "H8" smd circle
			(at 1.205 -2.283)
			(size 0.27 0.27)
			(layers "F.Cu" "F.Mask" "F.Paste")
			(net 2 "+1V1")
			(pinfunction "VDD2")
			(pintype "passive")
		)
		(pad "H9" smd circle
			(at 2.004 -2.283)
			(size 0.27 0.27)
			(layers "F.Cu" "F.Mask" "F.Paste")
			(net 598 "/FPGA MSS/LPDDR4.CA2_A")
			(pinfunction "CA2_A")
			(pintype "input")
		)
		(pad "H10" smd circle
			(at 2.805 -2.283)
			(size 0.27 0.27)
			(layers "F.Cu" "F.Mask" "F.Paste")
			(net 597 "/FPGA MSS/LPDDR4.CA3_A")
			(pinfunction "CA3_A")
			(pintype "input")
		)
		(pad "H11" smd circle
			(at 3.604 -2.283)
			(size 0.27 0.27)
			(layers "F.Cu" "F.Mask" "F.Paste")
			(net 583 "/FPGA MSS/LPDDR4.CA4_A")
			(pinfunction "CA4_A")
			(pintype "input")
		)
		(pad "H12" smd circle
			(at 4.405 -2.283)
			(size 0.27 0.27)
			(layers "F.Cu" "F.Mask" "F.Paste")
			(net 2 "+1V1")
			(pinfunction "VDD2")
			(pintype "passive")
		)
		(pad "J1" smd circle
			(at -4.396 -1.633)
			(size 0.27 0.27)
			(layers "F.Cu" "F.Mask" "F.Paste")
			(net 417 "GND")
			(pinfunction "VSS")
			(pintype "passive")
		)
		(pad "J2" smd circle
			(at -3.596 -1.633)
			(size 0.27 0.27)
			(layers "F.Cu" "F.Mask" "F.Paste")
			(net 588 "/FPGA MSS/LPDDR4.CA1_A")
			(pinfunction "CA1_A")
			(pintype "input")
		)
		(pad "J3" smd circle
			(at -2.795 -1.633)
			(size 0.27 0.27)
			(layers "F.Cu" "F.Mask" "F.Paste")
			(net 417 "GND")
			(pinfunction "VSS")
			(pintype "passive")
		)
		(pad "J4" smd circle
			(at -1.996 -1.633)
			(size 0.27 0.27)
			(layers "F.Cu" "F.Mask" "F.Paste")
			(net 389 "/FPGA MSS/LPDDR4.CKE0_A")
			(pinfunction "CKE0_A")
			(pintype "input")
		)
		(pad "J5" smd circle
			(at -1.196 -1.633)
			(size 0.27 0.27)
			(layers "F.Cu" "F.Mask" "F.Paste")
			(net 536 "unconnected-(U12A-NC-PadJ5)")
			(pinfunction "NC")
			(pintype "no_connect")
		)
		(pad "J8" smd circle
			(at 1.205 -1.633)
			(size 0.27 0.27)
			(layers "F.Cu" "F.Mask" "F.Paste")
			(net 593 "/FPGA MSS/LPDDR4.CK_P")
			(pinfunction "CK_t_A")
			(pintype "input")
		)
		(pad "J9" smd circle
			(at 2.004 -1.633)
			(size 0.27 0.27)
			(layers "F.Cu" "F.Mask" "F.Paste")
			(net 592 "/FPGA MSS/LPDDR4.CK_N")
			(pinfunction "CK_c_A")
			(pintype "input")
		)
		(pad "J10" smd circle
			(at 2.805 -1.633)
			(size 0.27 0.27)
			(layers "F.Cu" "F.Mask" "F.Paste")
			(net 417 "GND")
			(pinfunction "VSS")
			(pintype "passive")
		)
		(pad "J11" smd circle
			(at 3.604 -1.633)
			(size 0.27 0.27)
			(layers "F.Cu" "F.Mask" "F.Paste")
			(net 568 "/FPGA MSS/LPDDR4.CA5_A")
			(pinfunction "CA5_A")
			(pintype "input")
		)
		(pad "J12" smd circle
			(at 4.405 -1.633)
			(size 0.27 0.27)
			(layers "F.Cu" "F.Mask" "F.Paste")
			(net 417 "GND")
			(pinfunction "VSS")
			(pintype "passive")
		)
		(pad "K1" smd circle
			(at -4.396 -0.983)
			(size 0.27 0.27)
			(layers "F.Cu" "F.Mask" "F.Paste")
			(net 2 "+1V1")
			(pinfunction "VDD2")
			(pintype "passive")
		)
		(pad "K2" smd circle
			(at -3.596 -0.983)
			(size 0.27 0.27)
			(layers "F.Cu" "F.Mask" "F.Paste")
			(net 417 "GND")
			(pinfunction "VSS")
			(pintype "passive")
		)
		(pad "K3" smd circle
			(at -2.795 -0.983)
			(size 0.27 0.27)
			(layers "F.Cu" "F.Mask" "F.Paste")
			(net 2 "+1V1")
			(pinfunction "VDD2")
			(pintype "passive")
		)
		(pad "K4" smd circle
			(at -1.996 -0.983)
			(size 0.27 0.27)
			(layers "F.Cu" "F.Mask" "F.Paste")
			(net 417 "GND")
			(pinfunction "VSS")
			(pintype "passive")
		)
		(pad "K5" smd circle
			(at -1.196 -0.983)
			(size 0.27 0.27)
			(layers "F.Cu" "F.Mask" "F.Paste")
			(net 493 "unconnected-(U12A-NC-PadK5)")
			(pinfunction "NC")
			(pintype "no_connect")
		)
		(pad "K8" smd circle
			(at 1.205 -0.983)
			(size 0.27 0.27)
			(layers "F.Cu" "F.Mask" "F.Paste")
			(net 494 "unconnected-(U12A-NC-PadK8)")
			(pinfunction "NC")
			(pintype "no_connect")
		)
		(pad "K9" smd circle
			(at 2.004 -0.983)
			(size 0.27 0.27)
			(layers "F.Cu" "F.Mask" "F.Paste")
			(net 417 "GND")
			(pinfunction "VSS")
			(pintype "passive")
		)
		(pad "K10" smd circle
			(at 2.805 -0.983)
			(size 0.27 0.27)
			(layers "F.Cu" "F.Mask" "F.Paste")
			(net 2 "+1V1")
			(pinfunction "VDD2")
			(pintype "passive")
		)
		(pad "K11" smd circle
			(at 3.604 -0.983)
			(size 0.27 0.27)
			(layers "F.Cu" "F.Mask" "F.Paste")
			(net 417 "GND")
			(pinfunction "VSS")
			(pintype "passive")
		)
		(pad "K12" smd circle
			(at 4.405 -0.983)
			(size 0.27 0.27)
			(layers "F.Cu" "F.Mask" "F.Paste")
			(net 2 "+1V1")
			(pinfunction "VDD2")
			(pintype "passive")
		)
		(pad "N1" smd circle
			(at -4.396 0.966)
			(size 0.27 0.27)
			(layers "F.Cu" "F.Mask" "F.Paste")
			(net 2 "+1V1")
			(pinfunction "VDD2")
			(pintype "passive")
		)
		(pad "N2" smd circle
			(at -3.596 0.966)
			(size 0.27 0.27)
			(layers "F.Cu" "F.Mask" "F.Paste")
			(net 417 "GND")
			(pinfunction "VSS")
			(pintype "passive")
		)
		(pad "N3" smd circle
			(at -2.795 0.966)
			(size 0.27 0.27)
			(layers "F.Cu" "F.Mask" "F.Paste")
			(net 2 "+1V1")
			(pinfunction "VDD2")
			(pintype "passive")
		)
		(pad "N4" smd circle
			(at -1.996 0.966)
			(size 0.27 0.27)
			(layers "F.Cu" "F.Mask" "F.Paste")
			(net 417 "GND")
			(pinfunction "VSS")
			(pintype "passive")
		)
		(pad "N5" smd circle
			(at -1.196 0.966)
			(size 0.27 0.27)
			(layers "F.Cu" "F.Mask" "F.Paste")
			(net 495 "unconnected-(U12A-NC-PadN5)")
			(pinfunction "NC")
			(pintype "no_connect")
		)
		(pad "N8" smd circle
			(at 1.205 0.966)
			(size 0.27 0.27)
			(layers "F.Cu" "F.Mask" "F.Paste")
			(net 496 "unconnected-(U12A-NC-PadN8)")
			(pinfunction "NC")
			(pintype "no_connect")
		)
		(pad "N9" smd circle
			(at 2.004 0.966)
			(size 0.27 0.27)
			(layers "F.Cu" "F.Mask" "F.Paste")
			(net 417 "GND")
			(pinfunction "VSS")
			(pintype "passive")
		)
		(pad "N10" smd circle
			(at 2.805 0.966)
			(size 0.27 0.27)
			(layers "F.Cu" "F.Mask" "F.Paste")
			(net 2 "+1V1")
			(pinfunction "VDD2")
			(pintype "passive")
		)
		(pad "N11" smd circle
			(at 3.604 0.966)
			(size 0.27 0.27)
			(layers "F.Cu" "F.Mask" "F.Paste")
			(net 417 "GND")
			(pinfunction "VSS")
			(pintype "passive")
		)
		(pad "N12" smd circle
			(at 4.405 0.966)
			(size 0.27 0.27)
			(layers "F.Cu" "F.Mask" "F.Paste")
			(net 2 "+1V1")
			(pinfunction "VDD2")
			(pintype "passive")
		)
		(pad "P1" smd circle
			(at -4.396 1.616)
			(size 0.27 0.27)
			(layers "F.Cu" "F.Mask" "F.Paste")
			(net 417 "GND")
			(pinfunction "VSS")
			(pintype "passive")
		)
		(pad "P2" smd circle
			(at -3.596 1.616)
			(size 0.27 0.27)
			(layers "F.Cu" "F.Mask" "F.Paste")
			(net 588 "/FPGA MSS/LPDDR4.CA1_A")
			(pinfunction "CA1_B")
			(pintype "input")
		)
		(pad "P3" smd circle
			(at -2.795 1.616)
			(size 0.27 0.27)
			(layers "F.Cu" "F.Mask" "F.Paste")
			(net 417 "GND")
			(pinfunction "VSS")
			(pintype "passive")
		)
		(pad "P4" smd circle
			(at -1.996 1.616)
			(size 0.27 0.27)
			(layers "F.Cu" "F.Mask" "F.Paste")
			(net 389 "/FPGA MSS/LPDDR4.CKE0_A")
			(pinfunction "CKE0_B")
			(pintype "input")
		)
		(pad "P5" smd circle
			(at -1.196 1.616)
			(size 0.27 0.27)
			(layers "F.Cu" "F.Mask" "F.Paste")
			(net 535 "unconnected-(U12A-NC-PadP5)")
			(pinfunction "NC")
			(pintype "no_connect")
		)
		(pad "P8" smd circle
			(at 1.205 1.616)
			(size 0.27 0.27)
			(layers "F.Cu" "F.Mask" "F.Paste")
			(net 593 "/FPGA MSS/LPDDR4.CK_P")
			(pinfunction "CK_t_B")
			(pintype "input")
		)
		(pad "P9" smd circle
			(at 2.004 1.616)
			(size 0.27 0.27)
			(layers "F.Cu" "F.Mask" "F.Paste")
			(net 592 "/FPGA MSS/LPDDR4.CK_N")
			(pinfunction "CK_c_B")
			(pintype "input")
		)
		(pad "P10" smd circle
			(at 2.805 1.616)
			(size 0.27 0.27)
			(layers "F.Cu" "F.Mask" "F.Paste")
			(net 417 "GND")
			(pinfunction "VSS")
			(pintype "passive")
		)
		(pad "P11" smd circle
			(at 3.604 1.616)
			(size 0.27 0.27)
			(layers "F.Cu" "F.Mask" "F.Paste")
			(net 568 "/FPGA MSS/LPDDR4.CA5_A")
			(pinfunction "CA5_B")
			(pintype "input")
		)
		(pad "P12" smd circle
			(at 4.405 1.616)
			(size 0.27 0.27)
			(layers "F.Cu" "F.Mask" "F.Paste")
			(net 417 "GND")
			(pinfunction "VSS")
			(pintype "passive")
		)
		(pad "R1" smd circle
			(at -4.396 2.266)
			(size 0.27 0.27)
			(layers "F.Cu" "F.Mask" "F.Paste")
			(net 2 "+1V1")
			(pinfunction "VDD2")
			(pintype "passive")
		)
		(pad "R2" smd circle
			(at -3.596 2.266)
			(size 0.27 0.27)
			(layers "F.Cu" "F.Mask" "F.Paste")
			(net 587 "/FPGA MSS/LPDDR4.CA0_A")
			(pinfunction "CA0_B")
			(pintype "input")
		)
		(pad "R3" smd circle
			(at -2.795 2.266)
			(size 0.27 0.27)
			(layers "F.Cu" "F.Mask" "F.Paste")
			(net 497 "unconnected-(U12A-NC-PadR3)")
			(pinfunction "NC")
			(pintype "no_connect")
		)
		(pad "R4" smd circle
			(at -1.996 2.266)
			(size 0.27 0.27)
			(layers "F.Cu" "F.Mask" "F.Paste")
			(net 395 "/FPGA MSS/LPDDR4.CS0_A")
			(pinfunction "CS0_B")
			(pintype "input")
		)
		(pad "R5" smd circle
			(at -1.196 2.266)
			(size 0.27 0.27)
			(layers "F.Cu" "F.Mask" "F.Paste")
			(net 2 "+1V1")
			(pinfunction "VDD2")
			(pintype "passive")
		)
		(pad "R8" smd circle
			(at 1.205 2.266)
			(size 0.27 0.27)
			(layers "F.Cu" "F.Mask" "F.Paste")
			(net 2 "+1V1")
			(pinfunction "VDD2")
			(pintype "passive")
		)
		(pad "R9" smd circle
			(at 2.004 2.266)
			(size 0.27 0.27)
			(layers "F.Cu" "F.Mask" "F.Paste")
			(net 598 "/FPGA MSS/LPDDR4.CA2_A")
			(pinfunction "CA2_B")
			(pintype "input")
		)
		(pad "R10" smd circle
			(at 2.805 2.266)
			(size 0.27 0.27)
			(layers "F.Cu" "F.Mask" "F.Paste")
			(net 597 "/FPGA MSS/LPDDR4.CA3_A")
			(pinfunction "CA3_B")
			(pintype "input")
		)
		(pad "R11" smd circle
			(at 3.604 2.266)
			(size 0.27 0.27)
			(layers "F.Cu" "F.Mask" "F.Paste")
			(net 583 "/FPGA MSS/LPDDR4.CA4_A")
			(pinfunction "CA4_B")
			(pintype "input")
		)
		(pad "R12" smd circle
			(at 4.405 2.266)
			(size 0.27 0.27)
			(layers "F.Cu" "F.Mask" "F.Paste")
			(net 2 "+1V1")
			(pinfunction "VDD2")
			(pintype "passive")
		)
		(pad "T1" smd circle
			(at -4.396 2.917)
			(size 0.27 0.27)
			(layers "F.Cu" "F.Mask" "F.Paste")
			(net 417 "GND")
			(pinfunction "VSS")
			(pintype "passive")
		)
		(pad "T2" smd circle
			(at -3.596 2.917)
			(size 0.27 0.27)
			(layers "F.Cu" "F.Mask" "F.Paste")
			(net 393 "/FPGA MSS/LPDDR4.ODT_CA_A")
			(pinfunction "ODT_CA_B")
			(pintype "input")
		)
		(pad "T3" smd circle
			(at -2.795 2.917)
			(size 0.27 0.27)
			(layers "F.Cu" "F.Mask" "F.Paste")
			(net 417 "GND")
			(pinfunction "VSS")
			(pintype "passive")
		)
		(pad "T4" smd circle
			(at -1.996 2.917)
			(size 0.27 0.27)
			(layers "F.Cu" "F.Mask" "F.Paste")
			(net 48 "+1V8")
			(pinfunction "VDD1")
			(pintype "passive")
		)
		(pad "T5" smd circle
			(at -1.196 2.917)
			(size 0.27 0.27)
			(layers "F.Cu" "F.Mask" "F.Paste")
			(net 417 "GND")
			(pinfunction "VSS")
			(pintype "passive")
		)
		(pad "T8" smd circle
			(at 1.205 2.917)
			(size 0.27 0.27)
			(layers "F.Cu" "F.Mask" "F.Paste")
			(net 417 "GND")
			(pinfunction "VSS")
			(pintype "passive")
		)
		(pad "T9" smd circle
			(at 2.004 2.917)
			(size 0.27 0.27)
			(layers "F.Cu" "F.Mask" "F.Paste")
			(net 48 "+1V8")
			(pinfunction "VDD1")
			(pintype "passive")
		)
		(pad "T10" smd circle
			(at 2.805 2.917)
			(size 0.27 0.27)
			(layers "F.Cu" "F.Mask" "F.Paste")
			(net 417 "GND")
			(pinfunction "VSS")
			(pintype "passive")
		)
		(pad "T11" smd circle
			(at 3.604 2.917)
			(size 0.27 0.27)
			(layers "F.Cu" "F.Mask" "F.Paste")
			(net 394 "/FPGA MSS/LPDDR4.RESET_n")
			(pinfunction "RESET_n")
			(pintype "input")
		)
		(pad "T12" smd circle
			(at 4.405 2.917)
			(size 0.27 0.27)
			(layers "F.Cu" "F.Mask" "F.Paste")
			(net 417 "GND")
			(pinfunction "VSS")
			(pintype "passive")
		)
		(pad "U1" smd circle
			(at -4.396 3.567)
			(size 0.27 0.27)
			(layers "F.Cu" "F.Mask" "F.Paste")
			(net 48 "+1V8")
			(pinfunction "VDD1")
			(pintype "passive")
		)
		(pad "U2" smd circle
			(at -3.596 3.567)
			(size 0.27 0.27)
			(layers "F.Cu" "F.Mask" "F.Paste")
			(net 326 "/FPGA MSS/LPDDR4.DQ19")
			(pinfunction "DQ3_B")
			(pintype "bidirectional")
		)
		(pad "U3" smd circle
			(at -2.795 3.567)
			(size 0.27 0.27)
			(layers "F.Cu" "F.Mask" "F.Paste")
			(net 2 "+1V1")
			(pinfunction "VDDQ")
			(pintype "passive")
		)
		(pad "U4" smd circle
			(at -1.996 3.567)
			(size 0.27 0.27)
			(layers "F.Cu" "F.Mask" "F.Paste")
			(net 601 "/FPGA MSS/LPDDR4.DQ20")
			(pinfunction "DQ4_B")
			(pintype "bidirectional")
		)
		(pad "U5" smd circle
			(at -1.196 3.567)
			(size 0.27 0.27)
			(layers "F.Cu" "F.Mask" "F.Paste")
			(net 2 "+1V1")
			(pinfunction "VDD2")
			(pintype "passive")
		)
		(pad "U8" smd circle
			(at 1.205 3.567)
			(size 0.27 0.27)
			(layers "F.Cu" "F.Mask" "F.Paste")
			(net 2 "+1V1")
			(pinfunction "VDD2")
			(pintype "passive")
		)
		(pad "U9" smd circle
			(at 2.004 3.567)
			(size 0.27 0.27)
			(layers "F.Cu" "F.Mask" "F.Paste")
			(net 586 "/FPGA MSS/LPDDR4.DQ28")
			(pinfunction "DQ12_B")
			(pintype "bidirectional")
		)
		(pad "U10" smd circle
			(at 2.805 3.567)
			(size 0.27 0.27)
			(layers "F.Cu" "F.Mask" "F.Paste")
			(net 2 "+1V1")
			(pinfunction "VDDQ")
			(pintype "passive")
		)
		(pad "U11" smd circle
			(at 3.604 3.567)
			(size 0.27 0.27)
			(layers "F.Cu" "F.Mask" "F.Paste")
			(net 596 "/FPGA MSS/LPDDR4.DQ27")
			(pinfunction "DQ11_B")
			(pintype "bidirectional")
		)
		(pad "U12" smd circle
			(at 4.405 3.567)
			(size 0.27 0.27)
			(layers "F.Cu" "F.Mask" "F.Paste")
			(net 48 "+1V8")
			(pinfunction "VDD1")
			(pintype "passive")
		)
		(pad "V1" smd circle
			(at -4.396 4.217)
			(size 0.27 0.27)
			(layers "F.Cu" "F.Mask" "F.Paste")
			(net 417 "GND")
			(pinfunction "VSS")
			(pintype "passive")
		)
		(pad "V2" smd circle
			(at -3.596 4.217)
			(size 0.27 0.27)
			(layers "F.Cu" "F.Mask" "F.Paste")
			(net 324 "/FPGA MSS/LPDDR4.DQ18")
			(pinfunction "DQ2_B")
			(pintype "bidirectional")
		)
		(pad "V3" smd circle
			(at -2.795 4.217)
			(size 0.27 0.27)
			(layers "F.Cu" "F.Mask" "F.Paste")
			(net 312 "/FPGA MSS/LPDDR4.DQS2_N")
			(pinfunction "DQS0_c_B")
			(pintype "bidirectional")
		)
		(pad "V4" smd circle
			(at -1.996 4.217)
			(size 0.27 0.27)
			(layers "F.Cu" "F.Mask" "F.Paste")
			(net 600 "/FPGA MSS/LPDDR4.DQ21")
			(pinfunction "DQ5_B")
			(pintype "bidirectional")
		)
		(pad "V5" smd circle
			(at -1.196 4.217)
			(size 0.27 0.27)
			(layers "F.Cu" "F.Mask" "F.Paste")
			(net 417 "GND")
			(pinfunction "VSS")
			(pintype "passive")
		)
		(pad "V8" smd circle
			(at 1.205 4.217)
			(size 0.27 0.27)
			(layers "F.Cu" "F.Mask" "F.Paste")
			(net 417 "GND")
			(pinfunction "VSS")
			(pintype "passive")
		)
		(pad "V9" smd circle
			(at 2.004 4.217)
			(size 0.27 0.27)
			(layers "F.Cu" "F.Mask" "F.Paste")
			(net 585 "/FPGA MSS/LPDDR4.DQ29")
			(pinfunction "DQ13_B")
			(pintype "bidirectional")
		)
		(pad "V10" smd circle
			(at 2.805 4.217)
			(size 0.27 0.27)
			(layers "F.Cu" "F.Mask" "F.Paste")
			(net 599 "/FPGA MSS/LPDDR4.DQS3_N")
			(pinfunction "DQS1_c_B")
			(pintype "bidirectional")
		)
		(pad "V11" smd circle
			(at 3.604 4.217)
			(size 0.27 0.27)
			(layers "F.Cu" "F.Mask" "F.Paste")
			(net 591 "/FPGA MSS/LPDDR4.DQ26")
			(pinfunction "DQ10_B")
			(pintype "bidirectional")
		)
		(pad "V12" smd circle
			(at 4.405 4.217)
			(size 0.27 0.27)
			(layers "F.Cu" "F.Mask" "F.Paste")
			(net 417 "GND")
			(pinfunction "VSS")
			(pintype "passive")
		)
		(pad "W1" smd circle
			(at -4.396 4.866)
			(size 0.27 0.27)
			(layers "F.Cu" "F.Mask" "F.Paste")
			(net 2 "+1V1")
			(pinfunction "VDDQ")
			(pintype "passive")
		)
		(pad "W2" smd circle
			(at -3.596 4.866)
			(size 0.27 0.27)
			(layers "F.Cu" "F.Mask" "F.Paste")
			(net 417 "GND")
			(pinfunction "VSS")
			(pintype "passive")
		)
		(pad "W3" smd circle
			(at -2.795 4.866)
			(size 0.27 0.27)
			(layers "F.Cu" "F.Mask" "F.Paste")
			(net 313 "/FPGA MSS/LPDDR4.DQS2_P")
			(pinfunction "DQS0_t_B")
			(pintype "bidirectional")
		)
		(pad "W4" smd circle
			(at -1.996 4.866)
			(size 0.27 0.27)
			(layers "F.Cu" "F.Mask" "F.Paste")
			(net 417 "GND")
			(pinfunction "VSS")
			(pintype "passive")
		)
		(pad "W5" smd circle
			(at -1.196 4.866)
			(size 0.27 0.27)
			(layers "F.Cu" "F.Mask" "F.Paste")
			(net 2 "+1V1")
			(pinfunction "VDDQ")
			(pintype "passive")
		)
		(pad "W8" smd circle
			(at 1.205 4.866)
			(size 0.27 0.27)
			(layers "F.Cu" "F.Mask" "F.Paste")
			(net 2 "+1V1")
			(pinfunction "VDDQ")
			(pintype "passive")
		)
		(pad "W9" smd circle
			(at 2.004 4.866)
			(size 0.27 0.27)
			(layers "F.Cu" "F.Mask" "F.Paste")
			(net 417 "GND")
			(pinfunction "VSS")
			(pintype "passive")
		)
		(pad "W10" smd circle
			(at 2.805 4.866)
			(size 0.27 0.27)
			(layers "F.Cu" "F.Mask" "F.Paste")
			(net 595 "/FPGA MSS/LPDDR4.DQS3_P")
			(pinfunction "DQS1_t_B")
			(pintype "bidirectional")
		)
		(pad "W11" smd circle
			(at 3.604 4.866)
			(size 0.27 0.27)
			(layers "F.Cu" "F.Mask" "F.Paste")
			(net 417 "GND")
			(pinfunction "VSS")
			(pintype "passive")
		)
		(pad "W12" smd circle
			(at 4.405 4.866)
			(size 0.27 0.27)
			(layers "F.Cu" "F.Mask" "F.Paste")
			(net 2 "+1V1")
			(pinfunction "VDDQ")
			(pintype "passive")
		)
		(pad "Y1" smd circle
			(at -4.396 5.517)
			(size 0.27 0.27)
			(layers "F.Cu" "F.Mask" "F.Paste")
			(net 417 "GND")
			(pinfunction "VSS")
			(pintype "passive")
		)
		(pad "Y2" smd circle
			(at -3.596 5.517)
			(size 0.27 0.27)
			(layers "F.Cu" "F.Mask" "F.Paste")
			(net 605 "/FPGA MSS/LPDDR4.DQ17")
			(pinfunction "DQ1_B")
			(pintype "bidirectional")
		)
		(pad "Y3" smd circle
			(at -2.795 5.517)
			(size 0.27 0.27)
			(layers "F.Cu" "F.Mask" "F.Paste")
			(net 614 "/FPGA MSS/LPDDR4.DMI2")
			(pinfunction "DMI0_B")
			(pintype "bidirectional")
		)
		(pad "Y4" smd circle
			(at -1.996 5.517)
			(size 0.27 0.27)
			(layers "F.Cu" "F.Mask" "F.Paste")
			(net 615 "/FPGA MSS/LPDDR4.DQ22")
			(pinfunction "DQ6_B")
			(pintype "bidirectional")
		)
		(pad "Y5" smd circle
			(at -1.196 5.517)
			(size 0.27 0.27)
			(layers "F.Cu" "F.Mask" "F.Paste")
			(net 417 "GND")
			(pinfunction "VSS")
			(pintype "passive")
		)
		(pad "Y8" smd circle
			(at 1.205 5.517)
			(size 0.27 0.27)
			(layers "F.Cu" "F.Mask" "F.Paste")
			(net 417 "GND")
			(pinfunction "VSS")
			(pintype "passive")
		)
		(pad "Y9" smd circle
			(at 2.004 5.517)
			(size 0.27 0.27)
			(layers "F.Cu" "F.Mask" "F.Paste")
			(net 584 "/FPGA MSS/LPDDR4.DQ30")
			(pinfunction "DQ14_B")
			(pintype "bidirectional")
		)
		(pad "Y10" smd circle
			(at 2.805 5.517)
			(size 0.27 0.27)
			(layers "F.Cu" "F.Mask" "F.Paste")
			(net 590 "/FPGA MSS/LPDDR4.DMI3")
			(pinfunction "DMI1_B")
			(pintype "bidirectional")
		)
		(pad "Y11" smd circle
			(at 3.604 5.517)
			(size 0.27 0.27)
			(layers "F.Cu" "F.Mask" "F.Paste")
			(net 589 "/FPGA MSS/LPDDR4.DQ25")
			(pinfunction "DQ9_B")
			(pintype "bidirectional")
		)
		(pad "Y12" smd circle
			(at 4.405 5.517)
			(size 0.27 0.27)
			(layers "F.Cu" "F.Mask" "F.Paste")
			(net 417 "GND")
			(pinfunction "VSS")
			(pintype "passive")
		)
	)
	(footprint "antmicro-footprints:TP_SMD_0.75mm"
		(layer "F.Cu")
		(at 228.47 145.275)
		(property "Reference" "TP30"
			(at 9.74 1.515 0)
			(layer "F.SilkS")
			(hide yes)
			(effects
				(font
					(size 0.7 0.7)
					(thickness 0.15)
				)
				(justify left bottom)
			)
		)
		(property "Value" "TP_0.75mm_SMD"
			(at 0 1.2 0)
			(layer "F.Fab")
			(hide yes)
			(effects
				(font
					(size 0.7 0.7)
					(thickness 0.15)
				)
				(justify left bottom)
			)
		)
		(property "Description" "SMT test point"
			(at 0 0 0)
			(layer "F.Fab")
			(hide yes)
			(effects
				(font
					(size 1.27 1.27)
					(thickness 0.15)
				)
			)
		)
		(property "Author" "Antmicro"
			(at 0 0 0)
			(layer "F.Fab")
			(hide yes)
			(effects
				(font
					(size 1 1)
					(thickness 0.15)
				)
			)
		)
		(property "License" "Apache-2.0"
			(at 0 0 0)
			(layer "F.Fab")
			(hide yes)
			(effects
				(font
					(size 1 1)
					(thickness 0.15)
				)
			)
		)
		(property "MPN" ""
			(at 0 0 0)
			(layer "F.Fab")
			(hide yes)
			(effects
				(font
					(size 1 1)
					(thickness 0.15)
				)
			)
		)
		(property "Manufacturer" ""
			(at 0 0 0)
			(layer "F.Fab")
			(hide yes)
			(effects
				(font
					(size 1 1)
					(thickness 0.15)
				)
			)
		)
		(property "Public" "False"
			(at 0 0 0)
			(layer "F.Fab")
			(hide yes)
			(effects
				(font
					(size 1 1)
					(thickness 0.15)
				)
			)
		)
		(sheetname "/WiFi_Bluetooth/")
		(sheetfile "wifi_bt.kicad_sch")
		(attr exclude_from_pos_files exclude_from_bom)
		(fp_circle
			(center 0 0)
			(end 0.475 0)
			(stroke
				(width 0.05)
				(type default)
			)
			(fill no)
			(layer "F.CrtYd")
		)
		(fp_text user "License: Apache-2.0"
			(at -0.4 5.101 0)
			(layer "F.Fab")
			(effects
				(font
					(size 0.7 0.7)
					(thickness 0.15)
				)
				(justify left bottom)
			)
		)
		(fp_text user "${REFERENCE}"
			(at -0.4 2.7 0)
			(layer "F.Fab")
			(effects
				(font
					(size 0.7 0.7)
					(thickness 0.15)
				)
				(justify left bottom)
			)
		)
		(fp_text user "Author: Antmicro"
			(at -0.4 3.901 0)
			(layer "F.Fab")
			(effects
				(font
					(size 0.7 0.7)
					(thickness 0.15)
				)
				(justify left bottom)
			)
		)
		(pad "1" smd circle
			(at 0 0)
			(size 0.75 0.75)
			(layers "F.Cu" "F.Mask")
			(net 527 "Net-(U26A-BT_GPIO_2)")
			(pinfunction "1")
			(pintype "passive")
		)
	)
	(footprint "antmicro-footprints:TP_SMD_0.75mm"
		(layer "F.Cu")
		(at 227.2 145.91)
		(property "Reference" "TP29"
			(at 10.39 1.84 0)
			(layer "F.SilkS")
			(hide yes)
			(effects
				(font
					(size 0.7 0.7)
					(thickness 0.15)
				)
				(justify left bottom)
			)
		)
		(property "Value" "TP_0.75mm_SMD"
			(at 0 1.2 0)
			(layer "F.Fab")
			(hide yes)
			(effects
				(font
					(size 0.7 0.7)
					(thickness 0.15)
				)
				(justify left bottom)
			)
		)
		(property "Description" "SMT test point"
			(at 0 0 0)
			(layer "F.Fab")
			(hide yes)
			(effects
				(font
					(size 1.27 1.27)
					(thickness 0.15)
				)
			)
		)
		(property "Author" "Antmicro"
			(at 0 0 0)
			(layer "F.Fab")
			(hide yes)
			(effects
				(font
					(size 1 1)
					(thickness 0.15)
				)
			)
		)
		(property "License" "Apache-2.0"
			(at 0 0 0)
			(layer "F.Fab")
			(hide yes)
			(effects
				(font
					(size 1 1)
					(thickness 0.15)
				)
			)
		)
		(property "MPN" ""
			(at 0 0 0)
			(layer "F.Fab")
			(hide yes)
			(effects
				(font
					(size 1 1)
					(thickness 0.15)
				)
			)
		)
		(property "Manufacturer" ""
			(at 0 0 0)
			(layer "F.Fab")
			(hide yes)
			(effects
				(font
					(size 1 1)
					(thickness 0.15)
				)
			)
		)
		(property "Public" "False"
			(at 0 0 0)
			(layer "F.Fab")
			(hide yes)
			(effects
				(font
					(size 1 1)
					(thickness 0.15)
				)
			)
		)
		(sheetname "/WiFi_Bluetooth/")
		(sheetfile "wifi_bt.kicad_sch")
		(attr exclude_from_pos_files exclude_from_bom)
		(fp_circle
			(center 0 0)
			(end 0.475 0)
			(stroke
				(width 0.05)
				(type default)
			)
			(fill no)
			(layer "F.CrtYd")
		)
		(fp_text user "Author: Antmicro"
			(at -0.4 3.901 0)
			(layer "F.Fab")
			(effects
				(font
					(size 0.7 0.7)
					(thickness 0.15)
				)
				(justify left bottom)
			)
		)
		(fp_text user "${REFERENCE}"
			(at -0.4 2.7 0)
			(layer "F.Fab")
			(effects
				(font
					(size 0.7 0.7)
					(thickness 0.15)
				)
				(justify left bottom)
			)
		)
		(fp_text user "License: Apache-2.0"
			(at -0.4 5.101 0)
			(layer "F.Fab")
			(effects
				(font
					(size 0.7 0.7)
					(thickness 0.15)
				)
				(justify left bottom)
			)
		)
		(pad "1" smd circle
			(at 0 0)
			(size 0.75 0.75)
			(layers "F.Cu" "F.Mask")
			(net 526 "Net-(U26A-BT_HOST_WAKE)")
			(pinfunction "1")
			(pintype "passive")
		)
	)
	(footprint "antmicro-footprints:Oscillator_SMD_ECS_2520MV_2.5x2mm"
		(layer "F.Cu")
		(at 219.6 150.05 90)
		(descr "Miniature Crystal Clock Oscillator ECS 2520MV series")
		(tags "Crystal Clock Oscillator ECS 2520MV SMD")
		(property "Reference" "Y4"
			(at -0.05 2.4 90)
			(layer "F.SilkS")
			(effects
				(font
					(size 0.7 0.7)
					(thickness 0.15)
				)
				(justify left bottom)
			)
		)
		(property "Value" "Oscillator_32.768kHz_ECS_2520MV"
			(at 0 2.499 90)
			(layer "F.Fab")
			(hide yes)
			(effects
				(font
					(size 0.7 0.7)
					(thickness 0.15)
				)
				(justify left bottom)
			)
		)
		(property "Datasheet" "https://ecsxtal.com/store/pdf/ECS-327MVATX.pdf"
			(at 0 0 90)
			(layer "F.Fab")
			(hide yes)
			(effects
				(font
					(size 1.27 1.27)
					(thickness 0.15)
				)
			)
		)
		(property "Description" "32.768 kHz XO (Standard) CMOS Oscillator 1.6V ~ 3.6V Enable/Disable 4-SMD, No Lead"
			(at 0 0 90)
			(layer "F.Fab")
			(hide yes)
			(effects
				(font
					(size 1.27 1.27)
					(thickness 0.15)
				)
			)
		)
		(property "Author" "Antmicro"
			(at 369.65 -69.55 0)
			(layer "F.Fab")
			(hide yes)
			(effects
				(font
					(size 1 1)
					(thickness 0.15)
				)
			)
		)
		(property "License" "Apache-2.0"
			(at 369.65 -69.55 0)
			(layer "F.Fab")
			(hide yes)
			(effects
				(font
					(size 1 1)
					(thickness 0.15)
				)
			)
		)
		(property "MPN" "ECS-327MVATX-2-CN-TR3"
			(at 369.65 -69.55 0)
			(layer "F.Fab")
			(hide yes)
			(effects
				(font
					(size 1 1)
					(thickness 0.15)
				)
			)
		)
		(property "Manufacturer" "ECS Inc. International"
			(at 369.65 -69.55 0)
			(layer "F.Fab")
			(hide yes)
			(effects
				(font
					(size 1 1)
					(thickness 0.15)
				)
			)
		)
		(property "Public" ""
			(at 369.65 -69.55 0)
			(layer "F.Fab")
			(hide yes)
			(effects
				(font
					(size 1 1)
					(thickness 0.15)
				)
			)
		)
		(property "Val" "32.768 kHz"
			(at 369.65 -69.55 0)
			(layer "F.Fab")
			(hide yes)
			(effects
				(font
					(size 1 1)
					(thickness 0.15)
				)
			)
		)
		(sheetname "/WiFi_Bluetooth/")
		(sheetfile "wifi_bt.kicad_sch")
		(attr smd)
		(fp_line
			(start -0.16 -1.361)
			(end 0.17 -1.361)
			(stroke
				(width 0.15)
				(type solid)
			)
			(layer "F.SilkS")
		)
		(fp_line
			(start 1.11 0.32)
			(end 1.11 -0.32)
			(stroke
				(width 0.15)
				(type solid)
			)
			(layer "F.SilkS")
		)
		(fp_line
			(start -1.111 0.32)
			(end -1.111 -0.32)
			(stroke
				(width 0.15)
				(type solid)
			)
			(layer "F.SilkS")
		)
		(fp_line
			(start -0.172 1.36)
			(end 0.17 1.36)
			(stroke
				(width 0.15)
				(type solid)
			)
			(layer "F.SilkS")
		)
		(fp_circle
			(center -1.1 -1.5)
			(end -1.049 -1.5)
			(stroke
				(width 0.15)
				(type solid)
			)
			(fill yes)
			(layer "F.SilkS")
		)
		(fp_rect
			(start -1.25 -1.5)
			(end 1.25 1.5)
			(stroke
				(width 0.05)
				(type solid)
			)
			(fill no)
			(layer "F.CrtYd")
		)
		(fp_line
			(start -1 -0.75)
			(end -0.5 -1.25)
			(stroke
				(width 0.15)
				(type solid)
			)
			(layer "F.Fab")
		)
		(fp_rect
			(start 1 1.249)
			(end -1 -1.25)
			(stroke
				(width 0.15)
				(type solid)
			)
			(fill no)
			(layer "F.Fab")
		)
		(fp_text user "Author: Antmicro"
			(at -1.25 5.102 90)
			(layer "F.Fab")
			(effects
				(font
					(size 0.7 0.7)
					(thickness 0.15)
				)
				(justify left bottom)
			)
		)
		(fp_text user "${REFERENCE}"
			(at -1.25 3.9 90)
			(layer "F.Fab")
			(effects
				(font
					(size 0.7 0.7)
					(thickness 0.15)
				)
				(justify left bottom)
			)
		)
		(fp_text user "License: Apache-2.0"
			(at -1.25 6.302 90)
			(layer "F.Fab")
			(effects
				(font
					(size 0.7 0.7)
					(thickness 0.15)
				)
				(justify left bottom)
			)
		)
		(pad "1" smd roundrect
			(at -0.725 -0.927 90)
			(size 0.8 0.9)
			(layers "F.Cu" "F.Mask" "F.Paste")
			(roundrect_rratio 0.25)
			(net 50 "+3V3")
			(pinfunction "EN")
			(pintype "input")
		)
		(pad "2" smd roundrect
			(at -0.725 0.925 90)
			(size 0.8 0.9)
			(layers "F.Cu" "F.Mask" "F.Paste")
			(roundrect_rratio 0.25)
			(net 417 "GND")
			(pinfunction "GND")
			(pintype "power_in")
		)
		(pad "3" smd roundrect
			(at 0.723 0.925 90)
			(size 0.8 0.9)
			(layers "F.Cu" "F.Mask" "F.Paste")
			(roundrect_rratio 0.25)
			(net 430 "/WiFi_Bluetooth/LPO_IN")
			(pinfunction "OUT")
			(pintype "output")
		)
		(pad "4" smd roundrect
			(at 0.723 -0.927 90)
			(size 0.8 0.9)
			(layers "F.Cu" "F.Mask" "F.Paste")
			(roundrect_rratio 0.25)
			(net 50 "+3V3")
			(pinfunction "VDD")
			(pintype "power_in")
		)
	)
	(footprint "antmicro-footprints:TP_SMD_0.75mm"
		(layer "F.Cu")
		(at 180.72 145.3375 90)
		(property "Reference" "TP34"
			(at 0 -0.6 90)
			(layer "F.SilkS")
			(hide yes)
			(effects
				(font
					(size 0.7 0.7)
					(thickness 0.15)
				)
				(justify left bottom)
			)
		)
		(property "Value" "TP_0.75mm_SMD"
			(at 0 1.2 90)
			(layer "F.Fab")
			(hide yes)
			(effects
				(font
					(size 0.7 0.7)
					(thickness 0.15)
				)
				(justify left bottom)
			)
		)
		(property "Description" "SMT test point"
			(at 0 0 90)
			(layer "F.Fab")
			(hide yes)
			(effects
				(font
					(size 1.27 1.27)
					(thickness 0.15)
				)
			)
		)
		(property "Author" "Antmicro"
			(at 326.0575 -35.3825 0)
			(layer "F.Fab")
			(hide yes)
			(effects
				(font
					(size 1 1)
					(thickness 0.15)
				)
			)
		)
		(property "License" "Apache-2.0"
			(at 326.0575 -35.3825 0)
			(layer "F.Fab")
			(hide yes)
			(effects
				(font
					(size 1 1)
					(thickness 0.15)
				)
			)
		)
		(property "MPN" ""
			(at 326.0575 -35.3825 0)
			(layer "F.Fab")
			(hide yes)
			(effects
				(font
					(size 1 1)
					(thickness 0.15)
				)
			)
		)
		(property "Manufacturer" ""
			(at 326.0575 -35.3825 0)
			(layer "F.Fab")
			(hide yes)
			(effects
				(font
					(size 1 1)
					(thickness 0.15)
				)
			)
		)
		(property "Public" "False"
			(at 326.0575 -35.3825 0)
			(layer "F.Fab")
			(hide yes)
			(effects
				(font
					(size 1 1)
					(thickness 0.15)
				)
			)
		)
		(sheetname "/Supply/")
		(sheetfile "supply.kicad_sch")
		(attr exclude_from_pos_files exclude_from_bom)
		(fp_circle
			(center 0 0)
			(end 0.475 0)
			(stroke
				(width 0.05)
				(type default)
			)
			(fill no)
			(layer "F.CrtYd")
		)
		(fp_text user "License: Apache-2.0"
			(at -0.4 5.101 90)
			(layer "F.Fab")
			(effects
				(font
					(size 0.7 0.7)
					(thickness 0.15)
				)
				(justify left bottom)
			)
		)
		(fp_text user "Author: Antmicro"
			(at -0.4 3.901 90)
			(layer "F.Fab")
			(effects
				(font
					(size 0.7 0.7)
					(thickness 0.15)
				)
				(justify left bottom)
			)
		)
		(fp_text user "${REFERENCE}"
			(at -0.4 2.7 90)
			(layer "F.Fab")
			(effects
				(font
					(size 0.7 0.7)
					(thickness 0.15)
				)
				(justify left bottom)
			)
		)
		(pad "1" smd circle
			(at 0 0 90)
			(size 0.75 0.75)
			(layers "F.Cu" "F.Mask")
			(net 100 "/FPGA MSSIO/SUPPLY.SDA")
			(pinfunction "1")
			(pintype "passive")
		)
	)
	(footprint "antmicro-footprints:4x0R_0402_array_EXB28V"
		(layer "F.Cu")
		(at 193.085 144.45 180)
		(property "Reference" "R108"
			(at -1.265 1.95 0)
			(layer "F.SilkS")
			(effects
				(font
					(size 0.7 0.7)
					(thickness 0.15)
				)
				(justify right top)
			)
		)
		(property "Value" "4x0R_0402_array"
			(at 0.6604 2.8194 0)
			(layer "F.Fab")
			(hide yes)
			(effects
				(font
					(size 0.7 0.7)
					(thickness 0.15)
				)
				(justify right top)
			)
		)
		(property "Datasheet" "https://industrial.panasonic.com/cdbs/www-data/pdf/AOC0000/AOC0000C14.pdf"
			(at 0 0 0)
			(layer "F.Fab")
			(hide yes)
			(effects
				(font
					(size 1.27 1.27)
					(thickness 0.15)
				)
			)
		)
		(property "Description" "Zero Ohm Network Resistor, Jumper, 0402 [1005 Metric], Thick Film, Isolated, Convex, 4 Resistors"
			(at 0 0 0)
			(layer "F.Fab")
			(hide yes)
			(effects
				(font
					(size 1.27 1.27)
					(thickness 0.15)
				)
			)
		)
		(property "MPN" "EXB28VR000X"
			(at 0 0 180)
			(unlocked yes)
			(layer "F.Fab")
			(hide yes)
			(effects
				(font
					(size 1 1)
					(thickness 0.15)
				)
			)
		)
		(property "Manufacturer" "Panasonic"
			(at 0 0 180)
			(unlocked yes)
			(layer "F.Fab")
			(hide yes)
			(effects
				(font
					(size 1 1)
					(thickness 0.15)
				)
			)
		)
		(property "Author" "Antmicro"
			(at 0 0 180)
			(unlocked yes)
			(layer "F.Fab")
			(hide yes)
			(effects
				(font
					(size 1 1)
					(thickness 0.15)
				)
			)
		)
		(property "License" "Apache-2.0"
			(at 0 0 180)
			(unlocked yes)
			(layer "F.Fab")
			(hide yes)
			(effects
				(font
					(size 1 1)
					(thickness 0.15)
				)
			)
		)
		(property "Val" "4x0R_0402"
			(at 0 0 180)
			(unlocked yes)
			(layer "F.Fab")
			(hide yes)
			(effects
				(font
					(size 1 1)
					(thickness 0.15)
				)
			)
		)
		(sheetname "/HDMI/")
		(sheetfile "hdmi.kicad_sch")
		(attr smd)
		(fp_line
			(start 1.15 0.15)
			(end 1.15 -0.15)
			(stroke
				(width 0.15)
				(type solid)
			)
			(layer "F.SilkS")
		)
		(fp_line
			(start -1.15 -0.15)
			(end -1.15 0.15)
			(stroke
				(width 0.15)
				(type solid)
			)
			(layer "F.SilkS")
		)
		(fp_circle
			(center -0.9652 0.9144)
			(end -0.9144 0.9144)
			(stroke
				(width 0.15)
				(type solid)
			)
			(fill no)
			(layer "F.SilkS")
		)
		(fp_line
			(start 1.25 0.8)
			(end 1.25 -0.8)
			(stroke
				(width 0.05)
				(type solid)
			)
			(layer "F.CrtYd")
		)
		(fp_line
			(start 1.25 -0.8)
			(end -1.25 -0.8)
			(stroke
				(width 0.05)
				(type solid)
			)
			(layer "F.CrtYd")
		)
		(fp_line
			(start -1.25 0.8)
			(end 1.25 0.8)
			(stroke
				(width 0.05)
				(type solid)
			)
			(layer "F.CrtYd")
		)
		(fp_line
			(start -1.25 -0.8)
			(end -1.25 0.8)
			(stroke
				(width 0.05)
				(type solid)
			)
			(layer "F.CrtYd")
		)
		(fp_line
			(start 1 0.5)
			(end -1 0.5)
			(stroke
				(width 0.15)
				(type solid)
			)
			(layer "F.Fab")
		)
		(fp_line
			(start 1 -0.5)
			(end 1 0.5)
			(stroke
				(width 0.15)
				(type solid)
			)
			(layer "F.Fab")
		)
		(fp_line
			(start -1 0.5)
			(end -1 -0.5)
			(stroke
				(width 0.15)
				(type solid)
			)
			(layer "F.Fab")
		)
		(fp_line
			(start -1 0)
			(end -0.508 0.5)
			(stroke
				(width 0.15)
				(type solid)
			)
			(layer "F.Fab")
		)
		(fp_line
			(start -1 -0.5)
			(end 1 -0.5)
			(stroke
				(width 0.15)
				(type solid)
			)
			(layer "F.Fab")
		)
		(fp_circle
			(center -0.9652 0.9144)
			(end -0.9144 0.9144)
			(stroke
				(width 0.15)
				(type solid)
			)
			(fill no)
			(layer "F.Fab")
		)
		(fp_text user "License: Apache-2.0"
			(at -1.25 7.2194 0)
			(layer "F.Fab")
			(effects
				(font
					(size 0.7 0.7)
					(thickness 0.15)
				)
				(justify right top)
			)
		)
		(fp_text user "Author: Antmicro"
			(at -1.25 6.0194 0)
			(layer "F.Fab")
			(effects
				(font
					(size 0.7 0.7)
					(thickness 0.15)
				)
				(justify right top)
			)
		)
		(fp_text user "${REFERENCE}"
			(at -1.25 4.8194 0)
			(layer "F.Fab")
			(effects
				(font
					(size 0.7 0.7)
					(thickness 0.15)
				)
				(justify right top)
			)
		)
		(pad "1" smd roundrect
			(at -0.8875 0.45 180)
			(size 0.525 0.5)
			(layers "F.Cu" "F.Mask" "F.Paste")
			(roundrect_rratio 0.25)
			(net 86 "/FPGA GPIO/HDMI_FPGA.TX0_N")
			(pinfunction "R1.1")
			(pintype "passive")
		)
		(pad "2" smd roundrect
			(at -0.25 0.46 180)
			(size 0.25 0.48)
			(layers "F.Cu" "F.Mask" "F.Paste")
			(roundrect_rratio 0.25)
			(net 87 "/FPGA GPIO/HDMI_FPGA.TX0_P")
			(pinfunction "R2.1")
			(pintype "passive")
		)
		(pad "3" smd roundrect
			(at 0.25 0.46 180)
			(size 0.25 0.48)
			(layers "F.Cu" "F.Mask" "F.Paste")
			(roundrect_rratio 0.25)
			(net 88 "/FPGA GPIO/HDMI_FPGA.CLK_N")
			(pinfunction "R3.1")
			(pintype "passive")
		)
		(pad "4" smd roundrect
			(at 0.8875 0.45 180)
			(size 0.525 0.5)
			(layers "F.Cu" "F.Mask" "F.Paste")
			(roundrect_rratio 0.25)
			(net 89 "/FPGA GPIO/HDMI_FPGA.CLK_P")
			(pinfunction "R4.1")
			(pintype "passive")
		)
		(pad "5" smd roundrect
			(at 0.8875 -0.45 180)
			(size 0.525 0.5)
			(layers "F.Cu" "F.Mask" "F.Paste")
			(roundrect_rratio 0.25)
			(net 548 "/HDMI/PI3HDX_C_CLK_P")
			(pinfunction "R4.2")
			(pintype "passive")
		)
		(pad "6" smd roundrect
			(at 0.25 -0.46 180)
			(size 0.25 0.48)
			(layers "F.Cu" "F.Mask" "F.Paste")
			(roundrect_rratio 0.25)
			(net 552 "/HDMI/PI3HDX_C_CLK_N")
			(pinfunction "R3.2")
			(pintype "passive")
		)
		(pad "7" smd roundrect
			(at -0.25 -0.46 180)
			(size 0.25 0.48)
			(layers "F.Cu" "F.Mask" "F.Paste")
			(roundrect_rratio 0.25)
			(net 547 "/HDMI/PI3HDX_C_TX0_P")
			(pinfunction "R2.2")
			(pintype "passive")
		)
		(pad "8" smd roundrect
			(at -0.8875 -0.45 180)
			(size 0.525 0.5)
			(layers "F.Cu" "F.Mask" "F.Paste")
			(roundrect_rratio 0.25)
			(net 551 "/HDMI/PI3HDX_C_TX0_N")
			(pinfunction "R1.2")
			(pintype "passive")
		)
	)
	(footprint "antmicro-footprints:WLCSP-16_2.25x2.17x0.68mm_Layout4x4_P0.5x0.5mm"
		(layer "F.Cu")
		(at 176.7 147.9)
		(property "Reference" "U6"
			(at -1.67 2.13 0)
			(layer "F.SilkS")
			(effects
				(font
					(size 0.7 0.7)
					(thickness 0.15)
				)
				(justify left bottom)
			)
		)
		(property "Value" "PAC1934T_WLCSP"
			(at 2.25 0.75 0)
			(layer "F.Fab")
			(hide yes)
			(effects
				(font
					(size 0.7 0.7)
					(thickness 0.15)
				)
				(justify left bottom)
			)
		)
		(property "Datasheet" "https://www.mouser.com/datasheet/2/268/PAC1931_Family_Data_Sheet_DS20005850E-1519053.pdf"
			(at 0 0 0)
			(layer "F.Fab")
			(hide yes)
			(effects
				(font
					(size 1.27 1.27)
					(thickness 0.15)
				)
			)
		)
		(property "Description" "DC Power/Energy Monitor With Accumulator, Quad High-side current Sensor, 2.7V to 5.5V, WLCSP-16"
			(at 0 0 0)
			(layer "F.Fab")
			(hide yes)
			(effects
				(font
					(size 1.27 1.27)
					(thickness 0.15)
				)
			)
		)
		(property "Author" "Antmicro"
			(at 0 0 0)
			(layer "F.Fab")
			(hide yes)
			(effects
				(font
					(size 1 1)
					(thickness 0.15)
				)
			)
		)
		(property "License" "Apache-2.0"
			(at 0 0 0)
			(layer "F.Fab")
			(hide yes)
			(effects
				(font
					(size 1 1)
					(thickness 0.15)
				)
			)
		)
		(property "MPN" "PAC1934T-I/J6CX"
			(at 0 0 0)
			(layer "F.Fab")
			(hide yes)
			(effects
				(font
					(size 1 1)
					(thickness 0.15)
				)
			)
		)
		(property "Manufacturer" "Microchip Technology"
			(at 0 0 0)
			(layer "F.Fab")
			(hide yes)
			(effects
				(font
					(size 1 1)
					(thickness 0.15)
				)
			)
		)
		(sheetname "/Supply/")
		(sheetfile "supply.kicad_sch")
		(attr smd)
		(fp_line
			(start -1.2 -0.75)
			(end -0.8 -1.15)
			(stroke
				(width 0.15)
				(type solid)
			)
			(layer "F.SilkS")
		)
		(fp_line
			(start -1.2 1.15)
			(end -1.2 -0.75)
			(stroke
				(width 0.15)
				(type solid)
			)
			(layer "F.SilkS")
		)
		(fp_line
			(start -0.8 -1.15)
			(end 1.2 -1.15)
			(stroke
				(width 0.15)
				(type solid)
			)
			(layer "F.SilkS")
		)
		(fp_line
			(start 1.2 -1.15)
			(end 1.2 1.15)
			(stroke
				(width 0.15)
				(type solid)
			)
			(layer "F.SilkS")
		)
		(fp_line
			(start 1.2 1.15)
			(end -1.2 1.15)
			(stroke
				(width 0.15)
				(type solid)
			)
			(layer "F.SilkS")
		)
		(fp_circle
			(center -1.2 -1.19)
			(end -1.15 -1.19)
			(stroke
				(width 0.15)
				(type solid)
			)
			(fill yes)
			(layer "F.SilkS")
		)
		(fp_rect
			(start -1.35629 -1.35)
			(end 1.354896 1.355248)
			(stroke
				(width 0.05)
				(type solid)
			)
			(fill no)
			(layer "F.CrtYd")
		)
		(fp_text user "License: Apache-2.0"
			(at -2.16 7.4 0)
			(layer "F.Fab")
			(effects
				(font
					(size 0.7 0.7)
					(thickness 0.15)
				)
				(justify left bottom)
			)
		)
		(fp_text user "Author: Antmicro"
			(at -2.16 5 0)
			(layer "F.Fab")
			(effects
				(font
					(size 0.7 0.7)
					(thickness 0.15)
				)
				(justify left bottom)
			)
		)
		(fp_text user "${REFERENCE}"
			(at -2.16 6.2 0)
			(layer "F.Fab")
			(effects
				(font
					(size 0.7 0.7)
					(thickness 0.15)
				)
				(justify left bottom)
			)
		)
		(pad "A1" smd circle
			(at -0.75 -0.75 90)
			(size 0.312 0.312)
			(layers "F.Cu" "F.Mask" "F.Paste")
			(net 577 "Net-(U6-SENSE2+)")
			(pinfunction "SENSE2+")
			(pintype "input")
		)
		(pad "A2" smd circle
			(at -0.25 -0.75 90)
			(size 0.312 0.312)
			(layers "F.Cu" "F.Mask" "F.Paste")
			(net 50 "+3V3")
			(pinfunction "SENSE1-")
			(pintype "input")
		)
		(pad "A3" smd circle
			(at 0.25 -0.75 90)
			(size 0.312 0.312)
			(layers "F.Cu" "F.Mask" "F.Paste")
			(net 576 "Net-(U6-SENSE1+)")
			(pinfunction "SENSE1+")
			(pintype "input")
		)
		(pad "A4" smd circle
			(at 0.75 -0.75 90)
			(size 0.312 0.312)
			(layers "F.Cu" "F.Mask" "F.Paste")
			(net 50 "+3V3")
			(pinfunction "VDD")
			(pintype "power_in")
		)
		(pad "B1" smd circle
			(at -0.75 -0.25 90)
			(size 0.312 0.312)
			(layers "F.Cu" "F.Mask" "F.Paste")
			(net 48 "+1V8")
			(pinfunction "SENSE2-")
			(pintype "input")
		)
		(pad "B2" smd circle
			(at -0.25 -0.25 90)
			(size 0.312 0.312)
			(layers "F.Cu" "F.Mask" "F.Paste")
			(net 649 "VDD")
			(pinfunction "VDD_I/O")
			(pintype "power_in")
		)
		(pad "B3" smd circle
			(at 0.25 -0.25 90)
			(size 0.312 0.312)
			(layers "F.Cu" "F.Mask" "F.Paste")
			(net 263 "Net-(U6-~{PWRDN})")
			(pinfunction "~{PWRDN}")
			(pintype "input")
		)
		(pad "B4" smd circle
			(at 0.75 -0.25 90)
			(size 0.312 0.312)
			(layers "F.Cu" "F.Mask" "F.Paste")
			(net 417 "GND")
			(pinfunction "GND")
			(pintype "power_in")
		)
		(pad "C1" smd circle
			(at -0.75 0.25 90)
			(size 0.312 0.312)
			(layers "F.Cu" "F.Mask" "F.Paste")
			(net 2 "+1V1")
			(pinfunction "SENSE3-")
			(pintype "input")
		)
		(pad "C2" smd circle
			(at -0.25 0.25 90)
			(size 0.312 0.312)
			(layers "F.Cu" "F.Mask" "F.Paste")
			(net 260 "Net-(U6-ADDRSEL)")
			(pinfunction "ADDRSEL")
			(pintype "bidirectional")
		)
		(pad "C3" smd circle
			(at 0.25 0.25 90)
			(size 0.312 0.312)
			(layers "F.Cu" "F.Mask" "F.Paste")
			(net 428 "PAC1934_SLOW")
			(pinfunction "SLOW/~{ALERT}")
			(pintype "bidirectional")
		)
		(pad "C4" smd circle
			(at 0.75 0.25 90)
			(size 0.312 0.312)
			(layers "F.Cu" "F.Mask" "F.Paste")
			(net 92 "/FPGA MSSIO/SUPPLY.SCL")
			(pinfunction "SM_CLK")
			(pintype "input")
		)
		(pad "D1" smd circle
			(at -0.75 0.75 90)
			(size 0.312 0.312)
			(layers "F.Cu" "F.Mask" "F.Paste")
			(net 578 "Net-(U6-SENSE3+)")
			(pinfunction "SENSE3+")
			(pintype "input")
		)
		(pad "D2" smd circle
			(at -0.25 0.75 90)
			(size 0.312 0.312)
			(layers "F.Cu" "F.Mask" "F.Paste")
			(net 96 "+1V2")
			(pinfunction "SENSE4-")
			(pintype "input")
		)
		(pad "D3" smd circle
			(at 0.25 0.75 90)
			(size 0.312 0.312)
			(layers "F.Cu" "F.Mask" "F.Paste")
			(net 579 "Net-(U6-SENSE4+)")
			(pinfunction "SENSE4+")
			(pintype "input")
		)
		(pad "D4" smd circle
			(at 0.75 0.75 90)
			(size 0.312 0.312)
			(layers "F.Cu" "F.Mask" "F.Paste")
			(net 100 "/FPGA MSSIO/SUPPLY.SDA")
			(pinfunction "SM_DATA")
			(pintype "bidirectional")
		)
	)
	(footprint "antmicro-footprints:Tag-Connect_TC2050-IDC-NL_2x5_P1.27mm"
		(layer "F.Cu")
		(at 184.14 118.58 180)
		(property "Reference" "J2"
			(at -2.61 1.98 335.75)
			(layer "F.SilkS")
			(effects
				(font
					(size 0.7 0.7)
					(thickness 0.15)
				)
				(justify left bottom)
			)
		)
		(property "Value" "Tag-Connect_TC2050-IDC-NL_2x5_P1.27mm"
			(at 0 4.4 180)
			(layer "F.Fab")
			(hide yes)
			(effects
				(font
					(size 0.7 0.7)
					(thickness 0.15)
				)
				(justify left bottom)
			)
		)
		(property "Datasheet" "https://www.tag-connect.com/wp-content/uploads/bsk-pdf-manager/TC2050-IDC-NL_Datasheet_8.pdf"
			(at 0 0 180)
			(layer "F.Fab")
			(hide yes)
			(effects
				(font
					(size 1.27 1.27)
					(thickness 0.15)
				)
			)
		)
		(property "Description" "Tag Connect 2x5 1.27mm terminal"
			(at 0 0 180)
			(layer "F.Fab")
			(hide yes)
			(effects
				(font
					(size 1.27 1.27)
					(thickness 0.15)
				)
			)
		)
		(property "Author" "Antmicro"
			(at 368.28 237.16 0)
			(layer "F.Fab")
			(hide yes)
			(effects
				(font
					(size 1 1)
					(thickness 0.15)
				)
			)
		)
		(property "DNP" "DNP"
			(at 368.28 237.16 0)
			(layer "F.Fab")
			(hide yes)
			(effects
				(font
					(size 1 1)
					(thickness 0.15)
				)
			)
		)
		(property "License" "Apache-2.0"
			(at 368.28 237.16 0)
			(layer "F.Fab")
			(hide yes)
			(effects
				(font
					(size 1 1)
					(thickness 0.15)
				)
			)
		)
		(property "MPN" "TC2050-IDC-NL"
			(at 368.28 237.16 0)
			(layer "F.Fab")
			(hide yes)
			(effects
				(font
					(size 1 1)
					(thickness 0.15)
				)
			)
		)
		(property "Manufacturer" "Tag Connect"
			(at 368.28 237.16 0)
			(layer "F.Fab")
			(hide yes)
			(effects
				(font
					(size 1 1)
					(thickness 0.15)
				)
			)
		)
		(sheetname "/FPGA Config/")
		(sheetfile "fpga-config.kicad_sch")
		(attr exclude_from_pos_files exclude_from_bom dnp)
		(fp_line
			(start 5.1 -1.7)
			(end 5.1 1.7)
			(stroke
				(width 0.15)
				(type solid)
			)
			(layer "F.SilkS")
		)
		(fp_line
			(start 4.7 2.049)
			(end 5.1 1.7)
			(stroke
				(width 0.15)
				(type solid)
			)
			(layer "F.SilkS")
		)
		(fp_line
			(start 4.7 2.049)
			(end -2.3 2.049)
			(stroke
				(width 0.15)
				(type solid)
			)
			(layer "F.SilkS")
		)
		(fp_line
			(start 4.7 -2.05)
			(end 5.1 -1.7)
			(stroke
				(width 0.15)
				(type solid)
			)
			(layer "F.SilkS")
		)
		(fp_line
			(start -2.2 -2.05)
			(end 4.7 -2.05)
			(stroke
				(width 0.15)
				(type solid)
			)
			(layer "F.SilkS")
		)
		(fp_line
			(start -2.3 2.049)
			(end -5.08 0.8)
			(stroke
				(width 0.15)
				(type solid)
			)
			(layer "F.SilkS")
		)
		(fp_line
			(start -3.101 1.269)
			(end -3.101 0.4)
			(stroke
				(width 0.15)
				(type solid)
			)
			(layer "F.SilkS")
		)
		(fp_line
			(start -5.08 0.8)
			(end -5.08 -0.9)
			(stroke
				(width 0.15)
				(type solid)
			)
			(layer "F.SilkS")
		)
		(fp_line
			(start -5.08 -0.9)
			(end -2.2 -2.05)
			(stroke
				(width 0.15)
				(type solid)
			)
			(layer "F.SilkS")
		)
		(fp_line
			(start 5.32 -1.8)
			(end 5.32 1.8)
			(stroke
				(width 0.05)
				(type solid)
			)
			(layer "F.CrtYd")
		)
		(fp_line
			(start 4.8 2.29)
			(end 5.32 1.8)
			(stroke
				(width 0.05)
				(type solid)
			)
			(layer "F.CrtYd")
		)
		(fp_line
			(start 4.8 2.29)
			(end -2.4 2.29)
			(stroke
				(width 0.05)
				(type solid)
			)
			(layer "F.CrtYd")
		)
		(fp_line
			(start 4.8 -2.3)
			(end 5.32 -1.8)
			(stroke
				(width 0.05)
				(type solid)
			)
			(layer "F.CrtYd")
		)
		(fp_line
			(start -2.3 -2.3)
			(end 4.8 -2.3)
			(stroke
				(width 0.05)
				(type solid)
			)
			(layer "F.CrtYd")
		)
		(fp_line
			(start -2.4 2.29)
			(end -5.33 1)
			(stroke
				(width 0.05)
				(type solid)
			)
			(layer "F.CrtYd")
		)
		(fp_line
			(start -5.33 1)
			(end -5.33 -1.1)
			(stroke
				(width 0.05)
				(type solid)
			)
			(layer "F.CrtYd")
		)
		(fp_line
			(start -5.33 -1.1)
			(end -2.3 -2.3)
			(stroke
				(width 0.05)
				(type solid)
			)
			(layer "F.CrtYd")
		)
		(fp_text user "License: Apache-2.0"
			(at -6.223 8.449 180)
			(layer "F.Fab")
			(effects
				(font
					(size 0.7 0.7)
					(thickness 0.15)
				)
				(justify left bottom)
			)
		)
		(fp_text user "Author: Antmicro"
			(at -6.223 7.249 180)
			(layer "F.Fab")
			(effects
				(font
					(size 0.7 0.7)
					(thickness 0.15)
				)
				(justify left bottom)
			)
		)
		(fp_text user "${REFERENCE}"
			(at -6.223 6.049 180)
			(layer "F.Fab")
			(effects
				(font
					(size 0.7 0.7)
					(thickness 0.15)
				)
				(justify left bottom)
			)
		)
		(pad "" np_thru_hole circle
			(at -3.81 0 180)
			(size 0.9906 0.9906)
			(drill 0.9906)
			(layers "*.Cu" "*.Mask")
		)
		(pad "" np_thru_hole circle
			(at 3.809 -1.016 180)
			(size 0.9906 0.9906)
			(drill 0.9906)
			(layers "*.Cu" "*.Mask")
		)
		(pad "" np_thru_hole circle
			(at 3.809 1.015 180)
			(size 0.9906 0.9906)
			(drill 0.9906)
			(layers "*.Cu" "*.Mask")
		)
		(pad "1" connect circle
			(at -2.54 0.634 180)
			(size 0.7874 0.7874)
			(layers "F.Cu" "F.Mask")
			(net 124 "JTAG_TCK")
			(pinfunction "1")
			(pintype "passive")
		)
		(pad "2" connect circle
			(at -1.27 0.634 180)
			(size 0.7874 0.7874)
			(layers "F.Cu" "F.Mask")
			(net 417 "GND")
			(pinfunction "2")
			(pintype "passive")
		)
		(pad "3" connect circle
			(at 0 0.634 180)
			(size 0.7874 0.7874)
			(layers "F.Cu" "F.Mask")
			(net 125 "JTAG_TDO")
			(pinfunction "3")
			(pintype "passive")
		)
		(pad "4" connect circle
			(at 1.269 0.634 180)
			(size 0.7874 0.7874)
			(layers "F.Cu" "F.Mask")
			(net 648 "unconnected-(J2-Pad4)")
			(pinfunction "4")
			(pintype "passive+no_connect")
		)
		(pad "5" connect circle
			(at 2.539 0.634 180)
			(size 0.7874 0.7874)
			(layers "F.Cu" "F.Mask")
			(net 123 "JTAG_TMS")
			(pinfunction "5")
			(pintype "passive")
		)
		(pad "6" connect circle
			(at 2.539 -0.635 180)
			(size 0.7874 0.7874)
			(layers "F.Cu" "F.Mask")
			(net 50 "+3V3")
			(pinfunction "6")
			(pintype "passive")
		)
		(pad "7" connect circle
			(at 1.269 -0.635 180)
			(size 0.7874 0.7874)
			(layers "F.Cu" "F.Mask")
			(net 651 "unconnected-(J2-Pad7)")
			(pinfunction "7")
			(pintype "passive+no_connect")
		)
		(pad "8" connect circle
			(at 0 -0.635 180)
			(size 0.7874 0.7874)
			(layers "F.Cu" "F.Mask")
			(net 127 "JTAG_RESET_n")
			(pinfunction "8")
			(pintype "passive")
		)
		(pad "9" connect circle
			(at -1.27 -0.635 180)
			(size 0.7874 0.7874)
			(layers "F.Cu" "F.Mask")
			(net 126 "JTAG_TDI")
			(pinfunction "9")
			(pintype "passive")
		)
		(pad "10" connect circle
			(at -2.54 -0.635 180)
			(size 0.7874 0.7874)
			(layers "F.Cu" "F.Mask")
			(net 417 "GND")
			(pinfunction "10")
			(pintype "passive")
		)
	)
	(footprint "antmicro-footprints:MP_NPTH_Drill2.7mm"
		(locked yes)
		(layer "F.Cu")
		(at 178.017 152.336)
		(property "Reference" "MP2"
			(at 0 -1.8 0)
			(layer "F.SilkS")
			(hide yes)
			(effects
				(font
					(size 0.7 0.7)
					(thickness 0.15)
				)
				(justify left bottom)
			)
		)
		(property "Value" "MP_NPTH_Drill2.7mm"
			(at 0 2.3 0)
			(layer "F.Fab")
			(hide yes)
			(effects
				(font
					(size 0.7 0.7)
					(thickness 0.15)
				)
				(justify left bottom)
			)
		)
		(property "Description" "Mechanical part"
			(at 0 0 0)
			(layer "F.Fab")
			(hide yes)
			(effects
				(font
					(size 1.27 1.27)
					(thickness 0.15)
				)
			)
		)
		(property "Author" "Antmicro"
			(at 0 0 0)
			(layer "F.Fab")
			(hide yes)
			(effects
				(font
					(size 1 1)
					(thickness 0.15)
				)
			)
		)
		(property "License" "Apache-2.0"
			(at 0 0 0)
			(layer "F.Fab")
			(hide yes)
			(effects
				(font
					(size 1 1)
					(thickness 0.15)
				)
			)
		)
		(property "exclude_from_bom" ""
			(at 0 0 0)
			(layer "F.Fab")
			(hide yes)
			(effects
				(font
					(size 1 1)
					(thickness 0.15)
				)
			)
		)
		(sheetfile "polarfire-som.kicad_sch")
		(attr board_only exclude_from_pos_files exclude_from_bom)
		(fp_circle
			(center 0 0)
			(end 1.45 0)
			(stroke
				(width 0.05)
				(type default)
			)
			(fill no)
			(layer "F.CrtYd")
		)
		(fp_text user "License: Apache-2.0"
			(at 0 7.15 0)
			(layer "F.Fab")
			(effects
				(font
					(size 0.7 0.7)
					(thickness 0.15)
				)
				(justify left bottom)
			)
		)
		(fp_text user "Author: Antmicro"
			(at 0 5.95 0)
			(layer "F.Fab")
			(effects
				(font
					(size 0.7 0.7)
					(thickness 0.15)
				)
				(justify left bottom)
			)
		)
		(fp_text user "${REFERENCE}"
			(at 0 4.749 0)
			(layer "F.Fab")
			(effects
				(font
					(size 0.7 0.7)
					(thickness 0.15)
				)
				(justify left bottom)
			)
		)
		(pad "" np_thru_hole circle
			(at 0 0)
			(size 2.7 2.7)
			(drill 2.7)
			(layers "F&B.Cu" "*.Mask")
		)
	)
	(footprint "antmicro-footprints:R_Array_4x0201_Panasonic_EXB18V"
		(layer "F.Cu")
		(at 201.84884 121.25 -90)
		(property "Reference" "R26"
			(at 1.75 1.11884 180)
			(layer "F.SilkS")
			(effects
				(font
					(size 0.7 0.7)
					(thickness 0.15)
				)
				(justify left bottom)
			)
		)
		(property "Value" "R_4x0R_0201_array"
			(at -1.1 1.8 90)
			(layer "F.Fab")
			(hide yes)
			(effects
				(font
					(size 0.7 0.7)
					(thickness 0.15)
				)
				(justify right bottom)
			)
		)
		(property "Datasheet" "http://industrial.panasonic.com/cdbs/www-data/pdf/AOC0000/AOC0000C14.pdf"
			(at 0 0 270)
			(layer "F.Fab")
			(hide yes)
			(effects
				(font
					(size 1.27 1.27)
					(thickness 0.15)
				)
			)
		)
		(property "Description" "Zero Ohm Network Resistor, Jumper, 0201 [0603 Metric], Thick Film, Isolated, Flat, 4 Resistors"
			(at 0 0 270)
			(layer "F.Fab")
			(hide yes)
			(effects
				(font
					(size 1.27 1.27)
					(thickness 0.15)
				)
			)
		)
		(property "Author" "Antmicro"
			(at 80.59884 323.09884 0)
			(layer "F.Fab")
			(hide yes)
			(effects
				(font
					(size 1 1)
					(thickness 0.15)
				)
			)
		)
		(property "DNP" "DNP"
			(at 80.59884 323.09884 0)
			(layer "F.Fab")
			(hide yes)
			(effects
				(font
					(size 1 1)
					(thickness 0.15)
				)
			)
		)
		(property "License" "Apache-2.0"
			(at 80.59884 323.09884 0)
			(layer "F.Fab")
			(hide yes)
			(effects
				(font
					(size 1 1)
					(thickness 0.15)
				)
			)
		)
		(property "MPN" "EXB-18VR000X"
			(at 80.59884 323.09884 0)
			(layer "F.Fab")
			(hide yes)
			(effects
				(font
					(size 1 1)
					(thickness 0.15)
				)
			)
		)
		(property "Manufacturer" "Panasonic"
			(at 80.59884 323.09884 0)
			(layer "F.Fab")
			(hide yes)
			(effects
				(font
					(size 1 1)
					(thickness 0.15)
				)
			)
		)
		(property "Val" "4x0R_0201"
			(at 80.59884 323.09884 0)
			(layer "F.Fab")
			(hide yes)
			(effects
				(font
					(size 1 1)
					(thickness 0.15)
				)
			)
		)
		(sheetname "/FPGA MSSIO/")
		(sheetfile "fpga-mssio.kicad_sch")
		(attr smd dnp)
		(fp_line
			(start -0.8 -0.45)
			(end -0.8 0.45)
			(stroke
				(width 0.12)
				(type solid)
			)
			(layer "F.SilkS")
		)
		(fp_line
			(start 0.8 -0.45)
			(end 0.8 0.45)
			(stroke
				(width 0.12)
				(type solid)
			)
			(layer "F.SilkS")
		)
		(fp_rect
			(start -0.898 -0.66)
			(end 0.898 0.65)
			(stroke
				(width 0.05)
				(type solid)
			)
			(fill no)
			(layer "F.CrtYd")
		)
		(fp_text user "License: Apache-2.0"
			(at -1.051 6 270)
			(layer "F.Fab")
			(effects
				(font
					(size 0.7 0.7)
					(thickness 0.15)
				)
				(justify left bottom)
			)
		)
		(fp_text user "Author: Antmicro"
			(at -1.051 4.599 270)
			(layer "F.Fab")
			(effects
				(font
					(size 0.7 0.7)
					(thickness 0.15)
				)
				(justify left bottom)
			)
		)
		(fp_text user "${REFERENCE}"
			(at -1.051 3.2 270)
			(layer "F.Fab")
			(effects
				(font
					(size 0.7 0.7)
					(thickness 0.15)
				)
				(justify left bottom)
			)
		)
		(pad "1" smd roundrect
			(at -0.6 0.298 270)
			(size 0.2 0.4)
			(layers "F.Cu" "F.Mask" "F.Paste")
			(roundrect_rratio 0.25)
			(net 273 "/FPGA MSSIO/SD.DAT1")
			(pinfunction "R1.1")
			(pintype "passive")
		)
		(pad "2" smd roundrect
			(at -0.202 0.298 270)
			(size 0.2 0.4)
			(layers "F.Cu" "F.Mask" "F.Paste")
			(roundrect_rratio 0.25)
			(net 274 "/FPGA MSSIO/SD.DAT2")
			(pinfunction "R2.1")
			(pintype "passive")
		)
		(pad "3" smd roundrect
			(at 0.2 0.298 270)
			(size 0.2 0.4)
			(layers "F.Cu" "F.Mask" "F.Paste")
			(roundrect_rratio 0.25)
			(net 276 "/FPGA MSSIO/SD.DAT6")
			(pinfunction "R3.1")
			(pintype "passive")
		)
		(pad "4" smd roundrect
			(at 0.598 0.298 270)
			(size 0.2 0.4)
			(layers "F.Cu" "F.Mask" "F.Paste")
			(roundrect_rratio 0.25)
			(net 277 "/FPGA MSSIO/SD.DAT4")
			(pinfunction "R4.1")
			(pintype "passive")
		)
		(pad "5" smd roundrect
			(at 0.598 -0.3 270)
			(size 0.2 0.4)
			(layers "F.Cu" "F.Mask" "F.Paste")
			(roundrect_rratio 0.25)
			(net 251 "/FPGA MSSIO/MEM.DAT4")
			(pinfunction "R4.2")
			(pintype "passive")
		)
		(pad "6" smd roundrect
			(at 0.2 -0.3 270)
			(size 0.2 0.4)
			(layers "F.Cu" "F.Mask" "F.Paste")
			(roundrect_rratio 0.25)
			(net 252 "/FPGA MSSIO/MEM.DAT6")
			(pinfunction "R3.2")
			(pintype "passive")
		)
		(pad "7" smd roundrect
			(at -0.202 -0.3 270)
			(size 0.2 0.4)
			(layers "F.Cu" "F.Mask" "F.Paste")
			(roundrect_rratio 0.25)
			(net 261 "/FPGA MSSIO/MEM.DAT2")
			(pinfunction "R2.2")
			(pintype "passive")
		)
		(pad "8" smd roundrect
			(at -0.6 -0.3 270)
			(size 0.2 0.4)
			(layers "F.Cu" "F.Mask" "F.Paste")
			(roundrect_rratio 0.25)
			(net 262 "/FPGA MSSIO/MEM.DAT1")
			(pinfunction "R1.2")
			(pintype "passive")
		)
	)
	(footprint "antmicro-footprints:MPS_QFN-14_MP8869S"
		(layer "F.Cu")
		(at 182.858904 150.129531 180)
		(property "Reference" "U8"
			(at -1.861096 2.439531 0)
			(layer "F.SilkS")
			(effects
				(font
					(size 0.7 0.7)
					(thickness 0.15)
				)
				(justify right bottom)
			)
		)
		(property "Value" "MP8869S"
			(at -5.5 3.43 0)
			(layer "F.Fab")
			(hide yes)
			(effects
				(font
					(size 0.7 0.7)
					(thickness 0.15)
				)
				(justify right bottom)
			)
		)
		(property "Datasheet" "https://www.mouser.com/datasheet/2/277/MP8869S-2946178.pdf"
			(at 0 0 180)
			(layer "F.Fab")
			(hide yes)
			(effects
				(font
					(size 1.27 1.27)
					(thickness 0.15)
				)
			)
		)
		(property "Description" "DC-DC Switching Synchronous Buck Regulator, 2.85V-18V in, 600mV to 5.5V out, 12A, 500kHz, QFN-14"
			(at 0 0 180)
			(layer "F.Fab")
			(hide yes)
			(effects
				(font
					(size 1.27 1.27)
					(thickness 0.15)
				)
			)
		)
		(property "Author" "Antmicro"
			(at 365.717808 300.259062 0)
			(layer "F.Fab")
			(hide yes)
			(effects
				(font
					(size 1 1)
					(thickness 0.15)
				)
			)
		)
		(property "License" "Apache-2.0"
			(at 365.717808 300.259062 0)
			(layer "F.Fab")
			(hide yes)
			(effects
				(font
					(size 1 1)
					(thickness 0.15)
				)
			)
		)
		(property "MPN" "MP8869SGL-P"
			(at 365.717808 300.259062 0)
			(layer "F.Fab")
			(hide yes)
			(effects
				(font
					(size 1 1)
					(thickness 0.15)
				)
			)
		)
		(property "Manufacturer" "Monolithic Power Systems"
			(at 365.717808 300.259062 0)
			(layer "F.Fab")
			(hide yes)
			(effects
				(font
					(size 1 1)
					(thickness 0.15)
				)
			)
		)
		(property ki_fp_filters "QFN-14_MP8869S_MNP")
		(sheetname "/Supply/")
		(sheetfile "supply.kicad_sch")
		(attr smd)
		(fp_line
			(start 1.675 0.981)
			(end 1.675 2.171)
			(stroke
				(width 0.15)
				(type solid)
			)
			(layer "F.SilkS")
		)
		(fp_line
			(start 1.675 -2.173)
			(end 1.675 -0.983)
			(stroke
				(width 0.15)
				(type solid)
			)
			(layer "F.SilkS")
		)
		(fp_line
			(start -1.678 2.171)
			(end -1.678 0.481)
			(stroke
				(width 0.15)
				(type solid)
			)
			(layer "F.SilkS")
		)
		(fp_line
			(start -1.678 -0.959)
			(end -1.678 -2.173)
			(stroke
				(width 0.15)
				(type solid)
			)
			(layer "F.SilkS")
		)
		(fp_circle
			(center -2.361 -0.5)
			(end -2.311 -0.5)
			(stroke
				(width 0.15)
				(type solid)
			)
			(fill yes)
			(layer "F.SilkS")
		)
		(fp_rect
			(start -2.061 -2.55)
			(end 2.06 2.548)
			(stroke
				(width 0.05)
				(type solid)
			)
			(fill no)
			(layer "F.CrtYd")
		)
		(fp_line
			(start 1.548 2.043)
			(end 1.548 -2.045)
			(stroke
				(width 0.15)
				(type solid)
			)
			(layer "F.Fab")
		)
		(fp_line
			(start 1.548 -2.045)
			(end -1.551 -2.045)
			(stroke
				(width 0.15)
				(type solid)
			)
			(layer "F.Fab")
		)
		(fp_line
			(start -1.541 -1.841)
			(end -1.341 -2.04)
			(stroke
				(width 0.15)
				(type solid)
			)
			(layer "F.Fab")
		)
		(fp_line
			(start -1.551 2.043)
			(end 1.548 2.043)
			(stroke
				(width 0.15)
				(type solid)
			)
			(layer "F.Fab")
		)
		(fp_line
			(start -1.551 -2.045)
			(end -1.551 2.043)
			(stroke
				(width 0.15)
				(type solid)
			)
			(layer "F.Fab")
		)
		(fp_text user "License: Apache-2.0"
			(at -5.5 5.43 180)
			(layer "F.Fab")
			(effects
				(font
					(size 0.7 0.7)
					(thickness 0.15)
				)
				(justify left bottom)
			)
		)
		(fp_text user "${REFERENCE}"
			(at -5.5 6.63 180)
			(layer "F.Fab")
			(effects
				(font
					(size 0.7 0.7)
					(thickness 0.15)
				)
				(justify left bottom)
			)
		)
		(fp_text user "Author: Antmicro"
			(at -5.5 7.83 180)
			(layer "F.Fab")
			(effects
				(font
					(size 0.7 0.7)
					(thickness 0.15)
				)
				(justify left bottom)
			)
		)
		(pad "1" smd custom
			(at -1.401 -0.5 180)
			(size 0.799998 0.249998)
			(layers "F.Cu" "F.Mask" "F.Paste")
			(net 149 "/Supply/1V05_BS")
			(pinfunction "BST")
			(pintype "unspecified")
			(options
				(clearance outline)
				(anchor rect)
			)
			(primitives
				(gr_poly
					(pts
						(xy -0.400002 -0.125001) (xy -0.400002 0.124999) (xy 0.499998 0.124999) (xy 0.499998 -0.000001)
						(xy 0.374998 -0.125001)
					)
					(width 0.1)
					(fill yes)
				)
			)
		)
		(pad "2" smd rect
			(at -0.851 0 180)
			(size 1.9 0.3)
			(layers "F.Cu" "F.Mask" "F.Paste")
			(net 150 "/Supply/1V05_SW")
			(pinfunction "SW")
			(pintype "output")
		)
		(pad "3" smd rect
			(at -1.002 1.848 270)
			(size 0.9 0.25)
			(layers "F.Cu" "F.Mask" "F.Paste")
			(net 92 "/FPGA MSSIO/SUPPLY.SCL")
			(pinfunction "SCL")
			(pintype "unspecified")
		)
		(pad "4" smd rect
			(at -0.5 1.848 270)
			(size 0.9 0.25)
			(layers "F.Cu" "F.Mask" "F.Paste")
			(net 100 "/FPGA MSSIO/SUPPLY.SDA")
			(pinfunction "SDA")
			(pintype "unspecified")
		)
		(pad "5" smd rect
			(at 0 1.848 270)
			(size 0.9 0.25)
			(layers "F.Cu" "F.Mask" "F.Paste")
			(net 187 "/Supply/PWRON")
			(pinfunction "EN")
			(pintype "unspecified")
		)
		(pad "6" smd rect
			(at 0.498 1.848 270)
			(size 0.9 0.25)
			(layers "F.Cu" "F.Mask" "F.Paste")
			(net 417 "GND")
			(pinfunction "A0")
			(pintype "unspecified")
		)
		(pad "7" smd rect
			(at 0.999 1.848 270)
			(size 0.9 0.25)
			(layers "F.Cu" "F.Mask" "F.Paste")
			(net 656 "/Supply/PG")
			(pinfunction "PG")
			(pintype "unspecified")
		)
		(pad "8" smd custom
			(at 0.849 0.498 180)
			(size 0.127 0.127)
			(layers "F.Cu" "F.Mask" "F.Paste")
			(net 417 "GND")
			(pinfunction "PGND")
			(pintype "power_in")
			(options
				(clearance outline)
				(anchor rect)
			)
			(primitives
				(gr_poly
					(pts
						(xy 0.95 0.15) (xy 0.95 -0.15) (xy -0.55 -0.15) (xy -0.65 -0.05) (xy -0.95 -0.05) (xy -0.95 0.15)
					)
					(width 0.1)
					(fill yes)
				)
			)
		)
		(pad "9" smd custom
			(at 0.849 -0.5 180)
			(size 0.127 0.127)
			(layers "F.Cu" "F.Mask" "F.Paste")
			(net 90 "+5V")
			(pinfunction "VIN")
			(pintype "power_in")
			(options
				(clearance outline)
				(anchor rect)
			)
			(primitives
				(gr_poly
					(pts
						(xy 0.95 -0.15) (xy 0.95 0.15) (xy -0.55 0.15) (xy -0.65 0.05) (xy -0.95 0.05) (xy -0.95 -0.15)
					)
					(width 0.1)
					(fill yes)
				)
			)
		)
		(pad "10" smd rect
			(at 0.999 -1.851 270)
			(size 0.9 0.25)
			(layers "F.Cu" "F.Mask" "F.Paste")
			(net 522 "/Supply/1V05_REG")
			(pinfunction "VOUT")
			(pintype "unspecified")
		)
		(pad "11" smd rect
			(at 0.498 -1.851 270)
			(size 0.9 0.25)
			(layers "F.Cu" "F.Mask" "F.Paste")
			(net 398 "/Supply/1V05_FB")
			(pinfunction "FB")
			(pintype "unspecified")
		)
		(pad "12" smd rect
			(at 0 -1.851 270)
			(size 0.9 0.25)
			(layers "F.Cu" "F.Mask" "F.Paste")
			(net 228 "/Supply/1V05_SS")
			(pinfunction "SS")
			(pintype "unspecified")
		)
		(pad "13" smd rect
			(at -0.5 -1.851 270)
			(size 0.9 0.25)
			(layers "F.Cu" "F.Mask" "F.Paste")
			(net 148 "/Supply/1V05_VCC")
			(pinfunction "VCC")
			(pintype "power_out")
		)
		(pad "14" smd rect
			(at -1.002 -1.851 270)
			(size 0.9 0.25)
			(layers "F.Cu" "F.Mask" "F.Paste")
			(net 417 "GND")
			(pinfunction "AGND")
			(pintype "power_in")
		)
	)
	(footprint "antmicro-footprints:BGA-484_19x19mm_Layout22x22_P0.8mm_FCVG484"
		(layer "F.Cu")
		(at 197.699 132.701 -90)
		(descr "FCVG484, 19.0x19.0mm, 484 Ball, 22x22 Layout, 0.8mm Pitch")
		(tags "BGA 484 0.8")
		(property "Reference" "U1"
			(at 0 -10.8 270)
			(layer "F.SilkS")
			(effects
				(font
					(size 0.7 0.7)
					(thickness 0.15)
				)
				(justify left bottom)
			)
		)
		(property "Value" "MPFS250T-FCVG484"
			(at 0 11.5 270)
			(layer "F.Fab")
			(hide yes)
			(effects
				(font
					(size 0.7 0.7)
					(thickness 0.15)
				)
				(justify left bottom)
			)
		)
		(property "Datasheet" "https://ww1.microchip.com/downloads/aemDocuments/documents/FPGA/ProductDocuments/DataSheets/PolarFire-SoC-Datasheet-DS00004248.pdf"
			(at 0 0 270)
			(layer "F.Fab")
			(hide yes)
			(effects
				(font
					(size 1.27 1.27)
					(thickness 0.15)
				)
			)
		)
		(property "Description" "RISC-V System On Chip (SOC) IC PolarFire® FPGA - 254K Logic Modules 484-FCBGA (19x19)"
			(at 0 0 270)
			(layer "F.Fab")
			(hide yes)
			(effects
				(font
					(size 1.27 1.27)
					(thickness 0.15)
				)
			)
		)
		(property "MPN" "MPFS250T-FCVG484E"
			(at 0 0 270)
			(unlocked yes)
			(layer "F.Fab")
			(hide yes)
			(effects
				(font
					(size 1 1)
					(thickness 0.15)
				)
			)
		)
		(property "Manufacturer" "Microchip Technology"
			(at 0 0 270)
			(unlocked yes)
			(layer "F.Fab")
			(hide yes)
			(effects
				(font
					(size 1 1)
					(thickness 0.15)
				)
			)
		)
		(property "VSD_class" "MPFS250T"
			(at 0 0 270)
			(unlocked yes)
			(layer "F.Fab")
			(hide yes)
			(effects
				(font
					(size 1 1)
					(thickness 0.15)
				)
			)
		)
		(property "Author" "Antmicro"
			(at 0 0 270)
			(unlocked yes)
			(layer "F.Fab")
			(hide yes)
			(effects
				(font
					(size 1 1)
					(thickness 0.15)
				)
			)
		)
		(property "License" "Apache-2.0"
			(at 0 0 270)
			(unlocked yes)
			(layer "F.Fab")
			(hide yes)
			(effects
				(font
					(size 1 1)
					(thickness 0.15)
				)
			)
		)
		(sheetname "/FPGA Config/")
		(sheetfile "fpga-config.kicad_sch")
		(attr smd)
		(fp_line
			(start -9.61 9.61)
			(end -9.61 -9.61)
			(stroke
				(width 0.15)
				(type solid)
			)
			(layer "F.SilkS")
		)
		(fp_line
			(start 9.609 9.609)
			(end -9.61 9.609)
			(stroke
				(width 0.15)
				(type solid)
			)
			(layer "F.SilkS")
		)
		(fp_line
			(start -9.61 -9.61)
			(end 9.609 -9.61)
			(stroke
				(width 0.15)
				(type solid)
			)
			(layer "F.SilkS")
		)
		(fp_line
			(start 9.609 -9.61)
			(end 9.609 9.609)
			(stroke
				(width 0.15)
				(type solid)
			)
			(layer "F.SilkS")
		)
		(fp_circle
			(center -9.8 -9.8)
			(end -9.75 -9.8)
			(stroke
				(width 0.15)
				(type solid)
			)
			(fill yes)
			(layer "F.SilkS")
		)
		(fp_line
			(start -10.5 10.49)
			(end 10.49 10.49)
			(stroke
				(width 0.05)
				(type solid)
			)
			(layer "F.CrtYd")
		)
		(fp_line
			(start 10.49 10.49)
			(end 10.49 -10.5)
			(stroke
				(width 0.05)
				(type solid)
			)
			(layer "F.CrtYd")
		)
		(fp_line
			(start -10.5 -10.5)
			(end -10.5 10.49)
			(stroke
				(width 0.05)
				(type solid)
			)
			(layer "F.CrtYd")
		)
		(fp_line
			(start 10.49 -10.5)
			(end -10.5 -10.5)
			(stroke
				(width 0.05)
				(type solid)
			)
			(layer "F.CrtYd")
		)
		(fp_line
			(start -9.5 9.499)
			(end -9.5 -8.5)
			(stroke
				(width 0.15)
				(type solid)
			)
			(layer "F.Fab")
		)
		(fp_line
			(start 9.499 9.499)
			(end -9.5 9.499)
			(stroke
				(width 0.15)
				(type solid)
			)
			(layer "F.Fab")
		)
		(fp_line
			(start -9.5 -8.5)
			(end -8.5 -9.5)
			(stroke
				(width 0.15)
				(type solid)
			)
			(layer "F.Fab")
		)
		(fp_line
			(start -8.5 -9.5)
			(end 9.499 -9.5)
			(stroke
				(width 0.15)
				(type solid)
			)
			(layer "F.Fab")
		)
		(fp_line
			(start 9.499 -9.5)
			(end 9.499 9.499)
			(stroke
				(width 0.15)
				(type solid)
			)
			(layer "F.Fab")
		)
		(fp_text user "Author: Antmicro"
			(at -10.5 13.699 270)
			(layer "F.Fab")
			(effects
				(font
					(size 0.7 0.7)
					(thickness 0.15)
				)
				(justify left bottom)
			)
		)
		(fp_text user "${REFERENCE}"
			(at -10.5 12.499 270)
			(layer "F.Fab")
			(effects
				(font
					(size 0.7 0.7)
					(thickness 0.15)
				)
				(justify left bottom)
			)
		)
		(fp_text user "License: Apache-2.0"
			(at -10.5 14.899 270)
			(layer "F.Fab")
			(effects
				(font
					(size 0.7 0.7)
					(thickness 0.15)
				)
				(justify left bottom)
			)
		)
		(pad "A1" smd circle
			(at -8.401 -8.401 270)
			(size 0.45 0.45)
			(layers "F.Cu" "F.Mask" "F.Paste")
			(net 417 "GND")
			(pinfunction "VSS")
			(pintype "passive")
		)
		(pad "A2" smd circle
			(at -7.6 -8.401 270)
			(size 0.45 0.45)
			(layers "F.Cu" "F.Mask" "F.Paste")
			(net 357 "unconnected-(U1C-MSSIO33B2-PadA2)")
			(pinfunction "MSSIO33B2")
			(pintype "bidirectional+no_connect")
			(die_length 11.723)
		)
		(pad "A3" smd circle
			(at -6.8 -8.401 270)
			(size 0.45 0.45)
			(layers "F.Cu" "F.Mask" "F.Paste")
			(net 285 "Net-(U1C-MSSIO35B2)")
			(pinfunction "MSSIO35B2")
			(pintype "bidirectional")
			(die_length 11.2271)
		)
		(pad "A4" smd circle
			(at -6 -8.401 270)
			(size 0.45 0.45)
			(layers "F.Cu" "F.Mask" "F.Paste")
			(net 417 "GND")
			(pinfunction "VSS")
			(pintype "passive")
		)
		(pad "A5" smd circle
			(at -5.201 -8.401 270)
			(size 0.45 0.45)
			(layers "F.Cu" "F.Mask" "F.Paste")
			(net 334 "VREF_FLAG")
			(pinfunction "GPIO172NB1")
			(pintype "bidirectional")
			(die_length 6.59962)
		)
		(pad "A6" smd circle
			(at -4.401 -8.401 270)
			(size 0.45 0.45)
			(layers "F.Cu" "F.Mask" "F.Paste")
			(net 135 "UART3_TX{slash}RPI_GPIO04")
			(pinfunction "GPIO172PB1/CCC_SW_PLL1_OUT1")
			(pintype "bidirectional")
			(die_length 6.56707)
		)
		(pad "A7" smd circle
			(at -3.601 -8.401 270)
			(size 0.45 0.45)
			(layers "F.Cu" "F.Mask" "F.Paste")
			(net 173 "UART0_TX{slash}RPI_GPIO14")
			(pinfunction "GPIO173PB1/CLKIN_S_3/CCC_SW_CLKIN_S_3")
			(pintype "bidirectional")
			(die_length 6.40706)
		)
		(pad "A8" smd circle
			(at -2.8 -8.401 270)
			(size 0.45 0.45)
			(layers "F.Cu" "F.Mask" "F.Paste")
			(net 348 "/FPGA GPIO/HDMI0_SDA_SRC")
			(pinfunction "GPIO175PB1")
			(pintype "bidirectional")
			(die_length 6.73131)
		)
		(pad "A9" smd circle
			(at -2 -8.401 270)
			(size 0.45 0.45)
			(layers "F.Cu" "F.Mask" "F.Paste")
			(net 649 "VDD")
			(pinfunction "VDDI1")
			(pintype "passive")
		)
		(pad "A10" smd circle
			(at -1.2 -8.401 270)
			(size 0.45 0.45)
			(layers "F.Cu" "F.Mask" "F.Paste")
			(net 359 "unconnected-(U1B-GPIO177PB1{slash}CCC_SW_PLL0_OUT0-PadA10)")
			(pinfunction "GPIO177PB1/CCC_SW_PLL0_OUT0")
			(pintype "bidirectional+no_connect")
			(die_length 7.84164)
		)
		(pad "A11" smd circle
			(at -0.401 -8.401 270)
			(size 0.45 0.45)
			(layers "F.Cu" "F.Mask" "F.Paste")
			(net 558 "unconnected-(U1B-GPIO177NB1-PadA11)")
			(pinfunction "GPIO177NB1")
			(pintype "bidirectional+no_connect")
			(die_length 7.8195)
		)
		(pad "A12" smd circle
			(at 0.4 -8.401 270)
			(size 0.45 0.45)
			(layers "F.Cu" "F.Mask" "F.Paste")
			(net 113 "/Bottom Connector/CAM0.D1_N")
			(pinfunction "GPIO1NB1")
			(pintype "bidirectional")
			(die_length 7.19699)
		)
		(pad "A13" smd circle
			(at 1.199 -8.401 270)
			(size 0.45 0.45)
			(layers "F.Cu" "F.Mask" "F.Paste")
			(net 115 "/Bottom Connector/CAM0.D1_P")
			(pinfunction "GPIO1PB1/CLKIN_S_5")
			(pintype "bidirectional")
			(die_length 7.21046)
		)
		(pad "A14" smd circle
			(at 1.999 -8.401 270)
			(size 0.45 0.45)
			(layers "F.Cu" "F.Mask" "F.Paste")
			(net 417 "GND")
			(pinfunction "VSS")
			(pintype "passive")
		)
		(pad "A15" smd circle
			(at 2.799 -8.401 270)
			(size 0.45 0.45)
			(layers "F.Cu" "F.Mask" "F.Paste")
			(net 344 "/FPGA GPIO/PF_ETH_MDC")
			(pinfunction "GPIO5PB1/CLKIN_S_7")
			(pintype "bidirectional")
			(die_length 7.65884)
		)
		(pad "A16" smd circle
			(at 3.6 -8.401 270)
			(size 0.45 0.45)
			(layers "F.Cu" "F.Mask" "F.Paste")
			(net 30 "UART3_RX{slash}RPI_GPIO05")
			(pinfunction "GPIO13PB1")
			(pintype "bidirectional")
			(die_length 10.4183)
		)
		(pad "A17" smd circle
			(at 4.4 -8.401 270)
			(size 0.45 0.45)
			(layers "F.Cu" "F.Mask" "F.Paste")
			(net 12 "GPIO6")
			(pinfunction "GPIO13NB1")
			(pintype "bidirectional")
			(die_length 10.3918)
		)
		(pad "A18" smd circle
			(at 5.2 -8.401 270)
			(size 0.45 0.45)
			(layers "F.Cu" "F.Mask" "F.Paste")
			(net 8 "GPIO26")
			(pinfunction "GPIO17PB1/CCC_SE_CLKIN_S_11")
			(pintype "bidirectional")
			(die_length 10.8908)
		)
		(pad "A19" smd circle
			(at 5.999 -8.401 270)
			(size 0.45 0.45)
			(layers "F.Cu" "F.Mask" "F.Paste")
			(net 649 "VDD")
			(pinfunction "VDDI1")
			(pintype "power_in")
		)
		(pad "A20" smd circle
			(at 6.799 -8.401 270)
			(size 0.45 0.45)
			(layers "F.Cu" "F.Mask" "F.Paste")
			(net 351 "/FPGA GPIO/WiFi_DATA_3")
			(pinfunction "GPIO20PB9/DQS")
			(pintype "bidirectional")
			(die_length 10.6967)
		)
		(pad "A21" smd circle
			(at 7.599 -8.401 270)
			(size 0.45 0.45)
			(layers "F.Cu" "F.Mask" "F.Paste")
			(net 352 "/FPGA GPIO/WiFi_CLK")
			(pinfunction "GPIO20NB9/DQS")
			(pintype "bidirectional")
			(die_length 10.6945)
		)
		(pad "A22" smd circle
			(at 8.4 -8.401 270)
			(size 0.45 0.45)
			(layers "F.Cu" "F.Mask" "F.Paste")
			(net 417 "GND")
			(pinfunction "VSS")
			(pintype "passive")
		)
		(pad "AA1" smd circle
			(at -8.401 7.599 270)
			(size 0.45 0.45)
			(layers "F.Cu" "F.Mask" "F.Paste")
			(net 305 "/FPGA MSS/LPDDR4.DQ3")
			(pinfunction "MSS_DDR_DQ3")
			(pintype "bidirectional")
			(die_length 6.09637)
		)
		(pad "AA2" smd circle
			(at -7.6 7.599 270)
			(size 0.45 0.45)
			(layers "F.Cu" "F.Mask" "F.Paste")
			(net 306 "/FPGA MSS/LPDDR4.DQS0_P")
			(pinfunction "MSS_DDR_DQS_P0")
			(pintype "bidirectional")
			(die_length 6.03691)
		)
		(pad "AA3" smd circle
			(at -6.8 7.599 270)
			(size 0.45 0.45)
			(layers "F.Cu" "F.Mask" "F.Paste")
			(net 307 "/FPGA MSS/LPDDR4.DQS0_N")
			(pinfunction "MSS_DDR_DQS_N0")
			(pintype "bidirectional")
			(die_length 6.04366)
		)
		(pad "AA4" smd circle
			(at -6 7.599 270)
			(size 0.45 0.45)
			(layers "F.Cu" "F.Mask" "F.Paste")
			(net 417 "GND")
			(pinfunction "VSS")
			(pintype "passive")
		)
		(pad "AA5" smd circle
			(at -5.201 7.599 270)
			(size 0.45 0.45)
			(layers "F.Cu" "F.Mask" "F.Paste")
			(net 308 "/FPGA MSS/LPDDR4.DQ5")
			(pinfunction "MSS_DDR_DQ5")
			(pintype "bidirectional")
			(die_length 5.44591)
		)
		(pad "AA6" smd circle
			(at -4.401 7.599 270)
			(size 0.45 0.45)
			(layers "F.Cu" "F.Mask" "F.Paste")
			(net 309 "/FPGA MSS/LPDDR4.DQ11")
			(pinfunction "MSS_DDR_DQ11")
			(pintype "bidirectional")
			(die_length 6.62748)
		)
		(pad "AA7" smd circle
			(at -3.601 7.599 270)
			(size 0.45 0.45)
			(layers "F.Cu" "F.Mask" "F.Paste")
			(net 310 "/FPGA MSS/LPDDR4.DMI1")
			(pinfunction "MSS_DDR_DM1")
			(pintype "bidirectional")
			(die_length 6.55419)
		)
		(pad "AA8" smd circle
			(at -2.8 7.599 270)
			(size 0.45 0.45)
			(layers "F.Cu" "F.Mask" "F.Paste")
			(net 311 "/FPGA MSS/LPDDR4.DQ15")
			(pinfunction "MSS_DDR_DQ15")
			(pintype "bidirectional")
			(die_length 6.33971)
		)
		(pad "AA9" smd circle
			(at -2 7.599 270)
			(size 0.45 0.45)
			(layers "F.Cu" "F.Mask" "F.Paste")
			(net 2 "+1V1")
			(pinfunction "VDDI6")
			(pintype "power_in")
		)
		(pad "AA10" smd circle
			(at -1.2 7.599 270)
			(size 0.45 0.45)
			(layers "F.Cu" "F.Mask" "F.Paste")
			(net 312 "/FPGA MSS/LPDDR4.DQS2_N")
			(pinfunction "MSS_DDR_DQS_N2")
			(pintype "bidirectional")
			(die_length 8.02694)
		)
		(pad "AA11" smd circle
			(at -0.401 7.599 270)
			(size 0.45 0.45)
			(layers "F.Cu" "F.Mask" "F.Paste")
			(net 313 "/FPGA MSS/LPDDR4.DQS2_P")
			(pinfunction "MSS_DDR_DQS_P2")
			(pintype "bidirectional")
			(die_length 8.03866)
		)
		(pad "AA12" smd circle
			(at 0.4 7.599 270)
			(size 0.45 0.45)
			(layers "F.Cu" "F.Mask" "F.Paste")
			(net 360 "unconnected-(U1A-HSIO88PB0-PadAA12)")
			(pinfunction "HSIO88PB0")
			(pintype "bidirectional+no_connect")
			(die_length 6.6173)
		)
		(pad "AA13" smd circle
			(at 1.199 7.599 270)
			(size 0.45 0.45)
			(layers "F.Cu" "F.Mask" "F.Paste")
			(net 361 "unconnected-(U1A-HSIO86PB0{slash}CLKIN_N_4{slash}CCC_NW_PLL0_OUT0-PadAA13)")
			(pinfunction "HSIO86PB0/CLKIN_N_4/CCC_NW_PLL0_OUT0")
			(pintype "bidirectional+no_connect")
			(die_length 6.19556)
		)
		(pad "AA14" smd circle
			(at 1.999 7.599 270)
			(size 0.45 0.45)
			(layers "F.Cu" "F.Mask" "F.Paste")
			(net 417 "GND")
			(pinfunction "VSS")
			(pintype "passive")
		)
		(pad "AA15" smd circle
			(at 2.799 7.599 270)
			(size 0.45 0.45)
			(layers "F.Cu" "F.Mask" "F.Paste")
			(net 362 "unconnected-(U1A-HSIO85NB0-PadAA15)")
			(pinfunction "HSIO85NB0")
			(pintype "bidirectional+no_connect")
			(die_length 5.45513)
		)
		(pad "AA16" smd circle
			(at 3.6 7.599 270)
			(size 0.45 0.45)
			(layers "F.Cu" "F.Mask" "F.Paste")
			(net 363 "unconnected-(U1A-HSIO82PB0-PadAA16)")
			(pinfunction "HSIO82PB0")
			(pintype "bidirectional+no_connect")
			(die_length 6.6422)
		)
		(pad "AA17" smd circle
			(at 4.4 7.599 270)
			(size 0.45 0.45)
			(layers "F.Cu" "F.Mask" "F.Paste")
			(net 364 "unconnected-(U1A-HSIO81NB0{slash}DQS-PadAA17)")
			(pinfunction "HSIO81NB0/DQS")
			(pintype "bidirectional+no_connect")
			(die_length 6.85921)
		)
		(pad "AA18" smd circle
			(at 5.2 7.599 270)
			(size 0.45 0.45)
			(layers "F.Cu" "F.Mask" "F.Paste")
			(net 130 "/FPGA HSIO/Crosslink_B2.D6")
			(pinfunction "HSIO78NB0")
			(pintype "bidirectional")
			(die_length 5.90226)
		)
		(pad "AA19" smd circle
			(at 5.999 7.599 270)
			(size 0.45 0.45)
			(layers "F.Cu" "F.Mask" "F.Paste")
			(net 48 "+1V8")
			(pinfunction "VDDI0")
			(pintype "power_in")
		)
		(pad "AA20" smd circle
			(at 6.799 7.599 270)
			(size 0.45 0.45)
			(layers "F.Cu" "F.Mask" "F.Paste")
			(net 131 "/FPGA HSIO/Crosslink_B2.D2")
			(pinfunction "HSIO71NB0")
			(pintype "bidirectional")
			(die_length 6.7924)
		)
		(pad "AA21" smd circle
			(at 7.599 7.599 270)
			(size 0.45 0.45)
			(layers "F.Cu" "F.Mask" "F.Paste")
			(net 365 "unconnected-(U1A-HSIO69PB0{slash}DQS{slash}CCC_NE_PLL0_OUT0-PadAA21)")
			(pinfunction "HSIO69PB0/DQS/CCC_NE_PLL0_OUT0")
			(pintype "bidirectional+no_connect")
			(die_length 7.08107)
		)
		(pad "AA22" smd circle
			(at 8.4 7.599 270)
			(size 0.45 0.45)
			(layers "F.Cu" "F.Mask" "F.Paste")
			(net 136 "/FPGA HSIO/Crosslink_B2.D5")
			(pinfunction "HSIO69NB0/DQS")
			(pintype "bidirectional")
			(die_length 7.0736)
		)
		(pad "AB1" smd circle
			(at -8.401 8.4 270)
			(size 0.45 0.45)
			(layers "F.Cu" "F.Mask" "F.Paste")
			(net 417 "GND")
			(pinfunction "VSS")
			(pintype "passive")
		)
		(pad "AB2" smd circle
			(at -7.6 8.4 270)
			(size 0.45 0.45)
			(layers "F.Cu" "F.Mask" "F.Paste")
			(net 316 "/FPGA MSS/LPDDR4.DQ6")
			(pinfunction "MSS_DDR_DQ6")
			(pintype "bidirectional")
			(die_length 6.33626)
		)
		(pad "AB3" smd circle
			(at -6.8 8.4 270)
			(size 0.45 0.45)
			(layers "F.Cu" "F.Mask" "F.Paste")
			(net 319 "/FPGA MSS/LPDDR4.DQ7")
			(pinfunction "MSS_DDR_DQ7")
			(pintype "bidirectional")
			(die_length 5.58315)
		)
		(pad "AB4" smd circle
			(at -6 8.4 270)
			(size 0.45 0.45)
			(layers "F.Cu" "F.Mask" "F.Paste")
			(net 320 "/FPGA MSS/LPDDR4.DMI0")
			(pinfunction "MSS_DDR_DM0")
			(pintype "bidirectional")
			(die_length 5.56141)
		)
		(pad "AB5" smd circle
			(at -5.201 8.4 270)
			(size 0.45 0.45)
			(layers "F.Cu" "F.Mask" "F.Paste")
			(net 321 "/FPGA MSS/LPDDR4.DQ10")
			(pinfunction "MSS_DDR_DQ10")
			(pintype "bidirectional")
			(die_length 6.67168)
		)
		(pad "AB6" smd circle
			(at -4.401 8.4 270)
			(size 0.45 0.45)
			(layers "F.Cu" "F.Mask" "F.Paste")
			(net 2 "+1V1")
			(pinfunction "VDDI6")
			(pintype "passive")
		)
		(pad "AB7" smd circle
			(at -3.601 8.4 270)
			(size 0.45 0.45)
			(layers "F.Cu" "F.Mask" "F.Paste")
			(net 322 "/FPGA MSS/LPDDR4.DQ12")
			(pinfunction "MSS_DDR_DQ12")
			(pintype "bidirectional")
			(die_length 7.08953)
		)
		(pad "AB8" smd circle
			(at -2.8 8.4 270)
			(size 0.45 0.45)
			(layers "F.Cu" "F.Mask" "F.Paste")
			(net 323 "/FPGA MSS/LPDDR4.DQ13")
			(pinfunction "MSS_DDR_DQ13")
			(pintype "bidirectional")
			(die_length 6.89642)
		)
		(pad "AB9" smd circle
			(at -2 8.4 270)
			(size 0.45 0.45)
			(layers "F.Cu" "F.Mask" "F.Paste")
			(net 324 "/FPGA MSS/LPDDR4.DQ18")
			(pinfunction "MSS_DDR_DQ18")
			(pintype "bidirectional")
			(die_length 7.07175)
		)
		(pad "AB10" smd circle
			(at -1.2 8.4 270)
			(size 0.45 0.45)
			(layers "F.Cu" "F.Mask" "F.Paste")
			(net 326 "/FPGA MSS/LPDDR4.DQ19")
			(pinfunction "MSS_DDR_DQ19")
			(pintype "bidirectional")
			(die_length 7.08818)
		)
		(pad "AB11" smd circle
			(at -0.401 8.4 270)
			(size 0.45 0.45)
			(layers "F.Cu" "F.Mask" "F.Paste")
			(net 417 "GND")
			(pinfunction "VSS")
			(pintype "passive")
		)
		(pad "AB12" smd circle
			(at 0.4 8.4 270)
			(size 0.45 0.45)
			(layers "F.Cu" "F.Mask" "F.Paste")
			(net 366 "unconnected-(U1A-HSIO88NB0-PadAB12)")
			(pinfunction "HSIO88NB0")
			(pintype "bidirectional+no_connect")
			(die_length 6.62943)
		)
		(pad "AB13" smd circle
			(at 1.199 8.4 270)
			(size 0.45 0.45)
			(layers "F.Cu" "F.Mask" "F.Paste")
			(net 367 "unconnected-(U1A-HSIO86NB0-PadAB13)")
			(pinfunction "HSIO86NB0")
			(pintype "bidirectional+no_connect")
			(die_length 6.18996)
		)
		(pad "AB14" smd circle
			(at 1.999 8.4 270)
			(size 0.45 0.45)
			(layers "F.Cu" "F.Mask" "F.Paste")
			(net 368 "unconnected-(U1A-HSIO84PB0{slash}CLKIN_N_5-PadAB14)")
			(pinfunction "HSIO84PB0/CLKIN_N_5")
			(pintype "bidirectional+no_connect")
			(die_length 5.95763)
		)
		(pad "AB15" smd circle
			(at 2.799 8.4 270)
			(size 0.45 0.45)
			(layers "F.Cu" "F.Mask" "F.Paste")
			(net 369 "unconnected-(U1A-HSIO84NB0-PadAB15)")
			(pinfunction "HSIO84NB0")
			(pintype "bidirectional+no_connect")
			(die_length 5.94946)
		)
		(pad "AB16" smd circle
			(at 3.6 8.4 270)
			(size 0.45 0.45)
			(layers "F.Cu" "F.Mask" "F.Paste")
			(net 48 "+1V8")
			(pinfunction "VDDI0")
			(pintype "passive")
		)
		(pad "AB17" smd circle
			(at 4.4 8.4 270)
			(size 0.45 0.45)
			(layers "F.Cu" "F.Mask" "F.Paste")
			(net 370 "unconnected-(U1A-HSIO81PB0{slash}DQS-PadAB17)")
			(pinfunction "HSIO81PB0/DQS")
			(pintype "bidirectional+no_connect")
			(die_length 6.85682)
		)
		(pad "AB18" smd circle
			(at 5.2 8.4 270)
			(size 0.45 0.45)
			(layers "F.Cu" "F.Mask" "F.Paste")
			(net 145 "/FPGA HSIO/Crosslink_B2.D9")
			(pinfunction "HSIO78PB0/CLKIN_N_7")
			(pintype "bidirectional")
			(die_length 5.89156)
		)
		(pad "AB19" smd circle
			(at 5.999 8.4 270)
			(size 0.45 0.45)
			(layers "F.Cu" "F.Mask" "F.Paste")
			(net 154 "/FPGA HSIO/Crosslink_B2.D4")
			(pinfunction "HSIO70PB0")
			(pintype "bidirectional")
			(die_length 6.78063)
		)
		(pad "AB20" smd circle
			(at 6.799 8.4 270)
			(size 0.45 0.45)
			(layers "F.Cu" "F.Mask" "F.Paste")
			(net 210 "/FPGA HSIO/Crosslink_B2.D3")
			(pinfunction "HSIO70NB0")
			(pintype "bidirectional")
			(die_length 6.76848)
		)
		(pad "AB21" smd circle
			(at 7.599 8.4 270)
			(size 0.45 0.45)
			(layers "F.Cu" "F.Mask" "F.Paste")
			(net 223 "/FPGA HSIO/Crosslink_B2.D0")
			(pinfunction "HSIO71PB0")
			(pintype "bidirectional")
			(die_length 6.81909)
		)
		(pad "AB22" smd circle
			(at 8.4 8.4 270)
			(size 0.45 0.45)
			(layers "F.Cu" "F.Mask" "F.Paste")
			(net 417 "GND")
			(pinfunction "VSS")
			(pintype "passive")
		)
		(pad "B1" smd circle
			(at -8.401 -7.6 270)
			(size 0.45 0.45)
			(layers "F.Cu" "F.Mask" "F.Paste")
			(net 100 "/FPGA MSSIO/SUPPLY.SDA")
			(pinfunction "MSSIO27B2")
			(pintype "bidirectional")
			(die_length 11.6754)
		)
		(pad "B2" smd circle
			(at -7.6 -7.6 270)
			(size 0.45 0.45)
			(layers "F.Cu" "F.Mask" "F.Paste")
			(net 371 "unconnected-(U1C-MSSIO32B2-PadB2)")
			(pinfunction "MSSIO32B2")
			(pintype "bidirectional+no_connect")
			(die_length 10.9065)
		)
		(pad "B3" smd circle
			(at -6.8 -7.6 270)
			(size 0.45 0.45)
			(layers "F.Cu" "F.Mask" "F.Paste")
			(net 372 "unconnected-(U1C-MSSIO34B2-PadB3)")
			(pinfunction "MSSIO34B2")
			(pintype "bidirectional+no_connect")
			(die_length 10.3654)
		)
		(pad "B4" smd circle
			(at -6 -7.6 270)
			(size 0.45 0.45)
			(layers "F.Cu" "F.Mask" "F.Paste")
			(net 86 "/FPGA GPIO/HDMI_FPGA.TX0_N")
			(pinfunction "GPIO169NB1")
			(pintype "bidirectional")
			(die_length 6.68841)
		)
		(pad "B5" smd circle
			(at -5.201 -7.6 270)
			(size 0.45 0.45)
			(layers "F.Cu" "F.Mask" "F.Paste")
			(net 83 "/FPGA GPIO/HDMI_FPGA.TX1_N")
			(pinfunction "GPIO170NB1/DQS")
			(pintype "bidirectional")
			(die_length 6.42359)
		)
		(pad "B6" smd circle
			(at -4.401 -7.6 270)
			(size 0.45 0.45)
			(layers "F.Cu" "F.Mask" "F.Paste")
			(net 649 "VDD")
			(pinfunction "VDDI1")
			(pintype "passive")
		)
		(pad "B7" smd circle
			(at -3.601 -7.6 270)
			(size 0.45 0.45)
			(layers "F.Cu" "F.Mask" "F.Paste")
			(net 373 "unconnected-(U1B-GPIO173NB1-PadB7)")
			(pinfunction "GPIO173NB1")
			(pintype "bidirectional+no_connect")
			(die_length 6.39951)
		)
		(pad "B8" smd circle
			(at -2.8 -7.6 270)
			(size 0.45 0.45)
			(layers "F.Cu" "F.Mask" "F.Paste")
			(net 353 "/FPGA GPIO/HDMI0_SCL_SRC")
			(pinfunction "GPIO175NB1")
			(pintype "bidirectional")
			(die_length 6.72389)
		)
		(pad "B9" smd circle
			(at -2 -7.6 270)
			(size 0.45 0.45)
			(layers "F.Cu" "F.Mask" "F.Paste")
			(net 345 "/FPGA GPIO/Crosslink.CS")
			(pinfunction "GPIO179NB1")
			(pintype "bidirectional")
			(die_length 7.41584)
		)
		(pad "B10" smd circle
			(at -1.2 -7.6 270)
			(size 0.45 0.45)
			(layers "F.Cu" "F.Mask" "F.Paste")
			(net 346 "/FPGA GPIO/Crosslink.MOSI")
			(pinfunction "GPIO179PB1")
			(pintype "bidirectional")
			(die_length 7.43586)
		)
		(pad "B11" smd circle
			(at -0.401 -7.6 270)
			(size 0.45 0.45)
			(layers "F.Cu" "F.Mask" "F.Paste")
			(net 417 "GND")
			(pinfunction "VSS")
			(pintype "passive")
		)
		(pad "B12" smd circle
			(at 0.4 -7.6 270)
			(size 0.45 0.45)
			(layers "F.Cu" "F.Mask" "F.Paste")
			(net 111 "/Bottom Connector/CAM0.D0_P")
			(pinfunction "GPIO0PB1/CLKIN_S_4")
			(pintype "bidirectional")
			(die_length 7.45678)
		)
		(pad "B13" smd circle
			(at 1.199 -7.6 270)
			(size 0.45 0.45)
			(layers "F.Cu" "F.Mask" "F.Paste")
			(net 120 "/Bottom Connector/CAM0.C_P")
			(pinfunction "GPIO3PB1/CLKIN_S_6")
			(pintype "bidirectional")
			(die_length 7.81993)
		)
		(pad "B14" smd circle
			(at 1.999 -7.6 270)
			(size 0.45 0.45)
			(layers "F.Cu" "F.Mask" "F.Paste")
			(net 118 "/Bottom Connector/CAM0.C_N")
			(pinfunction "GPIO3NB1")
			(pintype "bidirectional")
			(die_length 7.83621)
		)
		(pad "B15" smd circle
			(at 2.799 -7.6 270)
			(size 0.45 0.45)
			(layers "F.Cu" "F.Mask" "F.Paste")
			(net 349 "/FPGA GPIO/PF_ETH_MDIO")
			(pinfunction "GPIO5NB1")
			(pintype "bidirectional")
			(die_length 7.64736)
		)
		(pad "B16" smd circle
			(at 3.6 -7.6 270)
			(size 0.45 0.45)
			(layers "F.Cu" "F.Mask" "F.Paste")
			(net 649 "VDD")
			(pinfunction "VDDI1")
			(pintype "passive")
		)
		(pad "B17" smd circle
			(at 4.4 -7.6 270)
			(size 0.45 0.45)
			(layers "F.Cu" "F.Mask" "F.Paste")
			(net 24 "SPI6_MISO{slash}RPI_GPIO19")
			(pinfunction "GPIO15PB1/CCC_SE_CLKIN_S_10/CCC_SE_PLL1_OUT0")
			(pintype "bidirectional")
			(die_length 10.4627)
		)
		(pad "B18" smd circle
			(at 5.2 -7.6 270)
			(size 0.45 0.45)
			(layers "F.Cu" "F.Mask" "F.Paste")
			(net 26 "GPIO27")
			(pinfunction "GPIO17NB1")
			(pintype "bidirectional")
			(die_length 10.8909)
		)
		(pad "B19" smd circle
			(at 5.999 -7.6 270)
			(size 0.45 0.45)
			(layers "F.Cu" "F.Mask" "F.Paste")
			(net 354 "/FPGA GPIO/WiFi_DATA_2")
			(pinfunction "GPIO19NB9")
			(pintype "bidirectional")
			(die_length 9.83847)
		)
		(pad "B20" smd circle
			(at 6.799 -7.6 270)
			(size 0.45 0.45)
			(layers "F.Cu" "F.Mask" "F.Paste")
			(net 355 "/FPGA GPIO/WiFi_DATA_1")
			(pinfunction "GPIO19PB9")
			(pintype "bidirectional")
			(die_length 9.84464)
		)
		(pad "B21" smd circle
			(at 7.599 -7.6 270)
			(size 0.45 0.45)
			(layers "F.Cu" "F.Mask" "F.Paste")
			(net 350 "/FPGA GPIO/SCL0_PF")
			(pinfunction "GPIO22PB9")
			(pintype "bidirectional")
			(die_length 10.6697)
		)
		(pad "B22" smd circle
			(at 8.4 -7.6 270)
			(size 0.45 0.45)
			(layers "F.Cu" "F.Mask" "F.Paste")
			(net 509 "/FPGA GPIO/SDA0_PF")
			(pinfunction "GPIO22NB9")
			(pintype "bidirectional")
			(die_length 10.6676)
		)
		(pad "C1" smd circle
			(at -8.401 -6.8 270)
			(size 0.45 0.45)
			(layers "F.Cu" "F.Mask" "F.Paste")
			(net 92 "/FPGA MSSIO/SUPPLY.SCL")
			(pinfunction "MSSIO26B2")
			(pintype "bidirectional")
			(die_length 10.9779)
		)
		(pad "C2" smd circle
			(at -7.6 -6.8 270)
			(size 0.45 0.45)
			(layers "F.Cu" "F.Mask" "F.Paste")
			(net 383 "unconnected-(U1C-MSSIO29B2-PadC2)")
			(pinfunction "MSSIO29B2")
			(pintype "bidirectional+no_connect")
			(die_length 10.7338)
		)
		(pad "C3" smd circle
			(at -6.8 -6.8 270)
			(size 0.45 0.45)
			(layers "F.Cu" "F.Mask" "F.Paste")
			(net 649 "VDD")
			(pinfunction "VDDI2")
			(pintype "power_in")
		)
		(pad "C4" smd circle
			(at -6 -6.8 270)
			(size 0.45 0.45)
			(layers "F.Cu" "F.Mask" "F.Paste")
			(net 87 "/FPGA GPIO/HDMI_FPGA.TX0_P")
			(pinfunction "GPIO169PB1/CCC_SW_CLKIN_S_1")
			(pintype "bidirectional")
			(die_length 6.70234)
		)
		(pad "C5" smd circle
			(at -5.201 -6.8 270)
			(size 0.45 0.45)
			(layers "F.Cu" "F.Mask" "F.Paste")
			(net 84 "/FPGA GPIO/HDMI_FPGA.TX1_P")
			(pinfunction "GPIO170PB1/DQS/CCC_SW_PLL1_OUT0")
			(pintype "bidirectional")
			(die_length 6.43731)
		)
		(pad "C6" smd circle
			(at -4.401 -6.8 270)
			(size 0.45 0.45)
			(layers "F.Cu" "F.Mask" "F.Paste")
			(net 11 "GPIO16")
			(pinfunction "GPIO171PB1/CLKIN_S_2/CCC_SW_CLKIN_S_2/CCC_SW_PLL1_OUT0")
			(pintype "bidirectional")
			(die_length 6.13895)
		)
		(pad "C7" smd circle
			(at -3.601 -6.8 270)
			(size 0.45 0.45)
			(layers "F.Cu" "F.Mask" "F.Paste")
			(net 375 "unconnected-(U1B-GPIO171NB1-PadC7)")
			(pinfunction "GPIO171NB1")
			(pintype "bidirectional+no_connect")
			(die_length 6.14822)
		)
		(pad "C8" smd circle
			(at -2.8 -6.8 270)
			(size 0.45 0.45)
			(layers "F.Cu" "F.Mask" "F.Paste")
			(net 417 "GND")
			(pinfunction "VSS")
			(pintype "passive")
		)
		(pad "C9" smd circle
			(at -2 -6.8 270)
			(size 0.45 0.45)
			(layers "F.Cu" "F.Mask" "F.Paste")
			(net 356 "/FPGA GPIO/HDMI0_HPD_SRC")
			(pinfunction "GPIO176NB1/DQS")
			(pintype "bidirectional")
			(die_length 7.80518)
		)
		(pad "C10" smd circle
			(at -1.2 -6.8 270)
			(size 0.45 0.45)
			(layers "F.Cu" "F.Mask" "F.Paste")
			(net 18 "GPIO11")
			(pinfunction "GPIO176PB1/DQS/CCC_SW_PLL0_OUT0")
			(pintype "bidirectional")
			(die_length 7.81684)
		)
		(pad "C11" smd circle
			(at -0.401 -6.8 270)
			(size 0.45 0.45)
			(layers "F.Cu" "F.Mask" "F.Paste")
			(net 559 "unconnected-(U1B-GPIO178PB1{slash}CCC_SW_PLL0_OUT1-PadC11)")
			(pinfunction "GPIO178PB1/CCC_SW_PLL0_OUT1")
			(pintype "bidirectional+no_connect")
			(die_length 8.84089)
		)
		(pad "C12" smd circle
			(at 0.4 -6.8 270)
			(size 0.45 0.45)
			(layers "F.Cu" "F.Mask" "F.Paste")
			(net 109 "/Bottom Connector/CAM0.D0_N")
			(pinfunction "GPIO0NB1")
			(pintype "bidirectional")
			(die_length 7.46342)
		)
		(pad "C13" smd circle
			(at 1.199 -6.8 270)
			(size 0.45 0.45)
			(layers "F.Cu" "F.Mask" "F.Paste")
			(net 649 "VDD")
			(pinfunction "VDDI1")
			(pintype "passive")
		)
		(pad "C14" smd circle
			(at 1.999 -6.8 270)
			(size 0.45 0.45)
			(layers "F.Cu" "F.Mask" "F.Paste")
			(net 376 "unconnected-(U1B-GPIO4PB1{slash}LPRB_A-PadC14)")
			(pinfunction "GPIO4PB1/LPRB_A")
			(pintype "bidirectional+no_connect")
			(die_length 8.46872)
		)
		(pad "C15" smd circle
			(at 2.799 -6.8 270)
			(size 0.45 0.45)
			(layers "F.Cu" "F.Mask" "F.Paste")
			(net 377 "unconnected-(U1B-GPIO4NB1{slash}LPRB_B-PadC15)")
			(pinfunction "GPIO4NB1/LPRB_B")
			(pintype "bidirectional+no_connect")
			(die_length 8.50071)
		)
		(pad "C16" smd circle
			(at 3.6 -6.8 270)
			(size 0.45 0.45)
			(layers "F.Cu" "F.Mask" "F.Paste")
			(net 177 "SDA1{slash}RPI_GPIO02")
			(pinfunction "GPIO12PB1")
			(pintype "bidirectional")
			(die_length 10.1134)
		)
		(pad "C17" smd circle
			(at 4.4 -6.8 270)
			(size 0.45 0.45)
			(layers "F.Cu" "F.Mask" "F.Paste")
			(net 25 "SPI6_MOSI{slash}RPI_GPIO20")
			(pinfunction "GPIO15NB1")
			(pintype "bidirectional")
			(die_length 10.4762)
		)
		(pad "C18" smd circle
			(at 5.2 -6.8 270)
			(size 0.45 0.45)
			(layers "F.Cu" "F.Mask" "F.Paste")
			(net 417 "GND")
			(pinfunction "VSS")
			(pintype "passive")
		)
		(pad "C19" smd circle
			(at 5.999 -6.8 270)
			(size 0.45 0.45)
			(layers "F.Cu" "F.Mask" "F.Paste")
			(net 358 "/FPGA GPIO/WiFi_CMD")
			(pinfunction "GPIO18PB9")
			(pintype "bidirectional")
			(die_length 9.19379)
		)
		(pad "C20" smd circle
			(at 6.799 -6.8 270)
			(size 0.45 0.45)
			(layers "F.Cu" "F.Mask" "F.Paste")
			(net 374 "/FPGA GPIO/WiFi_DATA_0")
			(pinfunction "GPIO18NB9")
			(pintype "bidirectional")
			(die_length 9.14934)
		)
		(pad "C21" smd circle
			(at 7.599 -6.8 270)
			(size 0.45 0.45)
			(layers "F.Cu" "F.Mask" "F.Paste")
			(net 649 "VDD")
			(pinfunction "VDDI1")
			(pintype "passive")
		)
		(pad "C22" smd circle
			(at 8.4 -6.8 270)
			(size 0.45 0.45)
			(layers "F.Cu" "F.Mask" "F.Paste")
			(net 378 "unconnected-(U1B-GPIO23PB9-PadC22)")
			(pinfunction "GPIO23PB9")
			(pintype "bidirectional+no_connect")
			(die_length 10.3467)
		)
		(pad "D1" smd circle
			(at -8.401 -6 270)
			(size 0.45 0.45)
			(layers "F.Cu" "F.Mask" "F.Paste")
			(net 637 "/FPGA GPIO/ULPI.DATA4")
			(pinfunction "MSSIO22B2")
			(pintype "bidirectional")
			(die_length 10.1837)
		)
		(pad "D2" smd circle
			(at -7.6 -6 270)
			(size 0.45 0.45)
			(layers "F.Cu" "F.Mask" "F.Paste")
			(net 638 "/FPGA GPIO/ULPI.DATA5")
			(pinfunction "MSSIO23B2")
			(pintype "bidirectional")
			(die_length 9.99134)
		)
		(pad "D3" smd circle
			(at -6.8 -6 270)
			(size 0.45 0.45)
			(layers "F.Cu" "F.Mask" "F.Paste")
			(net 284 "unconnected-(U1C-MSSIO28B2-PadD3)")
			(pinfunction "MSSIO28B2")
			(pintype "bidirectional+no_connect")
			(die_length 9.49076)
		)
		(pad "D4" smd circle
			(at -6 -6 270)
			(size 0.45 0.45)
			(layers "F.Cu" "F.Mask" "F.Paste")
			(net 380 "unconnected-(U1C-MSSIO37B2-PadD4)")
			(pinfunction "MSSIO37B2")
			(pintype "bidirectional+no_connect")
			(die_length 9.41653)
		)
		(pad "D5" smd circle
			(at -5.201 -6 270)
			(size 0.45 0.45)
			(layers "F.Cu" "F.Mask" "F.Paste")
			(net 417 "GND")
			(pinfunction "VSS")
			(pintype "passive")
		)
		(pad "D6" smd circle
			(at -4.401 -6 270)
			(size 0.45 0.45)
			(layers "F.Cu" "F.Mask" "F.Paste")
			(net 27 "UART5_TX{slash}RPI_GPIO13")
			(pinfunction "GPIO168NB1")
			(pintype "bidirectional")
			(die_length 5.98256)
		)
		(pad "D7" smd circle
			(at -3.601 -6 270)
			(size 0.45 0.45)
			(layers "F.Cu" "F.Mask" "F.Paste")
			(net 381 "unconnected-(U1B-GPIO168PB1{slash}CCC_SW_CLKIN_S_0-PadD7)")
			(pinfunction "GPIO168PB1/CCC_SW_CLKIN_S_0")
			(pintype "bidirectional+no_connect")
			(die_length 5.98411)
		)
		(pad "D8" smd circle
			(at -2.8 -6 270)
			(size 0.45 0.45)
			(layers "F.Cu" "F.Mask" "F.Paste")
			(net 60 "/FPGA GPIO/HDMI_FPGA.TX2_N")
			(pinfunction "GPIO174NB1")
			(pintype "bidirectional")
			(die_length 7.07352)
		)
		(pad "D9" smd circle
			(at -2 -6 270)
			(size 0.45 0.45)
			(layers "F.Cu" "F.Mask" "F.Paste")
			(net 82 "/FPGA GPIO/HDMI_FPGA.TX2_P")
			(pinfunction "GPIO174PB1")
			(pintype "bidirectional")
			(die_length 7.0517)
		)
		(pad "D10" smd circle
			(at -1.2 -6 270)
			(size 0.45 0.45)
			(layers "F.Cu" "F.Mask" "F.Paste")
			(net 649 "VDD")
			(pinfunction "VDDI1")
			(pintype "passive")
		)
		(pad "D11" smd circle
			(at -0.401 -6 270)
			(size 0.45 0.45)
			(layers "F.Cu" "F.Mask" "F.Paste")
			(net 537 "/FPGA GPIO/Crosslink.SDA")
			(pinfunction "GPIO178NB1")
			(pintype "bidirectional")
			(die_length 8.80638)
		)
		(pad "D12" smd circle
			(at 0.4 -6 270)
			(size 0.45 0.45)
			(layers "F.Cu" "F.Mask" "F.Paste")
			(net 342 "/FPGA GPIO/USER_LED_R")
			(pinfunction "GPIO183PB1")
			(pintype "bidirectional")
			(die_length 11.0319)
		)
		(pad "D13" smd circle
			(at 1.199 -6 270)
			(size 0.45 0.45)
			(layers "F.Cu" "F.Mask" "F.Paste")
			(net 89 "/FPGA GPIO/HDMI_FPGA.CLK_P")
			(pinfunction "GPIO2PB1/DQS")
			(pintype "bidirectional")
			(die_length 8.05981)
		)
		(pad "D14" smd circle
			(at 1.999 -6 270)
			(size 0.45 0.45)
			(layers "F.Cu" "F.Mask" "F.Paste")
			(net 88 "/FPGA GPIO/HDMI_FPGA.CLK_N")
			(pinfunction "GPIO2NB1/DQS")
			(pintype "bidirectional")
			(die_length 8.06844)
		)
		(pad "D15" smd circle
			(at 2.799 -6 270)
			(size 0.45 0.45)
			(layers "F.Cu" "F.Mask" "F.Paste")
			(net 417 "GND")
			(pinfunction "VSS")
			(pintype "passive")
		)
		(pad "D16" smd circle
			(at 3.6 -6 270)
			(size 0.45 0.45)
			(layers "F.Cu" "F.Mask" "F.Paste")
			(net 382 "unconnected-(U1B-GPIO10NB1-PadD16)")
			(pinfunction "GPIO10NB1")
			(pintype "bidirectional+no_connect")
			(die_length 10.5394)
		)
		(pad "D17" smd circle
			(at 4.4 -6 270)
			(size 0.45 0.45)
			(layers "F.Cu" "F.Mask" "F.Paste")
			(net 174 "SCL1{slash}RPI_GPIO03")
			(pinfunction "GPIO12NB1")
			(pintype "bidirectional")
			(die_length 10.1368)
		)
		(pad "D18" smd circle
			(at 5.2 -6 270)
			(size 0.45 0.45)
			(layers "F.Cu" "F.Mask" "F.Paste")
			(net 20 "SPI6_SCLK{slash}RPI_GPIO21")
			(pinfunction "GPIO16PB1/CCC_SE_PLL1_OUT1")
			(pintype "bidirectional")
			(die_length 10.3636)
		)
		(pad "D19" smd circle
			(at 5.999 -6 270)
			(size 0.45 0.45)
			(layers "F.Cu" "F.Mask" "F.Paste")
			(net 29 "UART5_TX{slash}RPI_GPIO12")
			(pinfunction "GPIO14NB1/DQS")
			(pintype "bidirectional")
			(die_length 10.7354)
		)
		(pad "D20" smd circle
			(at 6.799 -6 270)
			(size 0.45 0.45)
			(layers "F.Cu" "F.Mask" "F.Paste")
			(net 543 "/FPGA GPIO/PCIe_nRST_PF")
			(pinfunction "GPIO21NB9")
			(pintype "bidirectional")
			(die_length 9.54946)
		)
		(pad "D21" smd circle
			(at 7.599 -6 270)
			(size 0.45 0.45)
			(layers "F.Cu" "F.Mask" "F.Paste")
			(net 544 "/FPGA GPIO/PCIe_CLK_nREQ_PF")
			(pinfunction "GPIO21PB9")
			(pintype "bidirectional")
			(die_length 9.60192)
		)
		(pad "D22" smd circle
			(at 8.4 -6 270)
			(size 0.45 0.45)
			(layers "F.Cu" "F.Mask" "F.Paste")
			(net 635 "/FPGA GPIO/ULPI.RESET")
			(pinfunction "GPIO23NB9")
			(pintype "bidirectional")
			(die_length 10.342)
		)
		(pad "E1" smd circle
			(at -8.401 -5.201 270)
			(size 0.45 0.45)
			(layers "F.Cu" "F.Mask" "F.Paste")
			(net 639 "/FPGA GPIO/ULPI.DATA1")
			(pinfunction "MSSIO19B2")
			(pintype "bidirectional")
			(die_length 9.80097)
		)
		(pad "E2" smd circle
			(at -7.6 -5.201 270)
			(size 0.45 0.45)
			(layers "F.Cu" "F.Mask" "F.Paste")
			(net 417 "GND")
			(pinfunction "VSS")
			(pintype "passive")
		)
		(pad "E3" smd circle
			(at -6.8 -5.201 270)
			(size 0.45 0.45)
			(layers "F.Cu" "F.Mask" "F.Paste")
			(net 295 "Net-(U1C-MSSIO36B2)")
			(pinfunction "MSSIO36B2")
			(pintype "bidirectional")
			(die_length 8.49579)
		)
		(pad "E4" smd circle
			(at -6 -5.201 270)
			(size 0.45 0.45)
			(layers "F.Cu" "F.Mask" "F.Paste")
			(net 384 "unconnected-(U1C-MSSIO31B2-PadE4)")
			(pinfunction "MSSIO31B2")
			(pintype "bidirectional+no_connect")
			(die_length 10.1708)
		)
		(pad "E5" smd circle
			(at -5.201 -5.201 270)
			(size 0.45 0.45)
			(layers "F.Cu" "F.Mask" "F.Paste")
			(net 428 "PAC1934_SLOW")
			(pinfunction "MSSIO30B2")
			(pintype "bidirectional")
			(die_length 11.7656)
		)
		(pad "E6" smd circle
			(at -4.401 -5.201 270)
			(size 0.45 0.45)
			(layers "F.Cu" "F.Mask" "F.Paste")
			(net 286 "/FPGA Config/Flash.CLK")
			(pinfunction "SCK")
			(pintype "bidirectional")
			(die_length 5.66068)
		)
		(pad "E7" smd circle
			(at -3.601 -5.201 270)
			(size 0.45 0.45)
			(layers "F.Cu" "F.Mask" "F.Paste")
			(net 50 "+3V3")
			(pinfunction "VDDI3")
			(pintype "power_in")
		)
		(pad "E8" smd circle
			(at -2.8 -5.201 270)
			(size 0.45 0.45)
			(layers "F.Cu" "F.Mask" "F.Paste")
			(net 189 "Net-(U1D-TDO)")
			(pinfunction "TDO")
			(pintype "output")
			(die_length 4.21041)
		)
		(pad "E9" smd circle
			(at -2 -5.201 270)
			(size 0.45 0.45)
			(layers "F.Cu" "F.Mask" "F.Paste")
			(net 124 "JTAG_TCK")
			(pinfunction "TCK")
			(pintype "input")
			(die_length 4.35251)
		)
		(pad "E10" smd circle
			(at -1.2 -5.201 270)
			(size 0.45 0.45)
			(layers "F.Cu" "F.Mask" "F.Paste")
			(net 545 "/FPGA GPIO/Crosslink.CLK")
			(pinfunction "GPIO180PB1")
			(pintype "bidirectional")
			(die_length 11.3535)
		)
		(pad "E11" smd circle
			(at -0.401 -5.201 270)
			(size 0.45 0.45)
			(layers "F.Cu" "F.Mask" "F.Paste")
			(net 341 "/FPGA GPIO/USER_LED_G")
			(pinfunction "GPIO183NB1")
			(pintype "bidirectional")
			(die_length 11.0538)
		)
		(pad "E12" smd circle
			(at 0.4 -5.201 270)
			(size 0.45 0.45)
			(layers "F.Cu" "F.Mask" "F.Paste")
			(net 417 "GND")
			(pinfunction "VSS")
			(pintype "passive")
		)
		(pad "E13" smd circle
			(at 1.199 -5.201 270)
			(size 0.45 0.45)
			(layers "F.Cu" "F.Mask" "F.Paste")
			(net 224 "/FPGA GPIO/USER_LED_B")
			(pinfunction "GPIO184PB1")
			(pintype "bidirectional")
			(die_length 12.5139)
		)
		(pad "E14" smd circle
			(at 1.999 -5.201 270)
			(size 0.45 0.45)
			(layers "F.Cu" "F.Mask" "F.Paste")
			(net 21 "GPIO25")
			(pinfunction "GPIO9NB1")
			(pintype "bidirectional")
			(die_length 10.4171)
		)
		(pad "E15" smd circle
			(at 2.799 -5.201 270)
			(size 0.45 0.45)
			(layers "F.Cu" "F.Mask" "F.Paste")
			(net 386 "unconnected-(U1B-GPIO9PB1{slash}CLKIN_S_8{slash}CCC_SE_CLKIN_S_8{slash}CCC_SE_PLL0_OUT0-PadE15)")
			(pinfunction "GPIO9PB1/CLKIN_S_8/CCC_SE_CLKIN_S_8/CCC_SE_PLL0_OUT0")
			(pintype "bidirectional+no_connect")
			(die_length 10.4372)
		)
		(pad "E16" smd circle
			(at 3.6 -5.201 270)
			(size 0.45 0.45)
			(layers "F.Cu" "F.Mask" "F.Paste")
			(net 289 "~{Crosslink_RESET}")
			(pinfunction "GPIO10PB1/CCC_SE_PLL0_OUT1")
			(pintype "bidirectional")
			(die_length 10.5384)
		)
		(pad "E17" smd circle
			(at 4.4 -5.201 270)
			(size 0.45 0.45)
			(layers "F.Cu" "F.Mask" "F.Paste")
			(net 649 "VDD")
			(pinfunction "VDDI1")
			(pintype "passive")
		)
		(pad "E18" smd circle
			(at 5.2 -5.201 270)
			(size 0.45 0.45)
			(layers "F.Cu" "F.Mask" "F.Paste")
			(net 23 "GPIO24")
			(pinfunction "GPIO16NB1")
			(pintype "bidirectional")
			(die_length 10.4012)
		)
		(pad "E19" smd circle
			(at 5.999 -5.201 270)
			(size 0.45 0.45)
			(layers "F.Cu" "F.Mask" "F.Paste")
			(net 22 "GPIO10")
			(pinfunction "GPIO14PB1/DQS/CCC_SE_PLL1_OUT0")
			(pintype "bidirectional")
			(die_length 10.7473)
		)
		(pad "E20" smd circle
			(at 6.799 -5.201 270)
			(size 0.45 0.45)
			(layers "F.Cu" "F.Mask" "F.Paste")
			(net 417 "GND")
			(pinfunction "VSS")
			(pintype "passive")
		)
		(pad "E21" smd circle
			(at 7.599 -5.201 270)
			(size 0.45 0.45)
			(layers "F.Cu" "F.Mask" "F.Paste")
			(net 417 "GND")
			(pinfunction "VSS")
			(pintype "passive")
		)
		(pad "E22" smd circle
			(at 8.4 -5.201 270)
			(size 0.45 0.45)
			(layers "F.Cu" "F.Mask" "F.Paste")
			(net 417 "GND")
			(pinfunction "VSS")
			(pintype "passive")
		)
		(pad "F1" smd circle
			(at -8.401 -4.401 270)
			(size 0.45 0.45)
			(layers "F.Cu" "F.Mask" "F.Paste")
			(net 640 "/FPGA GPIO/ULPI.DIR")
			(pinfunction "MSSIO15B2")
			(pintype "bidirectional")
			(die_length 9.16566)
		)
		(pad "F2" smd circle
			(at -7.6 -4.401 270)
			(size 0.45 0.45)
			(layers "F.Cu" "F.Mask" "F.Paste")
			(net 641 "/FPGA GPIO/ULPI.DATA0")
			(pinfunction "MSSIO18B2")
			(pintype "bidirectional")
			(die_length 8.71051)
		)
		(pad "F3" smd circle
			(at -6.8 -4.401 270)
			(size 0.45 0.45)
			(layers "F.Cu" "F.Mask" "F.Paste")
			(net 642 "/FPGA GPIO/ULPI.DATA7")
			(pinfunction "MSSIO25B2")
			(pintype "bidirectional")
			(die_length 8.44991)
		)
		(pad "F4" smd circle
			(at -6 -4.401 270)
			(size 0.45 0.45)
			(layers "F.Cu" "F.Mask" "F.Paste")
			(net 649 "VDD")
			(pinfunction "VDDI2")
			(pintype "passive")
		)
		(pad "F5" smd circle
			(at -5.201 -4.401 270)
			(size 0.45 0.45)
			(layers "F.Cu" "F.Mask" "F.Paste")
			(net 643 "/FPGA GPIO/ULPI.DATA3")
			(pinfunction "MSSIO21B2")
			(pintype "bidirectional")
			(die_length 11.2446)
		)
		(pad "F6" smd circle
			(at -4.401 -4.401 270)
			(size 0.45 0.45)
			(layers "F.Cu" "F.Mask" "F.Paste")
			(net 644 "/FPGA GPIO/ULPI.DATA6")
			(pinfunction "MSSIO24B2")
			(pintype "bidirectional")
			(die_length 11.3029)
		)
		(pad "F7" smd circle
			(at -3.601 -4.401 270)
			(size 0.45 0.45)
			(layers "F.Cu" "F.Mask" "F.Paste")
			(net 287 "/FPGA Config/Flash.MOSI")
			(pinfunction "SDO")
			(pintype "output")
			(die_length 5.03293)
		)
		(pad "F8" smd circle
			(at -2.8 -4.401 270)
			(size 0.45 0.45)
			(layers "F.Cu" "F.Mask" "F.Paste")
			(net 123 "JTAG_TMS")
			(pinfunction "TMS")
			(pintype "input")
			(die_length 4.98175)
		)
		(pad "F9" smd circle
			(at -2 -4.401 270)
			(size 0.45 0.45)
			(layers "F.Cu" "F.Mask" "F.Paste")
			(net 417 "GND")
			(pinfunction "VSS")
			(pintype "passive")
		)
		(pad "F10" smd circle
			(at -1.2 -4.401 270)
			(size 0.45 0.45)
			(layers "F.Cu" "F.Mask" "F.Paste")
			(net 563 "/FPGA GPIO/Crosslink.MISO")
			(pinfunction "GPIO180NB1")
			(pintype "bidirectional")
			(die_length 11.3496)
		)
		(pad "F11" smd circle
			(at -0.401 -4.401 270)
			(size 0.45 0.45)
			(layers "F.Cu" "F.Mask" "F.Paste")
			(net 63 "SDA6{slash}RPI_GPIO22")
			(pinfunction "GPIO181NB1")
			(pintype "bidirectional")
			(die_length 11.0237)
		)
		(pad "F12" smd circle
			(at 0.4 -4.401 270)
			(size 0.45 0.45)
			(layers "F.Cu" "F.Mask" "F.Paste")
			(net 564 "/FPGA GPIO/Crosslink.SCL")
			(pinfunction "GPIO181PB1")
			(pintype "bidirectional")
			(die_length 11.0311)
		)
		(pad "F13" smd circle
			(at 1.199 -4.401 270)
			(size 0.45 0.45)
			(layers "F.Cu" "F.Mask" "F.Paste")
			(net 219 "unconnected-(U1B-GPIO184NB1-PadF13)")
			(pinfunction "GPIO184NB1")
			(pintype "bidirectional+no_connect")
			(die_length 12.4935)
		)
		(pad "F14" smd circle
			(at 1.999 -4.401 270)
			(size 0.45 0.45)
			(layers "F.Cu" "F.Mask" "F.Paste")
			(net 649 "VDD")
			(pinfunction "VDDI1")
			(pintype "passive")
		)
		(pad "F15" smd circle
			(at 2.799 -4.401 270)
			(size 0.45 0.45)
			(layers "F.Cu" "F.Mask" "F.Paste")
			(net 565 "/FPGA GPIO/PF_ETH_PWDN_n")
			(pinfunction "GPIO6PB1")
			(pintype "bidirectional")
			(die_length 10.3454)
		)
		(pad "F16" smd circle
			(at 3.6 -4.401 270)
			(size 0.45 0.45)
			(layers "F.Cu" "F.Mask" "F.Paste")
			(net 132 "SCL6{slash}RPI_GPIO23")
			(pinfunction "GPIO11NB1")
			(pintype "bidirectional")
			(die_length 10.7073)
		)
		(pad "F17" smd circle
			(at 4.4 -4.401 270)
			(size 0.45 0.45)
			(layers "F.Cu" "F.Mask" "F.Paste")
			(net 392 "unconnected-(U1B-GPIO11PB1{slash}CLKIN_S_9{slash}CCC_SE_CLKIN_S_9-PadF17)")
			(pinfunction "GPIO11PB1/CLKIN_S_9/CCC_SE_CLKIN_S_9")
			(pintype "bidirectional+no_connect")
			(die_length 10.7212)
		)
		(pad "F18" smd circle
			(at 5.2 -4.401 270)
			(size 0.45 0.45)
			(layers "F.Cu" "F.Mask" "F.Paste")
			(net 417 "GND")
			(pinfunction "VSS")
			(pintype "passive")
		)
		(pad "F19" smd circle
			(at 5.999 -4.401 270)
			(size 0.45 0.45)
			(layers "F.Cu" "F.Mask" "F.Paste")
			(net 417 "GND")
			(pinfunction "VSS")
			(pintype "passive")
		)
		(pad "F20" smd circle
			(at 6.799 -4.401 270)
			(size 0.45 0.45)
			(layers "F.Cu" "F.Mask" "F.Paste")
			(net 417 "GND")
			(pinfunction "VSS")
			(pintype "passive")
		)
		(pad "F21" smd circle
			(at 7.599 -4.401 270)
			(size 0.45 0.45)
			(layers "F.Cu" "F.Mask" "F.Paste")
			(net 53 "/PCIe/XCVR_TX0_N")
			(pinfunction "XCVR_0_TX0_N")
			(pintype "output")
			(die_length 8.36558)
		)
		(pad "F22" smd circle
			(at 8.4 -4.401 270)
			(size 0.45 0.45)
			(layers "F.Cu" "F.Mask" "F.Paste")
			(net 64 "/PCIe/XCVR_TX0_P")
			(pinfunction "XCVR_0_TX0_P")
			(pintype "output")
			(die_length 8.34976)
		)
		(pad "G1" smd circle
			(at -8.401 -3.601 270)
			(size 0.45 0.45)
			(layers "F.Cu" "F.Mask" "F.Paste")
			(net 649 "VDD")
			(pinfunction "VDDI2")
			(pintype "passive")
		)
		(pad "G2" smd circle
			(at -7.6 -3.601 270)
			(size 0.45 0.45)
			(layers "F.Cu" "F.Mask" "F.Paste")
			(net 636 "/FPGA GPIO/ULPI.CLK")
			(pinfunction "MSSIO14B2")
			(pintype "bidirectional")
			(die_length 8.06194)
		)
		(pad "G3" smd circle
			(at -6.8 -3.601 270)
			(size 0.45 0.45)
			(layers "F.Cu" "F.Mask" "F.Paste")
			(net 645 "/FPGA GPIO/ULPI.DATA2")
			(pinfunction "MSSIO20B2")
			(pintype "bidirectional")
			(die_length 7.76964)
		)
		(pad "G4" smd circle
			(at -6 -3.601 270)
			(size 0.45 0.45)
			(layers "F.Cu" "F.Mask" "F.Paste")
			(net 646 "/FPGA GPIO/ULPI.STP")
			(pinfunction "MSSIO17B2")
			(pintype "bidirectional")
			(die_length 9.16295)
		)
		(pad "G5" smd circle
			(at -5.201 -3.601 270)
			(size 0.45 0.45)
			(layers "F.Cu" "F.Mask" "F.Paste")
			(net 647 "/FPGA GPIO/ULPI.NXT")
			(pinfunction "MSSIO16B2")
			(pintype "bidirectional")
			(die_length 10.71)
		)
		(pad "G6" smd circle
			(at -4.401 -3.601 270)
			(size 0.45 0.45)
			(layers "F.Cu" "F.Mask" "F.Paste")
			(net 417 "GND")
			(pinfunction "VSS")
			(pintype "passive")
		)
		(pad "G7" smd circle
			(at -3.601 -3.601 270)
			(size 0.45 0.45)
			(layers "F.Cu" "F.Mask" "F.Paste")
			(net 288 "/FPGA Config/Flash.CS")
			(pinfunction "SS")
			(pintype "bidirectional")
			(die_length 5.17538)
		)
		(pad "G8" smd circle
			(at -2.8 -3.601 270)
			(size 0.45 0.45)
			(layers "F.Cu" "F.Mask" "F.Paste")
			(net 127 "JTAG_RESET_n")
			(pinfunction "TRSTB")
			(pintype "input")
			(die_length 4.93266)
		)
		(pad "G9" smd circle
			(at -2 -3.601 270)
			(size 0.45 0.45)
			(layers "F.Cu" "F.Mask" "F.Paste")
			(net 126 "JTAG_TDI")
			(pinfunction "TDI")
			(pintype "input")
			(die_length 5.59612)
		)
		(pad "G10" smd circle
			(at -1.2 -3.601 270)
			(size 0.45 0.45)
			(layers "F.Cu" "F.Mask" "F.Paste")
			(net 254 "Net-(U1D-FF_EXIT_N)")
			(pinfunction "FF_EXIT_N")
			(pintype "input")
			(die_length 6.55259)
		)
		(pad "G11" smd circle
			(at -0.401 -3.601 270)
			(size 0.45 0.45)
			(layers "F.Cu" "F.Mask" "F.Paste")
			(net 649 "VDD")
			(pinfunction "VDDI1")
			(pintype "passive")
		)
		(pad "G12" smd circle
			(at 0.4 -3.601 270)
			(size 0.45 0.45)
			(layers "F.Cu" "F.Mask" "F.Paste")
			(net 32 "UART4_RX{slash}RPI_GPIO09")
			(pinfunction "GPIO182NB1/DQS")
			(pintype "bidirectional")
			(die_length 12.3908)
		)
		(pad "G13" smd circle
			(at 1.199 -3.601 270)
			(size 0.45 0.45)
			(layers "F.Cu" "F.Mask" "F.Paste")
			(net 396 "unconnected-(U1B-GPIO185PB1-PadG13)")
			(pinfunction "GPIO185PB1")
			(pintype "bidirectional+no_connect")
			(die_length 12.308)
		)
		(pad "G14" smd circle
			(at 1.999 -3.601 270)
			(size 0.45 0.45)
			(layers "F.Cu" "F.Mask" "F.Paste")
			(net 566 "/FPGA GPIO/PF_ETH_RESET_n")
			(pinfunction "GPIO6NB1")
			(pintype "bidirectional")
			(die_length 10.3354)
		)
		(pad "G15" smd circle
			(at 2.799 -3.601 270)
			(size 0.45 0.45)
			(layers "F.Cu" "F.Mask" "F.Paste")
			(net 133 "SPI6_CEO_N{slash}RPI_GPIO18")
			(pinfunction "GPIO7PB1")
			(pintype "bidirectional")
			(die_length 10.6356)
		)
		(pad "G16" smd circle
			(at 3.6 -3.601 270)
			(size 0.45 0.45)
			(layers "F.Cu" "F.Mask" "F.Paste")
			(net 417 "GND")
			(pinfunction "VSS")
			(pintype "passive")
		)
		(pad "G17" smd circle
			(at 4.4 -3.601 270)
			(size 0.45 0.45)
			(layers "F.Cu" "F.Mask" "F.Paste")
			(net 397 "unconnected-(U1B-GPIO8PB1{slash}DQS{slash}CCC_SE_PLL0_OUT0-PadG17)")
			(pinfunction "GPIO8PB1/DQS/CCC_SE_PLL0_OUT0")
			(pintype "bidirectional+no_connect")
			(die_length 11.6563)
		)
		(pad "G18" smd circle
			(at 5.2 -3.601 270)
			(size 0.45 0.45)
			(layers "F.Cu" "F.Mask" "F.Paste")
			(net 417 "GND")
			(pinfunction "VSS")
			(pintype "passive")
		)
		(pad "G19" smd circle
			(at 5.999 -3.601 270)
			(size 0.45 0.45)
			(layers "F.Cu" "F.Mask" "F.Paste")
			(net 105 "/Bottom Connector/PCIE.RXD0_N")
			(pinfunction "XCVR_0_RX0_N")
			(pintype "input")
			(die_length 6.56405)
		)
		(pad "G20" smd circle
			(at 6.799 -3.601 270)
			(size 0.45 0.45)
			(layers "F.Cu" "F.Mask" "F.Paste")
			(net 102 "/Bottom Connector/PCIE.RXD0_P")
			(pinfunction "XCVR_0_RX0_P")
			(pintype "input")
			(die_length 6.55062)
		)
		(pad "G21" smd circle
			(at 7.599 -3.601 270)
			(size 0.45 0.45)
			(layers "F.Cu" "F.Mask" "F.Paste")
			(net 47 "+1V05")
			(pinfunction "VDDA")
			(pintype "power_in")
		)
		(pad "G22" smd circle
			(at 8.4 -3.601 270)
			(size 0.45 0.45)
			(layers "F.Cu" "F.Mask" "F.Paste")
			(net 417 "GND")
			(pinfunction "VSS")
			(pintype "passive")
		)
		(pad "H1" smd circle
			(at -8.401 -2.8 270)
			(size 0.45 0.45)
			(layers "F.Cu" "F.Mask" "F.Paste")
			(net 235 "/FPGA MSSIO/MEM.DAT0")
			(pinfunction "MSSIO2B4")
			(pintype "bidirectional")
			(die_length 8.33301)
		)
		(pad "H2" smd circle
			(at -7.6 -2.8 270)
			(size 0.45 0.45)
			(layers "F.Cu" "F.Mask" "F.Paste")
			(net 215 "/FPGA MSSIO/MEM.DAT7")
			(pinfunction "MSSIO11B4")
			(pintype "bidirectional")
			(die_length 7.77805)
		)
		(pad "H3" smd circle
			(at -6.8 -2.8 270)
			(size 0.45 0.45)
			(layers "F.Cu" "F.Mask" "F.Paste")
			(net 417 "GND")
			(pinfunction "VSS")
			(pintype "passive")
		)
		(pad "H4" smd circle
			(at -6 -2.8 270)
			(size 0.45 0.45)
			(layers "F.Cu" "F.Mask" "F.Paste")
			(net 387 "/FPGA MSSIO/EMMC.RST_n")
			(pinfunction "MSSIO7B4")
			(pintype "bidirectional")
			(die_length 9.16535)
		)
		(pad "H5" smd circle
			(at -5.201 -2.8 270)
			(size 0.45 0.45)
			(layers "F.Cu" "F.Mask" "F.Paste")
			(net 626 "unconnected-(U1E-MSSIO12B4-PadH5)")
			(pinfunction "MSSIO12B4")
			(pintype "bidirectional+no_connect")
			(die_length 9.27031)
		)
		(pad "H6" smd circle
			(at -4.401 -2.8 270)
			(size 0.45 0.45)
			(layers "F.Cu" "F.Mask" "F.Paste")
			(net 216 "/FPGA MSSIO/MEM.DAT5")
			(pinfunction "MSSIO9B4")
			(pintype "bidirectional")
			(die_length 10.6795)
		)
		(pad "H7" smd circle
			(at -3.601 -2.8 270)
			(size 0.45 0.45)
			(layers "F.Cu" "F.Mask" "F.Paste")
			(net 655 "/FPGA Config/DEVRST_N")
			(pinfunction "DEVRST_N")
			(pintype "input")
			(die_length 5.65884)
		)
		(pad "H8" smd circle
			(at -2.8 -2.8 270)
			(size 0.45 0.45)
			(layers "F.Cu" "F.Mask" "F.Paste")
			(net 418 "+2V5")
			(pinfunction "VDD25")
			(pintype "power_in")
		)
		(pad "H9" smd circle
			(at -2 -2.8 270)
			(size 0.45 0.45)
			(layers "F.Cu" "F.Mask" "F.Paste")
			(net 255 "Net-(U1D-IO_CFG_INTF)")
			(pinfunction "IO_CFG_INTF")
			(pintype "input")
			(die_length 6.79819)
		)
		(pad "H10" smd circle
			(at -1.2 -2.8 270)
			(size 0.45 0.45)
			(layers "F.Cu" "F.Mask" "F.Paste")
			(net 290 "/FPGA Config/Flash.MISO")
			(pinfunction "SDI")
			(pintype "input")
			(die_length 6.8817)
		)
		(pad "H11" smd circle
			(at -0.401 -2.8 270)
			(size 0.45 0.45)
			(layers "F.Cu" "F.Mask" "F.Paste")
			(net 256 "Net-(U1D-SPI_EN)")
			(pinfunction "SPI_EN")
			(pintype "input")
			(die_length 7.76583)
		)
		(pad "H12" smd circle
			(at 0.4 -2.8 270)
			(size 0.45 0.45)
			(layers "F.Cu" "F.Mask" "F.Paste")
			(net 31 "UART4_TX{slash}RPI_GPIO08")
			(pinfunction "GPIO182PB1/DQS")
			(pintype "bidirectional")
			(die_length 12.3884)
		)
		(pad "H13" smd circle
			(at 1.199 -2.8 270)
			(size 0.45 0.45)
			(layers "F.Cu" "F.Mask" "F.Paste")
			(net 17 "GPIO7")
			(pinfunction "GPIO185NB1")
			(pintype "bidirectional")
			(die_length 12.28)
		)
		(pad "H14" smd circle
			(at 1.999 -2.8 270)
			(size 0.45 0.45)
			(layers "F.Cu" "F.Mask" "F.Paste")
			(net 49 "VDDAUX")
			(pinfunction "VDDAUX1")
			(pintype "power_in")
		)
		(pad "H15" smd circle
			(at 2.799 -2.8 270)
			(size 0.45 0.45)
			(layers "F.Cu" "F.Mask" "F.Paste")
			(net 134 "UART0_RX{slash}RPI_GPIO15")
			(pinfunction "GPIO7NB1")
			(pintype "bidirectional")
			(die_length 10.5915)
		)
		(pad "H16" smd circle
			(at 3.6 -2.8 270)
			(size 0.45 0.45)
			(layers "F.Cu" "F.Mask" "F.Paste")
			(net 49 "VDDAUX")
			(pinfunction "VDDAUX1")
			(pintype "passive")
		)
		(pad "H17" smd circle
			(at 4.4 -2.8 270)
			(size 0.45 0.45)
			(layers "F.Cu" "F.Mask" "F.Paste")
			(net 28 "GPIO17")
			(pinfunction "GPIO8NB1/DQS")
			(pintype "bidirectional")
			(die_length 11.6441)
		)
		(pad "H18" smd circle
			(at 5.2 -2.8 270)
			(size 0.45 0.45)
			(layers "F.Cu" "F.Mask" "F.Paste")
			(net 1 "/FPGA Supply/XCVR_VREF")
			(pinfunction "XCVR_VREF")
			(pintype "power_in")
		)
		(pad "H19" smd circle
			(at 5.999 -2.8 270)
			(size 0.45 0.45)
			(layers "F.Cu" "F.Mask" "F.Paste")
			(net 1 "/FPGA Supply/XCVR_VREF")
			(pinfunction "XCVR_VREF")
			(pintype "passive")
		)
		(pad "H20" smd circle
			(at 6.799 -2.8 270)
			(size 0.45 0.45)
			(layers "F.Cu" "F.Mask" "F.Paste")
			(net 417 "GND")
			(pinfunction "VSS")
			(pintype "passive")
		)
		(pad "H21" smd circle
			(at 7.599 -2.8 270)
			(size 0.45 0.45)
			(layers "F.Cu" "F.Mask" "F.Paste")
			(net 46 "/PCIe/XCVR_TX1_N")
			(pinfunction "XCVR_0_TX1_N")
			(pintype "output")
			(die_length 7.41112)
		)
		(pad "H22" smd circle
			(at 8.4 -2.8 270)
			(size 0.45 0.45)
			(layers "F.Cu" "F.Mask" "F.Paste")
			(net 51 "/PCIe/XCVR_TX1_P")
			(pinfunction "XCVR_0_TX1_P")
			(pintype "output")
			(die_length 7.39947)
		)
		(pad "J1" smd circle
			(at -8.401 -2 270)
			(size 0.45 0.45)
			(layers "F.Cu" "F.Mask" "F.Paste")
			(net 265 "/FPGA MSSIO/MEM.CLK")
			(pinfunction "MSSIO0B4")
			(pintype "bidirectional")
			(die_length 7.51872)
		)
		(pad "J2" smd circle
			(at -7.6 -2 270)
			(size 0.45 0.45)
			(layers "F.Cu" "F.Mask" "F.Paste")
			(net 627 "unconnected-(U1E-MSSIO13B4-PadJ2)")
			(pinfunction "MSSIO13B4")
			(pintype "bidirectional+no_connect")
			(die_length 6.70124)
		)
		(pad "J3" smd circle
			(at -6.8 -2 270)
			(size 0.45 0.45)
			(layers "F.Cu" "F.Mask" "F.Paste")
			(net 252 "/FPGA MSSIO/MEM.DAT6")
			(pinfunction "MSSIO10B4")
			(pintype "bidirectional")
			(die_length 7.82186)
		)
		(pad "J4" smd circle
			(at -6 -2 270)
			(size 0.45 0.45)
			(layers "F.Cu" "F.Mask" "F.Paste")
			(net 262 "/FPGA MSSIO/MEM.DAT1")
			(pinfunction "MSSIO3B4")
			(pintype "bidirectional")
			(die_length 8.67867)
		)
		(pad "J5" smd circle
			(at -5.201 -2 270)
			(size 0.45 0.45)
			(layers "F.Cu" "F.Mask" "F.Paste")
			(net 137 "SD_VDD")
			(pinfunction "VDDI4")
			(pintype "power_in")
		)
		(pad "J6" smd circle
			(at -4.401 -2 270)
			(size 0.45 0.45)
			(layers "F.Cu" "F.Mask" "F.Paste")
			(net 251 "/FPGA MSSIO/MEM.DAT4")
			(pinfunction "MSSIO8B4")
			(pintype "bidirectional")
			(die_length 9.38542)
		)
		(pad "J7" smd circle
			(at -3.601 -2 270)
			(size 0.45 0.45)
			(layers "F.Cu" "F.Mask" "F.Paste")
			(net 236 "/FPGA MSSIO/MEM.DAT3")
			(pinfunction "MSSIO5B4")
			(pintype "bidirectional")
			(die_length 10.8496)
		)
		(pad "J8" smd circle
			(at -2.8 -2 270)
			(size 0.45 0.45)
			(layers "F.Cu" "F.Mask" "F.Paste")
			(net 417 "GND")
			(pinfunction "VSS")
			(pintype "passive")
		)
		(pad "J9" smd circle
			(at -2 -2 270)
			(size 0.45 0.45)
			(layers "F.Cu" "F.Mask" "F.Paste")
			(net 49 "VDDAUX")
			(pinfunction "VDDAUX1")
			(pintype "passive")
		)
		(pad "J10" smd circle
			(at -1.2 -2 270)
			(size 0.45 0.45)
			(layers "F.Cu" "F.Mask" "F.Paste")
			(net 417 "GND")
			(pinfunction "VSS")
			(pintype "passive")
		)
		(pad "J11" smd circle
			(at -0.401 -2 270)
			(size 0.45 0.45)
			(layers "F.Cu" "F.Mask" "F.Paste")
			(net 50 "+3V3")
			(pinfunction "VDDI3")
			(pintype "passive")
		)
		(pad "J12" smd circle
			(at 0.4 -2 270)
			(size 0.45 0.45)
			(layers "F.Cu" "F.Mask" "F.Paste")
			(net 417 "GND")
			(pinfunction "VSS")
			(pintype "passive")
		)
		(pad "J13" smd circle
			(at 1.199 -2 270)
			(size 0.45 0.45)
			(layers "F.Cu" "F.Mask" "F.Paste")
			(net 49 "VDDAUX")
			(pinfunction "VDDAUX1")
			(pintype "passive")
		)
		(pad "J14" smd circle
			(at 1.999 -2 270)
			(size 0.45 0.45)
			(layers "F.Cu" "F.Mask" "F.Paste")
			(net 417 "GND")
			(pinfunction "VSS")
			(pintype "passive")
		)
		(pad "J15" smd circle
			(at 2.799 -2 270)
			(size 0.45 0.45)
			(layers "F.Cu" "F.Mask" "F.Paste")
			(net 47 "+1V05")
			(pinfunction "VDD")
			(pintype "power_in")
		)
		(pad "J16" smd circle
			(at 3.6 -2 270)
			(size 0.45 0.45)
			(layers "F.Cu" "F.Mask" "F.Paste")
			(net 417 "GND")
			(pinfunction "VSS")
			(pintype "passive")
		)
		(pad "J17" smd circle
			(at 4.4 -2 270)
			(size 0.45 0.45)
			(layers "F.Cu" "F.Mask" "F.Paste")
			(net 418 "+2V5")
			(pinfunction "VDD25")
			(pintype "passive")
		)
		(pad "J18" smd circle
			(at 5.2 -2 270)
			(size 0.45 0.45)
			(layers "F.Cu" "F.Mask" "F.Paste")
			(net 418 "+2V5")
			(pinfunction "VDDA25")
			(pintype "power_in")
		)
		(pad "J19" smd circle
			(at 5.999 -2 270)
			(size 0.45 0.45)
			(layers "F.Cu" "F.Mask" "F.Paste")
			(net 399 "unconnected-(U1H-XCVR_0C_REFCLK_P-PadJ19)")
			(pinfunction "XCVR_0C_REFCLK_P")
			(pintype "input+no_connect")
			(die_length 4.98524)
		)
		(pad "J20" smd circle
			(at 6.799 -2 270)
			(size 0.45 0.45)
			(layers "F.Cu" "F.Mask" "F.Paste")
			(net 400 "unconnected-(U1H-XCVR_0C_REFCLK_N-PadJ20)")
			(pinfunction "XCVR_0C_REFCLK_N")
			(pintype "input+no_connect")
			(die_length 4.97965)
		)
		(pad "J21" smd circle
			(at 7.599 -2 270)
			(size 0.45 0.45)
			(layers "F.Cu" "F.Mask" "F.Paste")
			(net 47 "+1V05")
			(pinfunction "VDDA")
			(pintype "passive")
		)
		(pad "J22" smd circle
			(at 8.4 -2 270)
			(size 0.45 0.45)
			(layers "F.Cu" "F.Mask" "F.Paste")
			(net 417 "GND")
			(pinfunction "VSS")
			(pintype "passive")
		)
		(pad "K1" smd circle
			(at -8.401 -1.2 270)
			(size 0.45 0.45)
			(layers "F.Cu" "F.Mask" "F.Paste")
			(net 389 "/FPGA MSS/LPDDR4.CKE0_A")
			(pinfunction "MSS_DDR_CKE0")
			(pintype "bidirectional")
			(die_length 8.39963)
		)
		(pad "K2" smd circle
			(at -7.6 -1.2 270)
			(size 0.45 0.45)
			(layers "F.Cu" "F.Mask" "F.Paste")
			(net 137 "SD_VDD")
			(pinfunction "VDDI4")
			(pintype "passive")
		)
		(pad "K3" smd circle
			(at -6.8 -1.2 270)
			(size 0.45 0.45)
			(layers "F.Cu" "F.Mask" "F.Paste")
			(net 624 "/FPGA MSSIO/MEM.STRB")
			(pinfunction "MSSIO6B4")
			(pintype "bidirectional")
			(die_length 7.2517)
		)
		(pad "K4" smd circle
			(at -6 -1.2 270)
			(size 0.45 0.45)
			(layers "F.Cu" "F.Mask" "F.Paste")
			(net 261 "/FPGA MSSIO/MEM.DAT2")
			(pinfunction "MSSIO4B4")
			(pintype "bidirectional")
			(die_length 7.47273)
		)
		(pad "K5" smd circle
			(at -5.201 -1.2 270)
			(size 0.45 0.45)
			(layers "F.Cu" "F.Mask" "F.Paste")
			(net 625 "/FPGA MSSIO/MEM.CMD")
			(pinfunction "MSSIO1B4")
			(pintype "bidirectional")
			(die_length 9.04979)
		)
		(pad "K6" smd circle
			(at -4.401 -1.2 270)
			(size 0.45 0.45)
			(layers "F.Cu" "F.Mask" "F.Paste")
			(net 401 "unconnected-(U1F-MSS_SGMII_RXP1-PadK6)")
			(pinfunction "MSS_SGMII_RXP1")
			(pintype "bidirectional+no_connect")
			(die_length 10.8747)
		)
		(pad "K7" smd circle
			(at -3.601 -1.2 270)
			(size 0.45 0.45)
			(layers "F.Cu" "F.Mask" "F.Paste")
			(net 402 "unconnected-(U1F-MSS_SGMII_RXN1-PadK7)")
			(pinfunction "MSS_SGMII_RXN1")
			(pintype "bidirectional+no_connect")
			(die_length 10.9008)
		)
		(pad "K8" smd circle
			(at -2.8 -1.2 270)
			(size 0.45 0.45)
			(layers "F.Cu" "F.Mask" "F.Paste")
			(net 49 "VDDAUX")
			(pinfunction "VDDAUX2")
			(pintype "power_in")
		)
		(pad "K9" smd circle
			(at -2 -1.2 270)
			(size 0.45 0.45)
			(layers "F.Cu" "F.Mask" "F.Paste")
			(net 417 "GND")
			(pinfunction "VSS")
			(pintype "passive")
		)
		(pad "K10" smd circle
			(at -1.2 -1.2 270)
			(size 0.45 0.45)
			(layers "F.Cu" "F.Mask" "F.Paste")
			(net 49 "VDDAUX")
			(pinfunction "VDDAUX1")
			(pintype "passive")
		)
		(pad "K11" smd circle
			(at -0.401 -1.2 270)
			(size 0.45 0.45)
			(layers "F.Cu" "F.Mask" "F.Paste")
			(net 417 "GND")
			(pinfunction "VSS")
			(pintype "passive")
		)
		(pad "K12" smd circle
			(at 0.4 -1.2 270)
			(size 0.45 0.45)
			(layers "F.Cu" "F.Mask" "F.Paste")
			(net 47 "+1V05")
			(pinfunction "VDD")
			(pintype "passive")
		)
		(pad "K13" smd circle
			(at 1.199 -1.2 270)
			(size 0.45 0.45)
			(layers "F.Cu" "F.Mask" "F.Paste")
			(net 417 "GND")
			(pinfunction "VSS")
			(pintype "passive")
		)
		(pad "K14" smd circle
			(at 1.999 -1.2 270)
			(size 0.45 0.45)
			(layers "F.Cu" "F.Mask" "F.Paste")
			(net 47 "+1V05")
			(pinfunction "VDD")
			(pintype "passive")
		)
		(pad "K15" smd circle
			(at 2.799 -1.2 270)
			(size 0.45 0.45)
			(layers "F.Cu" "F.Mask" "F.Paste")
			(net 417 "GND")
			(pinfunction "VSS")
			(pintype "passive")
		)
		(pad "K16" smd circle
			(at 3.6 -1.2 270)
			(size 0.45 0.45)
			(layers "F.Cu" "F.Mask" "F.Paste")
			(net 47 "+1V05")
			(pinfunction "VDD")
			(pintype "passive")
		)
		(pad "K17" smd circle
			(at 4.4 -1.2 270)
			(size 0.45 0.45)
			(layers "F.Cu" "F.Mask" "F.Paste")
			(net 417 "GND")
			(pinfunction "VSS")
			(pintype "passive")
		)
		(pad "K18" smd circle
			(at 5.2 -1.2 270)
			(size 0.45 0.45)
			(layers "F.Cu" "F.Mask" "F.Paste")
			(net 418 "+2V5")
			(pinfunction "VDD_XCVR_CLK")
			(pintype "power_in")
		)
		(pad "K19" smd circle
			(at 5.999 -1.2 270)
			(size 0.45 0.45)
			(layers "F.Cu" "F.Mask" "F.Paste")
			(net 47 "+1V05")
			(pinfunction "VDDA")
			(pintype "passive")
		)
		(pad "K20" smd circle
			(at 6.799 -1.2 270)
			(size 0.45 0.45)
			(layers "F.Cu" "F.Mask" "F.Paste")
			(net 417 "GND")
			(pinfunction "VSS")
			(pintype "passive")
		)
		(pad "K21" smd circle
			(at 7.599 -1.2 270)
			(size 0.45 0.45)
			(layers "F.Cu" "F.Mask" "F.Paste")
			(net 138 "/Bottom Connector/PCIE.RXD1_N")
			(pinfunction "XCVR_0_RX1_N")
			(pintype "input")
			(die_length 5.26367)
		)
		(pad "K22" smd circle
			(at 8.4 -1.2 270)
			(size 0.45 0.45)
			(layers "F.Cu" "F.Mask" "F.Paste")
			(net 121 "/Bottom Connector/PCIE.RXD1_P")
			(pinfunction "XCVR_0_RX1_P")
			(pintype "input")
			(die_length 5.25117)
		)
		(pad "L1" smd circle
			(at -8.401 -0.401 270)
			(size 0.45 0.45)
			(layers "F.Cu" "F.Mask" "F.Paste")
			(net 393 "/FPGA MSS/LPDDR4.ODT_CA_A")
			(pinfunction "MSS_DDR_ODT0")
			(pintype "bidirectional")
			(die_length 7.44348)
		)
		(pad "L2" smd circle
			(at -7.6 -0.401 270)
			(size 0.45 0.45)
			(layers "F.Cu" "F.Mask" "F.Paste")
			(net 394 "/FPGA MSS/LPDDR4.RESET_n")
			(pinfunction "MSS_DDR_RAM_RST_N/DDR_PLL0_OUT1")
			(pintype "bidirectional")
			(die_length 6.88475)
		)
		(pad "L3" smd circle
			(at -6.8 -0.401 270)
			(size 0.45 0.45)
			(layers "F.Cu" "F.Mask" "F.Paste")
			(net 395 "/FPGA MSS/LPDDR4.CS0_A")
			(pinfunction "MSS_DDR_CS0")
			(pintype "bidirectional")
			(die_length 7.35905)
		)
		(pad "L4" smd circle
			(at -6 -0.401 270)
			(size 0.45 0.45)
			(layers "F.Cu" "F.Mask" "F.Paste")
			(net 417 "GND")
			(pinfunction "VSS")
			(pintype "passive")
		)
		(pad "L5" smd circle
			(at -5.201 -0.401 270)
			(size 0.45 0.45)
			(layers "F.Cu" "F.Mask" "F.Paste")
			(net 42 "/Ethernet/SGMII.RX0_P")
			(pinfunction "MSS_SGMII_RXP0")
			(pintype "bidirectional")
			(die_length 9.80775)
		)
		(pad "L6" smd circle
			(at -4.401 -0.401 270)
			(size 0.45 0.45)
			(layers "F.Cu" "F.Mask" "F.Paste")
			(net 41 "/Ethernet/SGMII.RX0_N")
			(pinfunction "MSS_SGMII_RXN0")
			(pintype "bidirectional")
			(die_length 9.80095)
		)
		(pad "L7" smd circle
			(at -3.601 -0.401 270)
			(size 0.45 0.45)
			(layers "F.Cu" "F.Mask" "F.Paste")
			(net 10 "MSS_REFCLK_P")
			(pinfunction "MSS_REFCLK_IN_P")
			(pintype "bidirectional")
			(die_length 10.0914)
		)
		(pad "L8" smd circle
			(at -2.8 -0.401 270)
			(size 0.45 0.45)
			(layers "F.Cu" "F.Mask" "F.Paste")
			(net 9 "MSS_REFCLK_N")
			(pinfunction "MSS_REFCLK_IN_N")
			(pintype "bidirectional")
			(die_length 10.0825)
		)
		(pad "L9" smd circle
			(at -2 -0.401 270)
			(size 0.45 0.45)
			(layers "F.Cu" "F.Mask" "F.Paste")
			(net 49 "VDDAUX")
			(pinfunction "VDDAUX2")
			(pintype "passive")
		)
		(pad "L10" smd circle
			(at -1.2 -0.401 270)
			(size 0.45 0.45)
			(layers "F.Cu" "F.Mask" "F.Paste")
			(net 417 "GND")
			(pinfunction "VSS")
			(pintype "passive")
		)
		(pad "L11" smd circle
			(at -0.401 -0.401 270)
			(size 0.45 0.45)
			(layers "F.Cu" "F.Mask" "F.Paste")
			(net 47 "+1V05")
			(pinfunction "VDD")
			(pintype "passive")
		)
		(pad "L12" smd circle
			(at 0.4 -0.401 270)
			(size 0.45 0.45)
			(layers "F.Cu" "F.Mask" "F.Paste")
			(net 417 "GND")
			(pinfunction "VSS")
			(pintype "passive")
		)
		(pad "L13" smd circle
			(at 1.199 -0.401 270)
			(size 0.45 0.45)
			(layers "F.Cu" "F.Mask" "F.Paste")
			(net 47 "+1V05")
			(pinfunction "VDD")
			(pintype "passive")
		)
		(pad "L14" smd circle
			(at 1.999 -0.401 270)
			(size 0.45 0.45)
			(layers "F.Cu" "F.Mask" "F.Paste")
			(net 417 "GND")
			(pinfunction "VSS")
			(pintype "passive")
		)
		(pad "L15" smd circle
			(at 2.799 -0.401 270)
			(size 0.45 0.45)
			(layers "F.Cu" "F.Mask" "F.Paste")
			(net 418 "+2V5")
			(pinfunction "VDD25")
			(pintype "passive")
		)
		(pad "L16" smd circle
			(at 3.6 -0.401 270)
			(size 0.45 0.45)
			(layers "F.Cu" "F.Mask" "F.Paste")
			(net 417 "GND")
			(pinfunction "VSS")
			(pintype "passive")
		)
		(pad "L17" smd circle
			(at 4.4 -0.401 270)
			(size 0.45 0.45)
			(layers "F.Cu" "F.Mask" "F.Paste")
			(net 47 "+1V05")
			(pinfunction "VDD")
			(pintype "passive")
		)
		(pad "L18" smd circle
			(at 5.2 -0.401 270)
			(size 0.45 0.45)
			(layers "F.Cu" "F.Mask" "F.Paste")
			(net 417 "GND")
			(pinfunction "VSS")
			(pintype "passive")
		)
		(pad "L19" smd circle
			(at 5.999 -0.401 270)
			(size 0.45 0.45)
			(layers "F.Cu" "F.Mask" "F.Paste")
			(net 461 "/PCIe/PF_PCIe_CLK_P")
			(pinfunction "XCVR_0A_REFCLK_P")
			(pintype "input")
			(die_length 5.39647)
		)
		(pad "L20" smd circle
			(at 6.799 -0.401 270)
			(size 0.45 0.45)
			(layers "F.Cu" "F.Mask" "F.Paste")
			(net 562 "/PCIe/PF_PCIe_CLK_N")
			(pinfunction "XCVR_0A_REFCLK_N")
			(pintype "input")
			(die_length 5.40211)
		)
		(pad "L21" smd circle
			(at 7.599 -0.401 270)
			(size 0.45 0.45)
			(layers "F.Cu" "F.Mask" "F.Paste")
			(net 47 "+1V05")
			(pinfunction "VDDA")
			(pintype "passive")
		)
		(pad "L22" smd circle
			(at 8.4 -0.401 270)
			(size 0.45 0.45)
			(layers "F.Cu" "F.Mask" "F.Paste")
			(net 417 "GND")
			(pinfunction "VSS")
			(pintype "passive")
		)
		(pad "M1" smd circle
			(at -8.401 0.4 270)
			(size 0.45 0.45)
			(layers "F.Cu" "F.Mask" "F.Paste")
			(net 417 "GND")
			(pinfunction "VSS")
			(pintype "passive")
		)
		(pad "M2" smd circle
			(at -7.6 0.4 270)
			(size 0.45 0.45)
			(layers "F.Cu" "F.Mask" "F.Paste")
			(net 403 "unconnected-(U1G-MSS_DDR_BG1-PadM2)")
			(pinfunction "MSS_DDR_BG1")
			(pintype "bidirectional+no_connect")
			(die_length 6.23809)
		)
		(pad "M3" smd circle
			(at -6.8 0.4 270)
			(size 0.45 0.45)
			(layers "F.Cu" "F.Mask" "F.Paste")
			(net 404 "unconnected-(U1G-MSS_DDR_CS1-PadM3)")
			(pinfunction "MSS_DDR_CS1")
			(pintype "bidirectional+no_connect")
			(die_length 6.42569)
		)
		(pad "M4" smd circle
			(at -6 0.4 270)
			(size 0.45 0.45)
			(layers "F.Cu" "F.Mask" "F.Paste")
			(net 405 "unconnected-(U1G-MSS_DDR_ODT1-PadM4)")
			(pinfunction "MSS_DDR_ODT1")
			(pintype "bidirectional+no_connect")
			(die_length 6.26668)
		)
		(pad "M5" smd circle
			(at -5.201 0.4 270)
			(size 0.45 0.45)
			(layers "F.Cu" "F.Mask" "F.Paste")
			(net 407 "unconnected-(U1G-MSS_DDR_PARITY-PadM5)")
			(pinfunction "MSS_DDR_PARITY")
			(pintype "bidirectional+no_connect")
			(die_length 6.72139)
		)
		(pad "M6" smd circle
			(at -4.401 0.4 270)
			(size 0.45 0.45)
			(layers "F.Cu" "F.Mask" "F.Paste")
			(net 50 "+3V3")
			(pinfunction "VDDI5")
			(pintype "power_in")
		)
		(pad "M7" smd circle
			(at -3.601 0.4 270)
			(size 0.45 0.45)
			(layers "F.Cu" "F.Mask" "F.Paste")
			(net 408 "unconnected-(U1F-MSS_SGMII_TXP1-PadM7)")
			(pinfunction "MSS_SGMII_TXP1")
			(pintype "bidirectional+no_connect")
			(die_length 10.1667)
		)
		(pad "M8" smd circle
			(at -2.8 0.4 270)
			(size 0.45 0.45)
			(layers "F.Cu" "F.Mask" "F.Paste")
			(net 50 "+3V3")
			(pinfunction "VDDI5")
			(pintype "passive")
		)
		(pad "M9" smd circle
			(at -2 0.4 270)
			(size 0.45 0.45)
			(layers "F.Cu" "F.Mask" "F.Paste")
			(net 417 "GND")
			(pinfunction "VSS")
			(pintype "passive")
		)
		(pad "M10" smd circle
			(at -1.2 0.4 270)
			(size 0.45 0.45)
			(layers "F.Cu" "F.Mask" "F.Paste")
			(net 519 "SD_VDD_AUX")
			(pinfunction "VDDAUX4")
			(pintype "power_in")
		)
		(pad "M11" smd circle
			(at -0.401 0.4 270)
			(size 0.45 0.45)
			(layers "F.Cu" "F.Mask" "F.Paste")
			(net 417 "GND")
			(pinfunction "VSS")
			(pintype "passive")
		)
		(pad "M12" smd circle
			(at 0.4 0.4 270)
			(size 0.45 0.45)
			(layers "F.Cu" "F.Mask" "F.Paste")
			(net 47 "+1V05")
			(pinfunction "VDD")
			(pintype "passive")
		)
		(pad "M13" smd circle
			(at 1.199 0.4 270)
			(size 0.45 0.45)
			(layers "F.Cu" "F.Mask" "F.Paste")
			(net 417 "GND")
			(pinfunction "VSS")
			(pintype "passive")
		)
		(pad "M14" smd circle
			(at 1.999 0.4 270)
			(size 0.45 0.45)
			(layers "F.Cu" "F.Mask" "F.Paste")
			(net 47 "+1V05")
			(pinfunction "VDD")
			(pintype "passive")
		)
		(pad "M15" smd circle
			(at 2.799 0.4 270)
			(size 0.45 0.45)
			(layers "F.Cu" "F.Mask" "F.Paste")
			(net 417 "GND")
			(pinfunction "VSS")
			(pintype "passive")
		)
		(pad "M16" smd circle
			(at 3.6 0.4 270)
			(size 0.45 0.45)
			(layers "F.Cu" "F.Mask" "F.Paste")
			(net 47 "+1V05")
			(pinfunction "VDD")
			(pintype "passive")
		)
		(pad "M17" smd circle
			(at 4.4 0.4 270)
			(size 0.45 0.45)
			(layers "F.Cu" "F.Mask" "F.Paste")
			(net 417 "GND")
			(pinfunction "VSS")
			(pintype "passive")
		)
		(pad "M18" smd circle
			(at 5.2 0.4 270)
			(size 0.45 0.45)
			(layers "F.Cu" "F.Mask" "F.Paste")
			(net 418 "+2V5")
			(pinfunction "VDDA25")
			(pintype "passive")
		)
		(pad "M19" smd circle
			(at 5.999 0.4 270)
			(size 0.45 0.45)
			(layers "F.Cu" "F.Mask" "F.Paste")
			(net 417 "GND")
			(pinfunction "VSS")
			(pintype "passive")
		)
		(pad "M20" smd circle
			(at 6.799 0.4 270)
			(size 0.45 0.45)
			(layers "F.Cu" "F.Mask" "F.Paste")
			(net 417 "GND")
			(pinfunction "VSS")
			(pintype "passive")
		)
		(pad "M21" smd circle
			(at 7.599 0.4 270)
			(size 0.45 0.45)
			(layers "F.Cu" "F.Mask" "F.Paste")
			(net 139 "/Bottom Connector/PCIE.RXD2_N")
			(pinfunction "XCVR_0_RX2_N")
			(pintype "input")
			(die_length 5.06127)
		)
		(pad "M22" smd circle
			(at 8.4 0.4 270)
			(size 0.45 0.45)
			(layers "F.Cu" "F.Mask" "F.Paste")
			(net 140 "/Bottom Connector/PCIE.RXD2_P")
			(pinfunction "XCVR_0_RX2_P")
			(pintype "input")
			(die_length 5.05345)
		)
		(pad "N1" smd circle
			(at -8.401 1.199 270)
			(size 0.45 0.45)
			(layers "F.Cu" "F.Mask" "F.Paste")
			(net 412 "unconnected-(U1G-MSS_DDR_BG0-PadN1)")
			(pinfunction "MSS_DDR_BG0")
			(pintype "bidirectional+no_connect")
			(die_length 5.69155)
		)
		(pad "N2" smd circle
			(at -7.6 1.199 270)
			(size 0.45 0.45)
			(layers "F.Cu" "F.Mask" "F.Paste")
			(net 413 "unconnected-(U1G-MSS_DDR_CKE1-PadN2)")
			(pinfunction "MSS_DDR_CKE1")
			(pintype "bidirectional+no_connect")
			(die_length 4.87548)
		)
		(pad "N3" smd circle
			(at -6.8 1.199 270)
			(size 0.45 0.45)
			(layers "F.Cu" "F.Mask" "F.Paste")
			(net 2 "+1V1")
			(pinfunction "VDDI6")
			(pintype "passive")
		)
		(pad "N4" smd circle
			(at -6 1.199 270)
			(size 0.45 0.45)
			(layers "F.Cu" "F.Mask" "F.Paste")
			(net 414 "unconnected-(U1G-MSS_DDR_ALERT_N-PadN4)")
			(pinfunction "MSS_DDR_ALERT_N")
			(pintype "bidirectional+no_connect")
			(die_length 5.90664)
		)
		(pad "N5" smd circle
			(at -5.201 1.199 270)
			(size 0.45 0.45)
			(layers "F.Cu" "F.Mask" "F.Paste")
			(net 415 "unconnected-(U1G-MSS_DDR_ACT_N-PadN5)")
			(pinfunction "MSS_DDR_ACT_N")
			(pintype "bidirectional+no_connect")
			(die_length 6.32348)
		)
		(pad "N6" smd circle
			(at -4.401 1.199 270)
			(size 0.45 0.45)
			(layers "F.Cu" "F.Mask" "F.Paste")
			(net 43 "/Ethernet/SGMII.TX0_P")
			(pinfunction "MSS_SGMII_TXP0")
			(pintype "bidirectional")
			(die_length 8.82437)
		)
		(pad "N7" smd circle
			(at -3.601 1.199 270)
			(size 0.45 0.45)
			(layers "F.Cu" "F.Mask" "F.Paste")
			(net 68 "/Ethernet/SGMII.TX0_N")
			(pinfunction "MSS_SGMII_TXN0")
			(pintype "bidirectional")
			(die_length 8.84193)
		)
		(pad "N8" smd circle
			(at -2.8 1.199 270)
			(size 0.45 0.45)
			(layers "F.Cu" "F.Mask" "F.Paste")
			(net 416 "unconnected-(U1F-MSS_SGMII_TXN1-PadN8)")
			(pinfunction "MSS_SGMII_TXN1")
			(pintype "bidirectional+no_connect")
			(die_length 10.1512)
		)
		(pad "N9" smd circle
			(at -2 1.199 270)
			(size 0.45 0.45)
			(layers "F.Cu" "F.Mask" "F.Paste")
			(net 519 "SD_VDD_AUX")
			(pinfunction "VDDAUX4")
			(pintype "passive")
		)
		(pad "N10" smd circle
			(at -1.2 1.199 270)
			(size 0.45 0.45)
			(layers "F.Cu" "F.Mask" "F.Paste")
			(net 417 "GND")
			(pinfunction "VSS")
			(pintype "passive")
		)
		(pad "N11" smd circle
			(at -0.401 1.199 270)
			(size 0.45 0.45)
			(layers "F.Cu" "F.Mask" "F.Paste")
			(net 47 "+1V05")
			(pinfunction "VDD")
			(pintype "passive")
		)
		(pad "N12" smd circle
			(at 0.4 1.199 270)
			(size 0.45 0.45)
			(layers "F.Cu" "F.Mask" "F.Paste")
			(net 417 "GND")
			(pinfunction "VSS")
			(pintype "passive")
		)
		(pad "N13" smd circle
			(at 1.199 1.199 270)
			(size 0.45 0.45)
			(layers "F.Cu" "F.Mask" "F.Paste")
			(net 47 "+1V05")
			(pinfunction "VDD")
			(pintype "passive")
		)
		(pad "N14" smd circle
			(at 1.999 1.199 270)
			(size 0.45 0.45)
			(layers "F.Cu" "F.Mask" "F.Paste")
			(net 417 "GND")
			(pinfunction "VSS")
			(pintype "passive")
		)
		(pad "N15" smd circle
			(at 2.799 1.199 270)
			(size 0.45 0.45)
			(layers "F.Cu" "F.Mask" "F.Paste")
			(net 47 "+1V05")
			(pinfunction "VDD")
			(pintype "passive")
		)
		(pad "N16" smd circle
			(at 3.6 1.199 270)
			(size 0.45 0.45)
			(layers "F.Cu" "F.Mask" "F.Paste")
			(net 417 "GND")
			(pinfunction "VSS")
			(pintype "passive")
		)
		(pad "N17" smd circle
			(at 4.4 1.199 270)
			(size 0.45 0.45)
			(layers "F.Cu" "F.Mask" "F.Paste")
			(net 47 "+1V05")
			(pinfunction "VDD")
			(pintype "passive")
		)
		(pad "N18" smd circle
			(at 5.2 1.199 270)
			(size 0.45 0.45)
			(layers "F.Cu" "F.Mask" "F.Paste")
			(net 417 "GND")
			(pinfunction "VSS")
			(pintype "passive")
		)
		(pad "N19" smd circle
			(at 5.999 1.199 270)
			(size 0.45 0.45)
			(layers "F.Cu" "F.Mask" "F.Paste")
			(net 419 "unconnected-(U1H-XCVR_0B_REFCLK_P-PadN19)")
			(pinfunction "XCVR_0B_REFCLK_P")
			(pintype "input+no_connect")
			(die_length 3.66682)
		)
		(pad "N20" smd circle
			(at 6.799 1.199 270)
			(size 0.45 0.45)
			(layers "F.Cu" "F.Mask" "F.Paste")
			(net 420 "unconnected-(U1H-XCVR_0B_REFCLK_N-PadN20)")
			(pinfunction "XCVR_0B_REFCLK_N")
			(pintype "input+no_connect")
			(die_length 3.67223)
		)
		(pad "N21" smd circle
			(at 7.599 1.199 270)
			(size 0.45 0.45)
			(layers "F.Cu" "F.Mask" "F.Paste")
			(net 47 "+1V05")
			(pinfunction "VDDA")
			(pintype "passive")
		)
		(pad "N22" smd circle
			(at 8.4 1.199 270)
			(size 0.45 0.45)
			(layers "F.Cu" "F.Mask" "F.Paste")
			(net 417 "GND")
			(pinfunction "VSS")
			(pintype "passive")
		)
		(pad "P1" smd circle
			(at -8.401 1.999 270)
			(size 0.45 0.45)
			(layers "F.Cu" "F.Mask" "F.Paste")
			(net 425 "unconnected-(U1G-MSS_DDR_A12-PadP1)")
			(pinfunction "MSS_DDR_A12")
			(pintype "bidirectional+no_connect")
			(die_length 5.26134)
		)
		(pad "P2" smd circle
			(at -7.6 1.999 270)
			(size 0.45 0.45)
			(layers "F.Cu" "F.Mask" "F.Paste")
			(net 426 "unconnected-(U1G-MSS_DDR_A13-PadP2)")
			(pinfunction "MSS_DDR_A13")
			(pintype "bidirectional+no_connect")
			(die_length 4.7942)
		)
		(pad "P3" smd circle
			(at -6.8 1.999 270)
			(size 0.45 0.45)
			(layers "F.Cu" "F.Mask" "F.Paste")
			(net 427 "unconnected-(U1G-MSS_DDR_A14-PadP3)")
			(pinfunction "MSS_DDR_A14")
			(pintype "bidirectional+no_connect")
			(die_length 5.81429)
		)
		(pad "P4" smd circle
			(at -6 1.999 270)
			(size 0.45 0.45)
			(layers "F.Cu" "F.Mask" "F.Paste")
			(net 429 "unconnected-(U1G-MSS_DDR_BA0-PadP4)")
			(pinfunction "MSS_DDR_BA0")
			(pintype "bidirectional+no_connect")
			(die_length 4.15969)
		)
		(pad "P5" smd circle
			(at -5.201 1.999 270)
			(size 0.45 0.45)
			(layers "F.Cu" "F.Mask" "F.Paste")
			(net 417 "GND")
			(pinfunction "VSS")
			(pintype "passive")
		)
		(pad "P6" smd circle
			(at -4.401 1.999 270)
			(size 0.45 0.45)
			(layers "F.Cu" "F.Mask" "F.Paste")
			(net 431 "unconnected-(U1G-MSS_DDR_A6-PadP6)")
			(pinfunction "MSS_DDR_A6")
			(pintype "bidirectional+no_connect")
			(die_length 5.75834)
		)
		(pad "P7" smd circle
			(at -3.601 1.999 270)
			(size 0.45 0.45)
			(layers "F.Cu" "F.Mask" "F.Paste")
			(net 432 "unconnected-(U1G-MSS_DDR_A8-PadP7)")
			(pinfunction "MSS_DDR_A8")
			(pintype "bidirectional+no_connect")
			(die_length 5.75727)
		)
		(pad "P8" smd circle
			(at -2.8 1.999 270)
			(size 0.45 0.45)
			(layers "F.Cu" "F.Mask" "F.Paste")
			(net 567 "/FPGA MSS/LPDDR4.DQ31")
			(pinfunction "MSS_DDR_DQ31")
			(pintype "bidirectional")
			(die_length 7.47712)
		)
		(pad "P9" smd circle
			(at -2 1.999 270)
			(size 0.45 0.45)
			(layers "F.Cu" "F.Mask" "F.Paste")
			(net 417 "GND")
			(pinfunction "VSS")
			(pintype "passive")
		)
		(pad "P10" smd circle
			(at -1.2 1.999 270)
			(size 0.45 0.45)
			(layers "F.Cu" "F.Mask" "F.Paste")
			(net 48 "+1V8")
			(pinfunction "VDD18")
			(pintype "power_in")
		)
		(pad "P11" smd circle
			(at -0.401 1.999 270)
			(size 0.45 0.45)
			(layers "F.Cu" "F.Mask" "F.Paste")
			(net 417 "GND")
			(pinfunction "VSS")
			(pintype "passive")
		)
		(pad "P12" smd circle
			(at 0.4 1.999 270)
			(size 0.45 0.45)
			(layers "F.Cu" "F.Mask" "F.Paste")
			(net 48 "+1V8")
			(pinfunction "VDD18")
			(pintype "passive")
		)
		(pad "P13" smd circle
			(at 1.199 1.999 270)
			(size 0.45 0.45)
			(layers "F.Cu" "F.Mask" "F.Paste")
			(net 417 "GND")
			(pinfunction "VSS")
			(pintype "passive")
		)
		(pad "P14" smd circle
			(at 1.999 1.999 270)
			(size 0.45 0.45)
			(layers "F.Cu" "F.Mask" "F.Paste")
			(net 48 "+1V8")
			(pinfunction "VDD18")
			(pintype "passive")
		)
		(pad "P15" smd circle
			(at 2.799 1.999 270)
			(size 0.45 0.45)
			(layers "F.Cu" "F.Mask" "F.Paste")
			(net 417 "GND")
			(pinfunction "VSS")
			(pintype "passive")
		)
		(pad "P16" smd circle
			(at 3.6 1.999 270)
			(size 0.45 0.45)
			(layers "F.Cu" "F.Mask" "F.Paste")
			(net 48 "+1V8")
			(pinfunction "VDD18")
			(pintype "passive")
		)
		(pad "P17" smd circle
			(at 4.4 1.999 270)
			(size 0.45 0.45)
			(layers "F.Cu" "F.Mask" "F.Paste")
			(net 417 "GND")
			(pinfunction "VSS")
			(pintype "passive")
		)
		(pad "P18" smd circle
			(at 5.2 1.999 270)
			(size 0.45 0.45)
			(layers "F.Cu" "F.Mask" "F.Paste")
			(net 418 "+2V5")
			(pinfunction "VDD_XCVR_CLK")
			(pintype "passive")
		)
		(pad "P19" smd circle
			(at 5.999 1.999 270)
			(size 0.45 0.45)
			(layers "F.Cu" "F.Mask" "F.Paste")
			(net 47 "+1V05")
			(pinfunction "VDDA")
			(pintype "passive")
		)
		(pad "P20" smd circle
			(at 6.799 1.999 270)
			(size 0.45 0.45)
			(layers "F.Cu" "F.Mask" "F.Paste")
			(net 417 "GND")
			(pinfunction "VSS")
			(pintype "passive")
		)
		(pad "P21" smd circle
			(at 7.599 1.999 270)
			(size 0.45 0.45)
			(layers "F.Cu" "F.Mask" "F.Paste")
			(net 93 "/PCIe/XCVR_TX2_N")
			(pinfunction "XCVR_0_TX2_N")
			(pintype "output")
			(die_length 5.22418)
		)
		(pad "P22" smd circle
			(at 8.4 1.999 270)
			(size 0.45 0.45)
			(layers "F.Cu" "F.Mask" "F.Paste")
			(net 95 "/PCIe/XCVR_TX2_P")
			(pinfunction "XCVR_0_TX2_P")
			(pintype "output")
			(die_length 5.20705)
		)
		(pad "R1" smd circle
			(at -8.401 2.799 270)
			(size 0.45 0.45)
			(layers "F.Cu" "F.Mask" "F.Paste")
			(net 433 "unconnected-(U1G-MSS_DDR_A11-PadR1)")
			(pinfunction "MSS_DDR_A11")
			(pintype "bidirectional+no_connect")
			(die_length 5.25487)
		)
		(pad "R2" smd circle
			(at -7.6 2.799 270)
			(size 0.45 0.45)
			(layers "F.Cu" "F.Mask" "F.Paste")
			(net 417 "GND")
			(pinfunction "VSS")
			(pintype "passive")
		)
		(pad "R3" smd circle
			(at -6.8 2.799 270)
			(size 0.45 0.45)
			(layers "F.Cu" "F.Mask" "F.Paste")
			(net 434 "unconnected-(U1G-MSS_DDR_A15-PadR3)")
			(pinfunction "MSS_DDR_A15")
			(pintype "bidirectional+no_connect")
			(die_length 5.32263)
		)
		(pad "R4" smd circle
			(at -6 2.799 270)
			(size 0.45 0.45)
			(layers "F.Cu" "F.Mask" "F.Paste")
			(net 435 "unconnected-(U1G-MSS_DDR_A16-PadR4)")
			(pinfunction "MSS_DDR_A16")
			(pintype "bidirectional+no_connect")
			(die_length 4.07803)
		)
		(pad "R5" smd circle
			(at -5.201 2.799 270)
			(size 0.45 0.45)
			(layers "F.Cu" "F.Mask" "F.Paste")
			(net 568 "/FPGA MSS/LPDDR4.CA5_A")
			(pinfunction "MSS_DDR_A5")
			(pintype "bidirectional")
			(die_length 6.19696)
		)
		(pad "R6" smd circle
			(at -4.401 2.799 270)
			(size 0.45 0.45)
			(layers "F.Cu" "F.Mask" "F.Paste")
			(net 583 "/FPGA MSS/LPDDR4.CA4_A")
			(pinfunction "MSS_DDR_A4")
			(pintype "bidirectional")
			(die_length 6.05244)
		)
		(pad "R7" smd circle
			(at -3.601 2.799 270)
			(size 0.45 0.45)
			(layers "F.Cu" "F.Mask" "F.Paste")
			(net 2 "+1V1")
			(pinfunction "VDDI6")
			(pintype "passive")
		)
		(pad "R8" smd circle
			(at -2.8 2.799 270)
			(size 0.45 0.45)
			(layers "F.Cu" "F.Mask" "F.Paste")
			(net 584 "/FPGA MSS/LPDDR4.DQ30")
			(pinfunction "MSS_DDR_DQ30")
			(pintype "bidirectional")
			(die_length 7.62709)
		)
		(pad "R9" smd circle
			(at -2 2.799 270)
			(size 0.45 0.45)
			(layers "F.Cu" "F.Mask" "F.Paste")
			(net 418 "+2V5")
			(pinfunction "VDD25")
			(pintype "passive")
		)
		(pad "R10" smd circle
			(at -1.2 2.799 270)
			(size 0.45 0.45)
			(layers "F.Cu" "F.Mask" "F.Paste")
			(net 585 "/FPGA MSS/LPDDR4.DQ29")
			(pinfunction "MSS_DDR_DQ29")
			(pintype "bidirectional")
			(die_length 7.80076)
		)
		(pad "R11" smd circle
			(at -0.401 2.799 270)
			(size 0.45 0.45)
			(layers "F.Cu" "F.Mask" "F.Paste")
			(net 586 "/FPGA MSS/LPDDR4.DQ28")
			(pinfunction "MSS_DDR_DQ28")
			(pintype "bidirectional")
			(die_length 8.72485)
		)
		(pad "R12" smd circle
			(at 0.4 2.799 270)
			(size 0.45 0.45)
			(layers "F.Cu" "F.Mask" "F.Paste")
			(net 436 "unconnected-(U1A-HSIO95PB0{slash}CCC_NW_CLKIN_N_0-PadR12)")
			(pinfunction "HSIO95PB0/CCC_NW_CLKIN_N_0")
			(pintype "bidirectional+no_connect")
			(die_length 7.47419)
		)
		(pad "R13" smd circle
			(at 1.199 2.799 270)
			(size 0.45 0.45)
			(layers "F.Cu" "F.Mask" "F.Paste")
			(net 48 "+1V8")
			(pinfunction "VDD18")
			(pintype "passive")
		)
		(pad "R14" smd circle
			(at 1.999 2.799 270)
			(size 0.45 0.45)
			(layers "F.Cu" "F.Mask" "F.Paste")
			(net 291 "/FPGA HSIO/Crosslink_B1.D9")
			(pinfunction "HSIO77NB0")
			(pintype "bidirectional")
			(die_length 7.79849)
		)
		(pad "R15" smd circle
			(at 2.799 2.799 270)
			(size 0.45 0.45)
			(layers "F.Cu" "F.Mask" "F.Paste")
			(net 292 "/FPGA HSIO/Crosslink_B1.D8")
			(pinfunction "HSIO77PB0")
			(pintype "bidirectional")
			(die_length 7.79503)
		)
		(pad "R16" smd circle
			(at 3.6 2.799 270)
			(size 0.45 0.45)
			(layers "F.Cu" "F.Mask" "F.Paste")
			(net 293 "/FPGA HSIO/Crosslink_B1.D7")
			(pinfunction "HSIO75NB0/DQS")
			(pintype "bidirectional")
			(die_length 7.16841)
		)
		(pad "R17" smd circle
			(at 4.4 2.799 270)
			(size 0.45 0.45)
			(layers "F.Cu" "F.Mask" "F.Paste")
			(net 418 "+2V5")
			(pinfunction "VDD25")
			(pintype "passive")
		)
		(pad "R18" smd circle
			(at 5.2 2.799 270)
			(size 0.45 0.45)
			(layers "F.Cu" "F.Mask" "F.Paste")
			(net 417 "GND")
			(pinfunction "VSS")
			(pintype "passive")
		)
		(pad "R19" smd circle
			(at 5.999 2.799 270)
			(size 0.45 0.45)
			(layers "F.Cu" "F.Mask" "F.Paste")
			(net 142 "/Bottom Connector/PCIE.RXD3_N")
			(pinfunction "XCVR_0_RX3_N")
			(pintype "input")
			(die_length 3.50387)
		)
		(pad "R20" smd circle
			(at 6.799 2.799 270)
			(size 0.45 0.45)
			(layers "F.Cu" "F.Mask" "F.Paste")
			(net 141 "/Bottom Connector/PCIE.RXD3_P")
			(pinfunction "XCVR_0_RX3_P")
			(pintype "input")
			(die_length 3.48923)
		)
		(pad "R21" smd circle
			(at 7.599 2.799 270)
			(size 0.45 0.45)
			(layers "F.Cu" "F.Mask" "F.Paste")
			(net 47 "+1V05")
			(pinfunction "VDDA")
			(pintype "passive")
		)
		(pad "R22" smd circle
			(at 8.4 2.799 270)
			(size 0.45 0.45)
			(layers "F.Cu" "F.Mask" "F.Paste")
			(net 417 "GND")
			(pinfunction "VSS")
			(pintype "passive")
		)
		(pad "T1" smd circle
			(at -8.401 3.6 270)
			(size 0.45 0.45)
			(layers "F.Cu" "F.Mask" "F.Paste")
			(net 437 "unconnected-(U1G-MSS_DDR_CK1{slash}DDR_PLL0_OUT0-PadT1)")
			(pinfunction "MSS_DDR_CK1/DDR_PLL0_OUT0")
			(pintype "bidirectional+no_connect")
			(die_length 4.79804)
		)
		(pad "T2" smd circle
			(at -7.6 3.6 270)
			(size 0.45 0.45)
			(layers "F.Cu" "F.Mask" "F.Paste")
			(net 438 "unconnected-(U1G-MSS_DDR_CK_N1-PadT2)")
			(pinfunction "MSS_DDR_CK_N1")
			(pintype "bidirectional+no_connect")
			(die_length 4.67044)
		)
		(pad "T3" smd circle
			(at -6.8 3.6 270)
			(size 0.45 0.45)
			(layers "F.Cu" "F.Mask" "F.Paste")
			(net 439 "unconnected-(U1G-MSS_DDR_BA1-PadT3)")
			(pinfunction "MSS_DDR_BA1")
			(pintype "bidirectional+no_connect")
			(die_length 4.12005)
		)
		(pad "T4" smd circle
			(at -6 3.6 270)
			(size 0.45 0.45)
			(layers "F.Cu" "F.Mask" "F.Paste")
			(net 2 "+1V1")
			(pinfunction "VDDI6")
			(pintype "passive")
		)
		(pad "T5" smd circle
			(at -5.201 3.6 270)
			(size 0.45 0.45)
			(layers "F.Cu" "F.Mask" "F.Paste")
			(net 587 "/FPGA MSS/LPDDR4.CA0_A")
			(pinfunction "MSS_DDR_A0")
			(pintype "bidirectional")
			(die_length 7.63353)
		)
		(pad "T6" smd circle
			(at -4.401 3.6 270)
			(size 0.45 0.45)
			(layers "F.Cu" "F.Mask" "F.Paste")
			(net 588 "/FPGA MSS/LPDDR4.CA1_A")
			(pinfunction "MSS_DDR_A1")
			(pintype "bidirectional")
			(die_length 8.29046)
		)
		(pad "T7" smd circle
			(at -3.601 3.6 270)
			(size 0.45 0.45)
			(layers "F.Cu" "F.Mask" "F.Paste")
			(net 440 "unconnected-(U1G-MSS_DDR_A7-PadT7)")
			(pinfunction "MSS_DDR_A7")
			(pintype "bidirectional+no_connect")
			(die_length 5.35265)
		)
		(pad "T8" smd circle
			(at -2.8 3.6 270)
			(size 0.45 0.45)
			(layers "F.Cu" "F.Mask" "F.Paste")
			(net 589 "/FPGA MSS/LPDDR4.DQ25")
			(pinfunction "MSS_DDR_DQ25")
			(pintype "bidirectional")
			(die_length 7.08383)
		)
		(pad "T9" smd circle
			(at -2 3.6 270)
			(size 0.45 0.45)
			(layers "F.Cu" "F.Mask" "F.Paste")
			(net 417 "GND")
			(pinfunction "VSS")
			(pintype "passive")
		)
		(pad "T10" smd circle
			(at -1.2 3.6 270)
			(size 0.45 0.45)
			(layers "F.Cu" "F.Mask" "F.Paste")
			(net 590 "/FPGA MSS/LPDDR4.DMI3")
			(pinfunction "MSS_DDR_DM3")
			(pintype "bidirectional")
			(die_length 7.77046)
		)
		(pad "T11" smd circle
			(at -0.401 3.6 270)
			(size 0.45 0.45)
			(layers "F.Cu" "F.Mask" "F.Paste")
			(net 591 "/FPGA MSS/LPDDR4.DQ26")
			(pinfunction "MSS_DDR_DQ26")
			(pintype "bidirectional")
			(die_length 8.39636)
		)
		(pad "T12" smd circle
			(at 0.4 3.6 270)
			(size 0.45 0.45)
			(layers "F.Cu" "F.Mask" "F.Paste")
			(net 441 "unconnected-(U1A-HSIO94NB0-PadT12)")
			(pinfunction "HSIO94NB0")
			(pintype "bidirectional+no_connect")
			(die_length 7.24278)
		)
		(pad "T13" smd circle
			(at 1.199 3.6 270)
			(size 0.45 0.45)
			(layers "F.Cu" "F.Mask" "F.Paste")
			(net 442 "unconnected-(U1A-HSIO95NB0-PadT13)")
			(pinfunction "HSIO95NB0")
			(pintype "bidirectional+no_connect")
			(die_length 7.48434)
		)
		(pad "T14" smd circle
			(at 1.999 3.6 270)
			(size 0.45 0.45)
			(layers "F.Cu" "F.Mask" "F.Paste")
			(net 48 "+1V8")
			(pinfunction "VDDI0")
			(pintype "passive")
		)
		(pad "T15" smd circle
			(at 2.799 3.6 270)
			(size 0.45 0.45)
			(layers "F.Cu" "F.Mask" "F.Paste")
			(net 443 "unconnected-(U1A-HSIO91NB0-PadT15)")
			(pinfunction "HSIO91NB0")
			(pintype "bidirectional+no_connect")
			(die_length 7.08627)
		)
		(pad "T16" smd circle
			(at 3.6 3.6 270)
			(size 0.45 0.45)
			(layers "F.Cu" "F.Mask" "F.Paste")
			(net 294 "/FPGA HSIO/Crosslink_B2.D8")
			(pinfunction "HSIO75PB0/DQS/CCC_NE_PLL1_OUT0")
			(pintype "bidirectional")
			(die_length 7.1755)
		)
		(pad "T17" smd circle
			(at 4.4 3.6 270)
			(size 0.45 0.45)
			(layers "F.Cu" "F.Mask" "F.Paste")
			(net 298 "/FPGA HSIO/Crosslink_B1.D2")
			(pinfunction "HSIO73PB0/CCC_NE_PLL1_OUT1")
			(pintype "bidirectional")
			(die_length 7.13684)
		)
		(pad "T18" smd circle
			(at 5.2 3.6 270)
			(size 0.45 0.45)
			(layers "F.Cu" "F.Mask" "F.Paste")
			(net 417 "GND")
			(pinfunction "VSS")
			(pintype "passive")
		)
		(pad "T19" smd circle
			(at 5.999 3.6 270)
			(size 0.45 0.45)
			(layers "F.Cu" "F.Mask" "F.Paste")
			(net 417 "GND")
			(pinfunction "VSS")
			(pintype "passive")
		)
		(pad "T20" smd circle
			(at 6.799 3.6 270)
			(size 0.45 0.45)
			(layers "F.Cu" "F.Mask" "F.Paste")
			(net 417 "GND")
			(pinfunction "VSS")
			(pintype "passive")
		)
		(pad "T21" smd circle
			(at 7.599 3.6 270)
			(size 0.45 0.45)
			(layers "F.Cu" "F.Mask" "F.Paste")
			(net 66 "/PCIe/XCVR_TX3_N")
			(pinfunction "XCVR_0_TX3_N")
			(pintype "output")
			(die_length 5.78253)
		)
		(pad "T22" smd circle
			(at 8.4 3.6 270)
			(size 0.45 0.45)
			(layers "F.Cu" "F.Mask" "F.Paste")
			(net 91 "/PCIe/XCVR_TX3_P")
			(pinfunction "XCVR_0_TX3_P")
			(pintype "output")
			(die_length 5.76703)
		)
		(pad "U1" smd circle
			(at -8.401 4.4 270)
			(size 0.45 0.45)
			(layers "F.Cu" "F.Mask" "F.Paste")
			(net 2 "+1V1")
			(pinfunction "VDDI6")
			(pintype "passive")
		)
		(pad "U2" smd circle
			(at -7.6 4.4 270)
			(size 0.45 0.45)
			(layers "F.Cu" "F.Mask" "F.Paste")
			(net 444 "unconnected-(U1G-MSS_DDR_A10-PadU2)")
			(pinfunction "MSS_DDR_A10")
			(pintype "bidirectional+no_connect")
			(die_length 5.14531)
		)
		(pad "U3" smd circle
			(at -6.8 4.4 270)
			(size 0.45 0.45)
			(layers "F.Cu" "F.Mask" "F.Paste")
			(net 445 "unconnected-(U1G-MSS_DDR3_WE_N-PadU3)")
			(pinfunction "MSS_DDR3_WE_N")
			(pintype "bidirectional+no_connect")
			(die_length 4.85174)
		)
		(pad "U4" smd circle
			(at -6 4.4 270)
			(size 0.45 0.45)
			(layers "F.Cu" "F.Mask" "F.Paste")
			(net 592 "/FPGA MSS/LPDDR4.CK_N")
			(pinfunction "MSS_DDR_CK_N0")
			(pintype "bidirectional")
			(die_length 6.59715)
		)
		(pad "U5" smd circle
			(at -5.201 4.4 270)
			(size 0.45 0.45)
			(layers "F.Cu" "F.Mask" "F.Paste")
			(net 593 "/FPGA MSS/LPDDR4.CK_P")
			(pinfunction "MSS_DDR_CK0/DDR_PLL0_OUT0")
			(pintype "bidirectional")
			(die_length 7.07391)
		)
		(pad "U6" smd circle
			(at -4.401 4.4 270)
			(size 0.45 0.45)
			(layers "F.Cu" "F.Mask" "F.Paste")
			(net 417 "GND")
			(pinfunction "VSS")
			(pintype "passive")
		)
		(pad "U7" smd circle
			(at -3.601 4.4 270)
			(size 0.45 0.45)
			(layers "F.Cu" "F.Mask" "F.Paste")
			(net 446 "unconnected-(U1G-MSS_DDR_A9-PadU7)")
			(pinfunction "MSS_DDR_A9")
			(pintype "bidirectional+no_connect")
			(die_length 5.68076)
		)
		(pad "U8" smd circle
			(at -2.8 4.4 270)
			(size 0.45 0.45)
			(layers "F.Cu" "F.Mask" "F.Paste")
			(net 594 "/FPGA MSS/LPDDR4.DQ24")
			(pinfunction "MSS_DDR_DQ24")
			(pintype "bidirectional")
			(die_length 7.11722)
		)
		(pad "U9" smd circle
			(at -2 4.4 270)
			(size 0.45 0.45)
			(layers "F.Cu" "F.Mask" "F.Paste")
			(net 595 "/FPGA MSS/LPDDR4.DQS3_P")
			(pinfunction "MSS_DDR_DQS_P3")
			(pintype "bidirectional")
			(die_length 8.22807)
		)
		(pad "U10" smd circle
			(at -1.2 4.4 270)
			(size 0.45 0.45)
			(layers "F.Cu" "F.Mask" "F.Paste")
			(net 596 "/FPGA MSS/LPDDR4.DQ27")
			(pinfunction "MSS_DDR_DQ27")
			(pintype "bidirectional")
			(die_length 7.48606)
		)
		(pad "U11" smd circle
			(at -0.401 4.4 270)
			(size 0.45 0.45)
			(layers "F.Cu" "F.Mask" "F.Paste")
			(net 2 "+1V1")
			(pinfunction "VDDI6")
			(pintype "passive")
		)
		(pad "U12" smd circle
			(at 0.4 4.4 270)
			(size 0.45 0.45)
			(layers "F.Cu" "F.Mask" "F.Paste")
			(net 447 "unconnected-(U1A-HSIO94PB0{slash}CCC_NW_CLKIN_N_1-PadU12)")
			(pinfunction "HSIO94PB0/CCC_NW_CLKIN_N_1")
			(pintype "bidirectional+no_connect")
			(die_length 7.22878)
		)
		(pad "U13" smd circle
			(at 1.199 4.4 270)
			(size 0.45 0.45)
			(layers "F.Cu" "F.Mask" "F.Paste")
			(net 448 "unconnected-(U1A-HSIO93NB0{slash}DQS-PadU13)")
			(pinfunction "HSIO93NB0/DQS")
			(pintype "bidirectional+no_connect")
			(die_length 6.85376)
		)
		(pad "U14" smd circle
			(at 1.999 4.4 270)
			(size 0.45 0.45)
			(layers "F.Cu" "F.Mask" "F.Paste")
			(net 449 "unconnected-(U1A-HSIO93PB0{slash}DQS{slash}CCC_NW_PLL1_OUT0-PadU14)")
			(pinfunction "HSIO93PB0/DQS/CCC_NW_PLL1_OUT0")
			(pintype "bidirectional+no_connect")
			(die_length 6.84078)
		)
		(pad "U15" smd circle
			(at 2.799 4.4 270)
			(size 0.45 0.45)
			(layers "F.Cu" "F.Mask" "F.Paste")
			(net 450 "unconnected-(U1A-HSIO91PB0{slash}CCC_NW_PLL1_OUT1-PadU15)")
			(pinfunction "HSIO91PB0/CCC_NW_PLL1_OUT1")
			(pintype "bidirectional+no_connect")
			(die_length 7.05354)
		)
		(pad "U16" smd circle
			(at 3.6 4.4 270)
			(size 0.45 0.45)
			(layers "F.Cu" "F.Mask" "F.Paste")
			(net 417 "GND")
			(pinfunction "VSS")
			(pintype "passive")
		)
		(pad "U17" smd circle
			(at 4.4 4.4 270)
			(size 0.45 0.45)
			(layers "F.Cu" "F.Mask" "F.Paste")
			(net 299 "/FPGA HSIO/Crosslink_B1.D3")
			(pinfunction "HSIO73NB0")
			(pintype "bidirectional")
			(die_length 7.1737)
		)
		(pad "U18" smd circle
			(at 5.2 4.4 270)
			(size 0.45 0.45)
			(layers "F.Cu" "F.Mask" "F.Paste")
			(net 300 "/FPGA HSIO/Crosslink_B1.D1")
			(pinfunction "HSIO74NB0")
			(pintype "bidirectional")
			(die_length 7.75836)
		)
		(pad "U19" smd circle
			(at 5.999 4.4 270)
			(size 0.45 0.45)
			(layers "F.Cu" "F.Mask" "F.Paste")
			(net 303 "/FPGA HSIO/Crosslink_B1.D0")
			(pinfunction "HSIO74PB0/CLKIN_N_8/CCC_NE_CLKIN_N_8/CCC_NE_PLL1_OUT0")
			(pintype "bidirectional")
			(die_length 7.74846)
		)
		(pad "U20" smd circle
			(at 6.799 4.4 270)
			(size 0.45 0.45)
			(layers "F.Cu" "F.Mask" "F.Paste")
			(net 417 "GND")
			(pinfunction "VSS")
			(pintype "passive")
		)
		(pad "U21" smd circle
			(at 7.599 4.4 270)
			(size 0.45 0.45)
			(layers "F.Cu" "F.Mask" "F.Paste")
			(net 417 "GND")
			(pinfunction "VSS")
			(pintype "passive")
		)
		(pad "U22" smd circle
			(at 8.4 4.4 270)
			(size 0.45 0.45)
			(layers "F.Cu" "F.Mask" "F.Paste")
			(net 417 "GND")
			(pinfunction "VSS")
			(pintype "passive")
		)
		(pad "V1" smd circle
			(at -8.401 5.2 270)
			(size 0.45 0.45)
			(layers "F.Cu" "F.Mask" "F.Paste")
			(net 451 "unconnected-(U1G-MSS_DDR_DQS_N4-PadV1)")
			(pinfunction "MSS_DDR_DQS_N4")
			(pintype "bidirectional+no_connect")
			(die_length 5.02325)
		)
		(pad "V2" smd circle
			(at -7.6 5.2 270)
			(size 0.45 0.45)
			(layers "F.Cu" "F.Mask" "F.Paste")
			(net 452 "unconnected-(U1G-MSS_DDR_DQS_P4-PadV2)")
			(pinfunction "MSS_DDR_DQS_P4")
			(pintype "bidirectional+no_connect")
			(die_length 5.02709)
		)
		(pad "V3" smd circle
			(at -6.8 5.2 270)
			(size 0.45 0.45)
			(layers "F.Cu" "F.Mask" "F.Paste")
			(net 417 "GND")
			(pinfunction "VSS")
			(pintype "passive")
		)
		(pad "V4" smd circle
			(at -6 5.2 270)
			(size 0.45 0.45)
			(layers "F.Cu" "F.Mask" "F.Paste")
			(net 270 "Net-(U1G-MSS_DDR_VREF_IN)")
			(pinfunction "MSS_DDR_VREF_IN")
			(pintype "input")
			(die_length 3.57164)
		)
		(pad "V5" smd circle
			(at -5.201 5.2 270)
			(size 0.45 0.45)
			(layers "F.Cu" "F.Mask" "F.Paste")
			(net 453 "unconnected-(U1G-MSS_DDR_DM4-PadV5)")
			(pinfunction "MSS_DDR_DM4")
			(pintype "bidirectional+no_connect")
			(die_length 4.03998)
		)
		(pad "V6" smd circle
			(at -4.401 5.2 270)
			(size 0.45 0.45)
			(layers "F.Cu" "F.Mask" "F.Paste")
			(net 597 "/FPGA MSS/LPDDR4.CA3_A")
			(pinfunction "MSS_DDR_A3")
			(pintype "bidirectional")
			(die_length 6.53023)
		)
		(pad "V7" smd circle
			(at -3.601 5.2 270)
			(size 0.45 0.45)
			(layers "F.Cu" "F.Mask" "F.Paste")
			(net 598 "/FPGA MSS/LPDDR4.CA2_A")
			(pinfunction "MSS_DDR_A2")
			(pintype "bidirectional")
			(die_length 6.68562)
		)
		(pad "V8" smd circle
			(at -2.8 5.2 270)
			(size 0.45 0.45)
			(layers "F.Cu" "F.Mask" "F.Paste")
			(net 2 "+1V1")
			(pinfunction "VDDI6")
			(pintype "passive")
		)
		(pad "V9" smd circle
			(at -2 5.2 270)
			(size 0.45 0.45)
			(layers "F.Cu" "F.Mask" "F.Paste")
			(net 599 "/FPGA MSS/LPDDR4.DQS3_N")
			(pinfunction "MSS_DDR_DQS_N3")
			(pintype "bidirectional")
			(die_length 8.21899)
		)
		(pad "V10" smd circle
			(at -1.2 5.2 270)
			(size 0.45 0.45)
			(layers "F.Cu" "F.Mask" "F.Paste")
			(net 600 "/FPGA MSS/LPDDR4.DQ21")
			(pinfunction "MSS_DDR_DQ21")
			(pintype "bidirectional")
			(die_length 8.68063)
		)
		(pad "V11" smd circle
			(at -0.401 5.2 270)
			(size 0.45 0.45)
			(layers "F.Cu" "F.Mask" "F.Paste")
			(net 601 "/FPGA MSS/LPDDR4.DQ20")
			(pinfunction "MSS_DDR_DQ20")
			(pintype "bidirectional")
			(die_length 9.2829)
		)
		(pad "V12" smd circle
			(at 0.4 5.2 270)
			(size 0.45 0.45)
			(layers "F.Cu" "F.Mask" "F.Paste")
			(net 454 "unconnected-(U1A-HSIO92NB0-PadV12)")
			(pinfunction "HSIO92NB0")
			(pintype "bidirectional+no_connect")
			(die_length 7.65608)
		)
		(pad "V13" smd circle
			(at 1.199 5.2 270)
			(size 0.45 0.45)
			(layers "F.Cu" "F.Mask" "F.Paste")
			(net 417 "GND")
			(pinfunction "VSS")
			(pintype "passive")
		)
		(pad "V14" smd circle
			(at 1.999 5.2 270)
			(size 0.45 0.45)
			(layers "F.Cu" "F.Mask" "F.Paste")
			(net 455 "unconnected-(U1A-HSIO90PB0{slash}CLKIN_N_3{slash}CCC_NW_CLKIN_N_3-PadV14)")
			(pinfunction "HSIO90PB0/CLKIN_N_3/CCC_NW_CLKIN_N_3")
			(pintype "bidirectional+no_connect")
			(die_length 7.13069)
		)
		(pad "V15" smd circle
			(at 2.799 5.2 270)
			(size 0.45 0.45)
			(layers "F.Cu" "F.Mask" "F.Paste")
			(net 456 "unconnected-(U1A-HSIO90NB0-PadV15)")
			(pinfunction "HSIO90NB0")
			(pintype "bidirectional+no_connect")
			(die_length 7.12976)
		)
		(pad "V16" smd circle
			(at 3.6 5.2 270)
			(size 0.45 0.45)
			(layers "F.Cu" "F.Mask" "F.Paste")
			(net 304 "/FPGA HSIO/Crosslink_B2.D7")
			(pinfunction "HSIO76NB0")
			(pintype "bidirectional")
			(die_length 6.53981)
		)
		(pad "V17" smd circle
			(at 4.4 5.2 270)
			(size 0.45 0.45)
			(layers "F.Cu" "F.Mask" "F.Paste")
			(net 327 "/FPGA HSIO/Crosslink_B1.D4")
			(pinfunction "HSIO76PB0")
			(pintype "bidirectional")
			(die_length 6.54753)
		)
		(pad "V18" smd circle
			(at 5.2 5.2 270)
			(size 0.45 0.45)
			(layers "F.Cu" "F.Mask" "F.Paste")
			(net 48 "+1V8")
			(pinfunction "VDDI0")
			(pintype "passive")
		)
		(pad "V19" smd circle
			(at 5.999 5.2 270)
			(size 0.45 0.45)
			(layers "F.Cu" "F.Mask" "F.Paste")
			(net 328 "/FPGA HSIO/Crosslink_B1.D6")
			(pinfunction "HSIO72NB0")
			(pintype "bidirectional")
			(die_length 8.19662)
		)
		(pad "V20" smd circle
			(at 6.799 5.2 270)
			(size 0.45 0.45)
			(layers "F.Cu" "F.Mask" "F.Paste")
			(net 329 "/FPGA HSIO/Crosslink_B2.D1")
			(pinfunction "HSIO72PB0/CLKIN_N_9/CCC_NE_CLKIN_N_9")
			(pintype "bidirectional")
			(die_length 8.20769)
		)
		(pad "V21" smd circle
			(at 7.599 5.2 270)
			(size 0.45 0.45)
			(layers "F.Cu" "F.Mask" "F.Paste")
			(net 331 "/FPGA HSIO/Crosslink_B2.PCLK")
			(pinfunction "HSIO68NB0")
			(pintype "bidirectional")
			(die_length 6.55804)
		)
		(pad "V22" smd circle
			(at 8.4 5.2 270)
			(size 0.45 0.45)
			(layers "F.Cu" "F.Mask" "F.Paste")
			(net 335 "/FPGA HSIO/Crosslink_B1.HSYNC")
			(pinfunction "HSIO66NB0")
			(pintype "bidirectional")
			(die_length 6.64242)
		)
		(pad "W1" smd circle
			(at -8.401 5.999 270)
			(size 0.45 0.45)
			(layers "F.Cu" "F.Mask" "F.Paste")
			(net 457 "unconnected-(U1G-MSS_DDR_DQ35-PadW1)")
			(pinfunction "MSS_DDR_DQ35")
			(pintype "bidirectional+no_connect")
			(die_length 5.04829)
		)
		(pad "W2" smd circle
			(at -7.6 5.999 270)
			(size 0.45 0.45)
			(layers "F.Cu" "F.Mask" "F.Paste")
			(net 458 "unconnected-(U1G-MSS_DDR_DQ34-PadW2)")
			(pinfunction "MSS_DDR_DQ34")
			(pintype "bidirectional+no_connect")
			(die_length 4.45648)
		)
		(pad "W3" smd circle
			(at -6.8 5.999 270)
			(size 0.45 0.45)
			(layers "F.Cu" "F.Mask" "F.Paste")
			(net 459 "unconnected-(U1G-MSS_DDR_DQ33-PadW3)")
			(pinfunction "MSS_DDR_DQ33")
			(pintype "bidirectional+no_connect")
			(die_length 3.88376)
		)
		(pad "W4" smd circle
			(at -6 5.999 270)
			(size 0.45 0.45)
			(layers "F.Cu" "F.Mask" "F.Paste")
			(net 460 "unconnected-(U1G-MSS_DDR_DQ32-PadW4)")
			(pinfunction "MSS_DDR_DQ32")
			(pintype "bidirectional+no_connect")
			(die_length 4.30238)
		)
		(pad "W5" smd circle
			(at -5.201 5.999 270)
			(size 0.45 0.45)
			(layers "F.Cu" "F.Mask" "F.Paste")
			(net 2 "+1V1")
			(pinfunction "VDDI6")
			(pintype "passive")
		)
		(pad "W6" smd circle
			(at -4.401 5.999 270)
			(size 0.45 0.45)
			(layers "F.Cu" "F.Mask" "F.Paste")
			(net 602 "/FPGA MSS/LPDDR4.DQS1_N")
			(pinfunction "MSS_DDR_DQS_N1")
			(pintype "bidirectional")
			(die_length 6.70831)
		)
		(pad "W7" smd circle
			(at -3.601 5.999 270)
			(size 0.45 0.45)
			(layers "F.Cu" "F.Mask" "F.Paste")
			(net 603 "/FPGA MSS/LPDDR4.DQ9")
			(pinfunction "MSS_DDR_DQ9")
			(pintype "bidirectional")
			(die_length 6.57901)
		)
		(pad "W8" smd circle
			(at -2.8 5.999 270)
			(size 0.45 0.45)
			(layers "F.Cu" "F.Mask" "F.Paste")
			(net 604 "/FPGA MSS/LPDDR4.DQ8")
			(pinfunction "MSS_DDR_DQ8")
			(pintype "bidirectional")
			(die_length 7.65979)
		)
		(pad "W9" smd circle
			(at -2 5.999 270)
			(size 0.45 0.45)
			(layers "F.Cu" "F.Mask" "F.Paste")
			(net 605 "/FPGA MSS/LPDDR4.DQ17")
			(pinfunction "MSS_DDR_DQ17")
			(pintype "bidirectional")
			(die_length 6.80016)
		)
		(pad "W10" smd circle
			(at -1.2 5.999 270)
			(size 0.45 0.45)
			(layers "F.Cu" "F.Mask" "F.Paste")
			(net 417 "GND")
			(pinfunction "VSS")
			(pintype "passive")
		)
		(pad "W11" smd circle
			(at -0.401 5.999 270)
			(size 0.45 0.45)
			(layers "F.Cu" "F.Mask" "F.Paste")
			(net 606 "/FPGA MSS/LPDDR4.DQ23")
			(pinfunction "MSS_DDR_DQ23")
			(pintype "bidirectional")
			(die_length 7.37032)
		)
		(pad "W12" smd circle
			(at 0.4 5.999 270)
			(size 0.45 0.45)
			(layers "F.Cu" "F.Mask" "F.Paste")
			(net 336 "/FPGA HSIO/PF_CLK")
			(pinfunction "HSIO92PB0/CLKIN_N_2/CCC_NW_CLKIN_N_2/CCC_NW_PLL1_OUT0")
			(pintype "bidirectional")
			(die_length 7.66699)
		)
		(pad "W13" smd circle
			(at 1.199 5.999 270)
			(size 0.45 0.45)
			(layers "F.Cu" "F.Mask" "F.Paste")
			(net 462 "unconnected-(U1A-HSIO89PB0-PadW13)")
			(pinfunction "HSIO89PB0")
			(pintype "bidirectional+no_connect")
			(die_length 5.70016)
		)
		(pad "W14" smd circle
			(at 1.999 5.999 270)
			(size 0.45 0.45)
			(layers "F.Cu" "F.Mask" "F.Paste")
			(net 463 "unconnected-(U1A-HSIO87NB0{slash}DQS-PadW14)")
			(pinfunction "HSIO87NB0/DQS")
			(pintype "bidirectional+no_connect")
			(die_length 6.51699)
		)
		(pad "W15" smd circle
			(at 2.799 5.999 270)
			(size 0.45 0.45)
			(layers "F.Cu" "F.Mask" "F.Paste")
			(net 48 "+1V8")
			(pinfunction "VDDI0")
			(pintype "passive")
		)
		(pad "W16" smd circle
			(at 3.6 5.999 270)
			(size 0.45 0.45)
			(layers "F.Cu" "F.Mask" "F.Paste")
			(net 464 "unconnected-(U1A-HSIO83PB0-PadW16)")
			(pinfunction "HSIO83PB0")
			(pintype "bidirectional+no_connect")
			(die_length 6.04706)
		)
		(pad "W17" smd circle
			(at 4.4 5.999 270)
			(size 0.45 0.45)
			(layers "F.Cu" "F.Mask" "F.Paste")
			(net 465 "unconnected-(U1A-HSIO83NB0-PadW17)")
			(pinfunction "HSIO83NB0")
			(pintype "bidirectional+no_connect")
			(die_length 6.04459)
		)
		(pad "W18" smd circle
			(at 5.2 5.999 270)
			(size 0.45 0.45)
			(layers "F.Cu" "F.Mask" "F.Paste")
			(net 466 "unconnected-(U1A-HSIO79NB0-PadW18)")
			(pinfunction "HSIO79NB0")
			(pintype "bidirectional+no_connect")
			(die_length 6.53818)
		)
		(pad "W19" smd circle
			(at 5.999 5.999 270)
			(size 0.45 0.45)
			(layers "F.Cu" "F.Mask" "F.Paste")
			(net 337 "/FPGA HSIO/Crosslink_B1.D5")
			(pinfunction "HSIO79PB0")
			(pintype "bidirectional")
			(die_length 6.51467)
		)
		(pad "W20" smd circle
			(at 6.799 5.999 270)
			(size 0.45 0.45)
			(layers "F.Cu" "F.Mask" "F.Paste")
			(net 417 "GND")
			(pinfunction "VSS")
			(pintype "passive")
		)
		(pad "W21" smd circle
			(at 7.599 5.999 270)
			(size 0.45 0.45)
			(layers "F.Cu" "F.Mask" "F.Paste")
			(net 338 "/FPGA HSIO/Crosslink_B2.HSYNC")
			(pinfunction "HSIO68PB0/CCC_NE_CLKIN_N_10/CCC_NE_PLL0_OUT0")
			(pintype "bidirectional")
			(die_length 6.54838)
		)
		(pad "W22" smd circle
			(at 8.4 5.999 270)
			(size 0.45 0.45)
			(layers "F.Cu" "F.Mask" "F.Paste")
			(net 339 "/FPGA HSIO/Crosslink_B1.VSYNC")
			(pinfunction "HSIO66PB0/CCC_NE_CLKIN_N_11")
			(pintype "bidirectional")
			(die_length 6.65293)
		)
		(pad "Y1" smd circle
			(at -8.401 6.799 270)
			(size 0.45 0.45)
			(layers "F.Cu" "F.Mask" "F.Paste")
			(net 607 "/FPGA MSS/LPDDR4.DQ2")
			(pinfunction "MSS_DDR_DQ2")
			(pintype "bidirectional")
			(die_length 5.78605)
		)
		(pad "Y2" smd circle
			(at -7.6 6.799 270)
			(size 0.45 0.45)
			(layers "F.Cu" "F.Mask" "F.Paste")
			(net 2 "+1V1")
			(pinfunction "VDDI6")
			(pintype "passive")
		)
		(pad "Y3" smd circle
			(at -6.8 6.799 270)
			(size 0.45 0.45)
			(layers "F.Cu" "F.Mask" "F.Paste")
			(net 608 "/FPGA MSS/LPDDR4.DQ0")
			(pinfunction "MSS_DDR_DQ0")
			(pintype "bidirectional")
			(die_length 5.09962)
		)
		(pad "Y4" smd circle
			(at -6 6.799 270)
			(size 0.45 0.45)
			(layers "F.Cu" "F.Mask" "F.Paste")
			(net 609 "/FPGA MSS/LPDDR4.DQ1")
			(pinfunction "MSS_DDR_DQ1")
			(pintype "bidirectional")
			(die_length 5.44242)
		)
		(pad "Y5" smd circle
			(at -5.201 6.799 270)
			(size 0.45 0.45)
			(layers "F.Cu" "F.Mask" "F.Paste")
			(net 610 "/FPGA MSS/LPDDR4.DQ4")
			(pinfunction "MSS_DDR_DQ4")
			(pintype "bidirectional")
			(die_length 4.77603)
		)
		(pad "Y6" smd circle
			(at -4.401 6.799 270)
			(size 0.45 0.45)
			(layers "F.Cu" "F.Mask" "F.Paste")
			(net 611 "/FPGA MSS/LPDDR4.DQS1_P")
			(pinfunction "MSS_DDR_DQS_P1")
			(pintype "bidirectional")
			(die_length 6.71775)
		)
		(pad "Y7" smd circle
			(at -3.601 6.799 270)
			(size 0.45 0.45)
			(layers "F.Cu" "F.Mask" "F.Paste")
			(net 417 "GND")
			(pinfunction "VSS")
			(pintype "passive")
		)
		(pad "Y8" smd circle
			(at -2.8 6.799 270)
			(size 0.45 0.45)
			(layers "F.Cu" "F.Mask" "F.Paste")
			(net 612 "/FPGA MSS/LPDDR4.DQ14")
			(pinfunction "MSS_DDR_DQ14")
			(pintype "bidirectional")
			(die_length 6.40444)
		)
		(pad "Y9" smd circle
			(at -2 6.799 270)
			(size 0.45 0.45)
			(layers "F.Cu" "F.Mask" "F.Paste")
			(net 613 "/FPGA MSS/LPDDR4.DQ16")
			(pinfunction "MSS_DDR_DQ16")
			(pintype "bidirectional")
			(die_length 6.5997)
		)
		(pad "Y10" smd circle
			(at -1.2 6.799 270)
			(size 0.45 0.45)
			(layers "F.Cu" "F.Mask" "F.Paste")
			(net 614 "/FPGA MSS/LPDDR4.DMI2")
			(pinfunction "MSS_DDR_DM2")
			(pintype "bidirectional")
			(die_length 6.72065)
		)
		(pad "Y11" smd circle
			(at -0.401 6.799 270)
			(size 0.45 0.45)
			(layers "F.Cu" "F.Mask" "F.Paste")
			(net 615 "/FPGA MSS/LPDDR4.DQ22")
			(pinfunction "MSS_DDR_DQ22")
			(pintype "bidirectional")
			(die_length 7.06682)
		)
		(pad "Y12" smd circle
			(at 0.4 6.799 270)
			(size 0.45 0.45)
			(layers "F.Cu" "F.Mask" "F.Paste")
			(net 48 "+1V8")
			(pinfunction "VDDI0")
			(pintype "passive")
		)
		(pad "Y13" smd circle
			(at 1.199 6.799 270)
			(size 0.45 0.45)
			(layers "F.Cu" "F.Mask" "F.Paste")
			(net 467 "unconnected-(U1A-HSIO89NB0-PadY13)")
			(pinfunction "HSIO89NB0")
			(pintype "bidirectional+no_connect")
			(die_length 5.65691)
		)
		(pad "Y14" smd circle
			(at 1.999 6.799 270)
			(size 0.45 0.45)
			(layers "F.Cu" "F.Mask" "F.Paste")
			(net 468 "unconnected-(U1A-HSIO87PB0{slash}DQS{slash}CCC_NW_PLL0_OUT0-PadY14)")
			(pinfunction "HSIO87PB0/DQS/CCC_NW_PLL0_OUT0")
			(pintype "bidirectional+no_connect")
			(die_length 6.51034)
		)
		(pad "Y15" smd circle
			(at 2.799 6.799 270)
			(size 0.45 0.45)
			(layers "F.Cu" "F.Mask" "F.Paste")
			(net 469 "unconnected-(U1A-HSIO85PB0{slash}CCC_NW_PLL0_OUT1-PadY15)")
			(pinfunction "HSIO85PB0/CCC_NW_PLL0_OUT1")
			(pintype "bidirectional+no_connect")
			(die_length 5.39115)
		)
		(pad "Y16" smd circle
			(at 3.6 6.799 270)
			(size 0.45 0.45)
			(layers "F.Cu" "F.Mask" "F.Paste")
			(net 470 "unconnected-(U1A-HSIO82NB0-PadY16)")
			(pinfunction "HSIO82NB0")
			(pintype "bidirectional+no_connect")
			(die_length 6.52137)
		)
		(pad "Y17" smd circle
			(at 4.4 6.799 270)
			(size 0.45 0.45)
			(layers "F.Cu" "F.Mask" "F.Paste")
			(net 417 "GND")
			(pinfunction "VSS")
			(pintype "passive")
		)
		(pad "Y18" smd circle
			(at 5.2 6.799 270)
			(size 0.45 0.45)
			(layers "F.Cu" "F.Mask" "F.Paste")
			(net 471 "unconnected-(U1A-HSIO80NB0-PadY18)")
			(pinfunction "HSIO80NB0")
			(pintype "bidirectional+no_connect")
			(die_length 7.63395)
		)
		(pad "Y19" smd circle
			(at 5.999 6.799 270)
			(size 0.45 0.45)
			(layers "F.Cu" "F.Mask" "F.Paste")
			(net 472 "unconnected-(U1A-HSIO80PB0{slash}CLKIN_N_6-PadY19)")
			(pinfunction "HSIO80PB0/CLKIN_N_6")
			(pintype "bidirectional+no_connect")
			(die_length 7.64669)
		)
		(pad "Y20" smd circle
			(at 6.799 6.799 270)
			(size 0.45 0.45)
			(layers "F.Cu" "F.Mask" "F.Paste")
			(net 340 "/FPGA HSIO/Crosslink_B1.PCLK")
			(pinfunction "HSIO67PB0/CCC_NE_PLL0_OUT1")
			(pintype "bidirectional")
			(die_length 5.4505)
		)
		(pad "Y21" smd circle
			(at 7.599 6.799 270)
			(size 0.45 0.45)
			(layers "F.Cu" "F.Mask" "F.Paste")
			(net 347 "/FPGA HSIO/Crosslink_B2.VSYNC")
			(pinfunction "HSIO67NB0")
			(pintype "bidirectional")
			(die_length 5.38301)
		)
		(pad "Y22" smd circle
			(at 8.4 6.799 270)
			(size 0.45 0.45)
			(layers "F.Cu" "F.Mask" "F.Paste")
			(net 48 "+1V8")
			(pinfunction "VDDI0")
			(pintype "passive")
		)
	)
	(footprint "antmicro-footprints:FB_0402_1005Metric"
		(layer "F.Cu")
		(at 208.085 149.74)
		(descr "Ferrite Bead SMD 0402")
		(tags "ferrite bead SMD 0402")
		(property "Reference" "FB11"
			(at -2.195 4.575 90)
			(layer "F.SilkS")
			(effects
				(font
					(size 0.7 0.7)
					(thickness 0.15)
				)
				(justify left bottom)
			)
		)
		(property "Value" "FB_120Z_1.2A_TDK-MPZ_0402"
			(at 0 1.4 0)
			(layer "F.Fab")
			(hide yes)
			(effects
				(font
					(size 0.7 0.7)
					(thickness 0.15)
				)
				(justify left bottom)
			)
		)
		(property "Datasheet" "https://product.tdk.com/en/search/emc/emc/beads/info?part_no=MPZ1005S121CT000"
			(at 0 0 0)
			(layer "F.Fab")
			(hide yes)
			(effects
				(font
					(size 1.27 1.27)
					(thickness 0.15)
				)
			)
		)
		(property "Description" "Ferrite Bead, 0402 [1005 Metric], 120 ohm, 1.2A, MPZ, 0.06 ohm, ± 25%, DC Power line"
			(at 0 0 0)
			(layer "F.Fab")
			(hide yes)
			(effects
				(font
					(size 1.27 1.27)
					(thickness 0.15)
				)
			)
		)
		(property "Author" "Antmicro"
			(at 0 0 0)
			(layer "F.Fab")
			(hide yes)
			(effects
				(font
					(size 1 1)
					(thickness 0.15)
				)
			)
		)
		(property "Current" ""
			(at 0 0 0)
			(layer "F.Fab")
			(hide yes)
			(effects
				(font
					(size 1 1)
					(thickness 0.15)
				)
			)
		)
		(property "License" "Apache-2.0"
			(at 0 0 0)
			(layer "F.Fab")
			(hide yes)
			(effects
				(font
					(size 1 1)
					(thickness 0.15)
				)
			)
		)
		(property "MPN" "MPZ1005S121CT000"
			(at 0 0 0)
			(layer "F.Fab")
			(hide yes)
			(effects
				(font
					(size 1 1)
					(thickness 0.15)
				)
			)
		)
		(property "Manufacturer" "TDK"
			(at 0 0 0)
			(layer "F.Fab")
			(hide yes)
			(effects
				(font
					(size 1 1)
					(thickness 0.15)
				)
			)
		)
		(property "Public" ""
			(at 0 0 0)
			(layer "F.Fab")
			(hide yes)
			(effects
				(font
					(size 1 1)
					(thickness 0.15)
				)
			)
		)
		(property "Val" "120Z/1.2A"
			(at 0 0 0)
			(layer "F.Fab")
			(hide yes)
			(effects
				(font
					(size 1 1)
					(thickness 0.15)
				)
			)
		)
		(sheetname "/MIPI CrossLink/")
		(sheetfile "crosslink.kicad_sch")
		(attr smd)
		(fp_rect
			(start -0.925 -0.47)
			(end 0.925 0.47)
			(stroke
				(width 0.05)
				(type default)
			)
			(fill no)
			(layer "F.CrtYd")
		)
		(fp_rect
			(start -0.5 -0.25)
			(end 0.5 0.25)
			(stroke
				(width 0.15)
				(type solid)
			)
			(fill no)
			(layer "F.Fab")
		)
		(fp_text user "Author: Antmicro"
			(at -0.95 4.169 0)
			(layer "F.Fab")
			(effects
				(font
					(size 0.7 0.7)
					(thickness 0.15)
				)
				(justify left bottom)
			)
		)
		(fp_text user "License: Apache-2.0"
			(at -0.95 5.169 0)
			(layer "F.Fab")
			(effects
				(font
					(size 0.7 0.7)
					(thickness 0.15)
				)
				(justify left bottom)
			)
		)
		(fp_text user "${REFERENCE}"
			(at -0.95 3.168 0)
			(layer "F.Fab")
			(effects
				(font
					(size 0.7 0.7)
					(thickness 0.15)
				)
				(justify left bottom)
			)
		)
		(pad "1" smd roundrect
			(at -0.48 0)
			(size 0.59 0.64)
			(layers "F.Cu" "F.Mask" "F.Paste")
			(roundrect_rratio 0.25)
			(net 211 "/MIPI CrossLink/CL_VCCPLL_DPHY1")
			(pintype "passive")
		)
		(pad "2" smd roundrect
			(at 0.48 0)
			(size 0.59 0.64)
			(layers "F.Cu" "F.Mask" "F.Paste")
			(roundrect_rratio 0.25)
			(net 96 "+1V2")
			(pintype "passive")
		)
	)
	(footprint "antmicro-footprints:C_0402_1005Metric"
		(layer "F.Cu")
		(at 185 140.9675 90)
		(descr "Capacitor SMD 0402")
		(tags "capacitor SMD 0402")
		(property "Reference" "C100"
			(at 0.8375 0.43 90)
			(layer "F.SilkS")
			(effects
				(font
					(size 0.7 0.7)
					(thickness 0.15)
				)
				(justify left bottom)
			)
		)
		(property "Value" "C_22u_0402"
			(at -1.022927 2.155213 90)
			(layer "F.Fab")
			(hide yes)
			(effects
				(font
					(size 0.7 0.7)
					(thickness 0.15)
				)
				(justify left bottom)
			)
		)
		(property "Datasheet" "https://www.murata.com/products/productdetail?partno=GRM158R60J226ME01%23"
			(at 0 0 90)
			(layer "F.Fab")
			(hide yes)
			(effects
				(font
					(size 1.27 1.27)
					(thickness 0.15)
				)
			)
		)
		(property "Description" "SMD Multilayer Ceramic Capacitor, 22 uF, 4 V, 0402 [1005 Metric], X6S"
			(at 0 0 90)
			(layer "F.Fab")
			(hide yes)
			(effects
				(font
					(size 1.27 1.27)
					(thickness 0.15)
				)
			)
		)
		(property "Author" "Antmicro"
			(at 325.9675 -44.0325 0)
			(layer "F.Fab")
			(hide yes)
			(effects
				(font
					(size 1 1)
					(thickness 0.15)
				)
			)
		)
		(property "Dielectric" ""
			(at 325.9675 -44.0325 0)
			(layer "F.Fab")
			(hide yes)
			(effects
				(font
					(size 1 1)
					(thickness 0.15)
				)
			)
		)
		(property "License" "Apache-2.0"
			(at 325.9675 -44.0325 0)
			(layer "F.Fab")
			(hide yes)
			(effects
				(font
					(size 1 1)
					(thickness 0.15)
				)
			)
		)
		(property "MPN" "GRM158R60J226ME01D"
			(at 325.9675 -44.0325 0)
			(layer "F.Fab")
			(hide yes)
			(effects
				(font
					(size 1 1)
					(thickness 0.15)
				)
			)
		)
		(property "Manufacturer" "Murata"
			(at 325.9675 -44.0325 0)
			(layer "F.Fab")
			(hide yes)
			(effects
				(font
					(size 1 1)
					(thickness 0.15)
				)
			)
		)
		(property "Public" ""
			(at 325.9675 -44.0325 0)
			(layer "F.Fab")
			(hide yes)
			(effects
				(font
					(size 1 1)
					(thickness 0.15)
				)
			)
		)
		(property "Val" "22u"
			(at 325.9675 -44.0325 0)
			(layer "F.Fab")
			(hide yes)
			(effects
				(font
					(size 1 1)
					(thickness 0.15)
				)
			)
		)
		(property "Voltage" ""
			(at 325.9675 -44.0325 0)
			(layer "F.Fab")
			(hide yes)
			(effects
				(font
					(size 1 1)
					(thickness 0.15)
				)
			)
		)
		(sheetname "/Supply/")
		(sheetfile "supply.kicad_sch")
		(attr smd)
		(fp_rect
			(start -0.925 -0.47)
			(end 0.925 0.47)
			(stroke
				(width 0.05)
				(type default)
			)
			(fill no)
			(layer "F.CrtYd")
		)
		(fp_line
			(start 0.504 -0.25)
			(end 0.504 0.248)
			(stroke
				(width 0.15)
				(type solid)
			)
			(layer "F.Fab")
		)
		(fp_line
			(start -0.494 -0.25)
			(end 0.504 -0.25)
			(stroke
				(width 0.15)
				(type solid)
			)
			(layer "F.Fab")
		)
		(fp_line
			(start 0.504 0.248)
			(end -0.494 0.248)
			(stroke
				(width 0.15)
				(type solid)
			)
			(layer "F.Fab")
		)
		(fp_line
			(start -0.494 0.248)
			(end -0.494 -0.25)
			(stroke
				(width 0.15)
				(type solid)
			)
			(layer "F.Fab")
		)
		(fp_text user "License: Apache-2.0"
			(at -0.939 5.799 90)
			(layer "F.Fab")
			(effects
				(font
					(size 0.7 0.7)
					(thickness 0.15)
				)
				(justify left bottom)
			)
		)
		(fp_text user "Author: Antmicro"
			(at -0.939 3.399 90)
			(layer "F.Fab")
			(effects
				(font
					(size 0.7 0.7)
					(thickness 0.15)
				)
				(justify left bottom)
			)
		)
		(fp_text user "${REFERENCE}"
			(at -0.939 4.599 90)
			(layer "F.Fab")
			(effects
				(font
					(size 0.7 0.7)
					(thickness 0.15)
				)
				(justify left bottom)
			)
		)
		(pad "1" smd roundrect
			(at -0.48 0 90)
			(size 0.59 0.64)
			(layers "F.Cu" "F.Mask" "F.Paste")
			(roundrect_rratio 0.25)
			(net 417 "GND")
			(pintype "passive")
		)
		(pad "2" smd roundrect
			(at 0.48 0 90)
			(size 0.59 0.64)
			(layers "F.Cu" "F.Mask" "F.Paste")
			(roundrect_rratio 0.25)
			(net 272 "/Supply/SENSE3_P")
			(pintype "passive")
		)
	)
	(footprint "antmicro-footprints:R_0402_1005Metric"
		(layer "F.Cu")
		(at 213.225 139.2 180)
		(descr "Resistor SMD 0402")
		(tags "resistor SMD 0402")
		(property "Reference" "R59"
			(at -1.925 -0.42 180)
			(layer "F.SilkS")
			(effects
				(font
					(size 0.7 0.7)
					(thickness 0.15)
				)
				(justify left bottom)
			)
		)
		(property "Value" "R_1k_0402"
			(at -1.011843 1.772047 180)
			(layer "F.Fab")
			(hide yes)
			(effects
				(font
					(size 0.7 0.7)
					(thickness 0.15)
				)
				(justify left bottom)
			)
		)
		(property "Datasheet" "https://www.bourns.com/docs/product-datasheets/cr.pdf"
			(at 0 0 180)
			(layer "F.Fab")
			(hide yes)
			(effects
				(font
					(size 1.27 1.27)
					(thickness 0.15)
				)
			)
		)
		(property "Description" "SMD Chip Resistor, 1 kohm, ± 1%, 63 mW, 0402 [1005 Metric], Thick Film, General Purpose"
			(at 0 0 180)
			(layer "F.Fab")
			(hide yes)
			(effects
				(font
					(size 1.27 1.27)
					(thickness 0.15)
				)
			)
		)
		(property "Author" "Antmicro"
			(at 426.45 278.4 0)
			(layer "F.Fab")
			(hide yes)
			(effects
				(font
					(size 1 1)
					(thickness 0.15)
				)
			)
		)
		(property "License" "Apache-2.0"
			(at 426.45 278.4 0)
			(layer "F.Fab")
			(hide yes)
			(effects
				(font
					(size 1 1)
					(thickness 0.15)
				)
			)
		)
		(property "MPN" "CR0402-FX-1001GLF"
			(at 426.45 278.4 0)
			(layer "F.Fab")
			(hide yes)
			(effects
				(font
					(size 1 1)
					(thickness 0.15)
				)
			)
		)
		(property "Manufacturer" "Bourns"
			(at 426.45 278.4 0)
			(layer "F.Fab")
			(hide yes)
			(effects
				(font
					(size 1 1)
					(thickness 0.15)
				)
			)
		)
		(property "Public" ""
			(at 426.45 278.4 0)
			(layer "F.Fab")
			(hide yes)
			(effects
				(font
					(size 1 1)
					(thickness 0.15)
				)
			)
		)
		(property "Tolerance" "1%"
			(at 426.45 278.4 0)
			(layer "F.Fab")
			(hide yes)
			(effects
				(font
					(size 1 1)
					(thickness 0.15)
				)
			)
		)
		(property "Val" "1k"
			(at 426.45 278.4 0)
			(layer "F.Fab")
			(hide yes)
			(effects
				(font
					(size 1 1)
					(thickness 0.15)
				)
			)
		)
		(sheetname "/USB/")
		(sheetfile "usb.kicad_sch")
		(attr smd)
		(fp_rect
			(start -0.925 -0.47)
			(end 0.925 0.47)
			(stroke
				(width 0.05)
				(type default)
			)
			(fill no)
			(layer "F.CrtYd")
		)
		(fp_rect
			(start -0.5 -0.25)
			(end 0.5 0.25)
			(stroke
				(width 0.15)
				(type solid)
			)
			(fill no)
			(layer "F.Fab")
		)
		(fp_text user "${REFERENCE}"
			(at -0.95 3.168 180)
			(layer "F.Fab")
			(effects
				(font
					(size 0.7 0.7)
					(thickness 0.15)
				)
				(justify left bottom)
			)
		)
		(fp_text user "License: Apache-2.0"
			(at -0.95 5.169 180)
			(layer "F.Fab")
			(effects
				(font
					(size 0.7 0.7)
					(thickness 0.15)
				)
				(justify left bottom)
			)
		)
		(fp_text user "Author: Antmicro"
			(at -0.95 4.169 180)
			(layer "F.Fab")
			(effects
				(font
					(size 0.7 0.7)
					(thickness 0.15)
				)
				(justify left bottom)
			)
		)
		(pad "1" smd roundrect
			(at -0.48 0 180)
			(size 0.59 0.64)
			(layers "F.Cu" "F.Mask" "F.Paste")
			(roundrect_rratio 0.25)
			(net 221 "VBUS")
			(pintype "passive")
		)
		(pad "2" smd roundrect
			(at 0.48 0 180)
			(size 0.59 0.64)
			(layers "F.Cu" "F.Mask" "F.Paste")
			(roundrect_rratio 0.25)
			(net 90 "+5V")
			(pintype "passive")
		)
	)
	(footprint "antmicro-footprints:FB_0402_1005Metric"
		(layer "F.Cu")
		(at 208.06 152.67)
		(descr "Ferrite Bead SMD 0402")
		(tags "ferrite bead SMD 0402")
		(property "Reference" "FB7"
			(at -1.02 2.45 180)
			(layer "F.SilkS")
			(effects
				(font
					(size 0.7 0.7)
					(thickness 0.15)
				)
				(justify left bottom)
			)
		)
		(property "Value" "FB_120Z_1.2A_TDK-MPZ_0402"
			(at 0 1.4 0)
			(layer "F.Fab")
			(hide yes)
			(effects
				(font
					(size 0.7 0.7)
					(thickness 0.15)
				)
				(justify left bottom)
			)
		)
		(property "Datasheet" "https://product.tdk.com/en/search/emc/emc/beads/info?part_no=MPZ1005S121CT000"
			(at 0 0 0)
			(layer "F.Fab")
			(hide yes)
			(effects
				(font
					(size 1.27 1.27)
					(thickness 0.15)
				)
			)
		)
		(property "Description" "Ferrite Bead, 0402 [1005 Metric], 120 ohm, 1.2A, MPZ, 0.06 ohm, ± 25%, DC Power line"
			(at 0 0 0)
			(layer "F.Fab")
			(hide yes)
			(effects
				(font
					(size 1.27 1.27)
					(thickness 0.15)
				)
			)
		)
		(property "Author" "Antmicro"
			(at 0 0 0)
			(layer "F.Fab")
			(hide yes)
			(effects
				(font
					(size 1 1)
					(thickness 0.15)
				)
			)
		)
		(property "Current" ""
			(at 0 0 0)
			(layer "F.Fab")
			(hide yes)
			(effects
				(font
					(size 1 1)
					(thickness 0.15)
				)
			)
		)
		(property "License" "Apache-2.0"
			(at 0 0 0)
			(layer "F.Fab")
			(hide yes)
			(effects
				(font
					(size 1 1)
					(thickness 0.15)
				)
			)
		)
		(property "MPN" "MPZ1005S121CT000"
			(at 0 0 0)
			(layer "F.Fab")
			(hide yes)
			(effects
				(font
					(size 1 1)
					(thickness 0.15)
				)
			)
		)
		(property "Manufacturer" "TDK"
			(at 0 0 0)
			(layer "F.Fab")
			(hide yes)
			(effects
				(font
					(size 1 1)
					(thickness 0.15)
				)
			)
		)
		(property "Public" ""
			(at 0 0 0)
			(layer "F.Fab")
			(hide yes)
			(effects
				(font
					(size 1 1)
					(thickness 0.15)
				)
			)
		)
		(property "Val" "120Z/1.2A"
			(at 0 0 0)
			(layer "F.Fab")
			(hide yes)
			(effects
				(font
					(size 1 1)
					(thickness 0.15)
				)
			)
		)
		(sheetname "/MIPI CrossLink/")
		(sheetfile "crosslink.kicad_sch")
		(attr smd)
		(fp_rect
			(start -0.925 -0.47)
			(end 0.925 0.47)
			(stroke
				(width 0.05)
				(type default)
			)
			(fill no)
			(layer "F.CrtYd")
		)
		(fp_rect
			(start -0.5 -0.25)
			(end 0.5 0.25)
			(stroke
				(width 0.15)
				(type solid)
			)
			(fill no)
			(layer "F.Fab")
		)
		(fp_text user "License: Apache-2.0"
			(at -0.95 5.169 0)
			(layer "F.Fab")
			(effects
				(font
					(size 0.7 0.7)
					(thickness 0.15)
				)
				(justify left bottom)
			)
		)
		(fp_text user "${REFERENCE}"
			(at -0.95 3.168 0)
			(layer "F.Fab")
			(effects
				(font
					(size 0.7 0.7)
					(thickness 0.15)
				)
				(justify left bottom)
			)
		)
		(fp_text user "Author: Antmicro"
			(at -0.95 4.169 0)
			(layer "F.Fab")
			(effects
				(font
					(size 0.7 0.7)
					(thickness 0.15)
				)
				(justify left bottom)
			)
		)
		(pad "1" smd roundrect
			(at -0.48 0)
			(size 0.59 0.64)
			(layers "F.Cu" "F.Mask" "F.Paste")
			(roundrect_rratio 0.25)
			(net 203 "/MIPI CrossLink/CL_VCCA_DPHY0")
			(pintype "passive")
		)
		(pad "2" smd roundrect
			(at 0.48 0)
			(size 0.59 0.64)
			(layers "F.Cu" "F.Mask" "F.Paste")
			(roundrect_rratio 0.25)
			(net 96 "+1V2")
			(pintype "passive")
		)
	)
	(footprint "antmicro-footprints:XSON-8_1x1.95mm_P0.5mm"
		(layer "F.Cu")
		(at 193.5 120.9)
		(property "Reference" "U20"
			(at -0.36 -1.21 0)
			(layer "F.SilkS")
			(effects
				(font
					(size 0.7 0.7)
					(thickness 0.15)
				)
				(justify left bottom)
			)
		)
		(property "Value" "NTS0102_XSON"
			(at 0 2.2 0)
			(layer "F.Fab")
			(hide yes)
			(effects
				(font
					(size 0.7 0.7)
					(thickness 0.15)
				)
				(justify left bottom)
			)
		)
		(property "Datasheet" "http://www.farnell.com/datasheets/1760723.pdf"
			(at 0 0 0)
			(layer "F.Fab")
			(hide yes)
			(effects
				(font
					(size 1.27 1.27)
					(thickness 0.15)
				)
			)
		)
		(property "Description" "Transceiver, 1.65 V to 3.6 V, XSON-8"
			(at 0 0 0)
			(layer "F.Fab")
			(hide yes)
			(effects
				(font
					(size 1.27 1.27)
					(thickness 0.15)
				)
			)
		)
		(property "Author" "Antmicro"
			(at 0 0 0)
			(layer "F.Fab")
			(hide yes)
			(effects
				(font
					(size 1 1)
					(thickness 0.15)
				)
			)
		)
		(property "License" "Apache-2.0"
			(at 0 0 0)
			(layer "F.Fab")
			(hide yes)
			(effects
				(font
					(size 1 1)
					(thickness 0.15)
				)
			)
		)
		(property "MPN" "NTS0102GT"
			(at 0 0 0)
			(layer "F.Fab")
			(hide yes)
			(effects
				(font
					(size 1 1)
					(thickness 0.15)
				)
			)
		)
		(property "Manufacturer" "NXP"
			(at 0 0 0)
			(layer "F.Fab")
			(hide yes)
			(effects
				(font
					(size 1 1)
					(thickness 0.15)
				)
			)
		)
		(sheetname "/FPGA GPIO/")
		(sheetfile "fpga-gpio.kicad_sch")
		(attr smd)
		(fp_line
			(start -0.5 -1.1)
			(end 0.5 -1.1)
			(stroke
				(width 0.15)
				(type solid)
			)
			(layer "F.SilkS")
		)
		(fp_line
			(start 0.5 1.1)
			(end -0.5 1.1)
			(stroke
				(width 0.15)
				(type solid)
			)
			(layer "F.SilkS")
		)
		(fp_circle
			(center -0.75 -1.1)
			(end -0.701 -1.1)
			(stroke
				(width 0.15)
				(type solid)
			)
			(fill no)
			(layer "F.SilkS")
		)
		(fp_rect
			(start -0.8 -1.2)
			(end 0.8 1.2)
			(stroke
				(width 0.05)
				(type solid)
			)
			(fill no)
			(layer "F.CrtYd")
		)
		(fp_line
			(start -0.5305 -1.001)
			(end 0.5305 -1.001)
			(stroke
				(width 0.15)
				(type solid)
			)
			(layer "F.Fab")
		)
		(fp_line
			(start -0.5305 1)
			(end -0.5305 -1.001)
			(stroke
				(width 0.15)
				(type solid)
			)
			(layer "F.Fab")
		)
		(fp_line
			(start 0.5305 -1.001)
			(end 0.5305 1)
			(stroke
				(width 0.15)
				(type solid)
			)
			(layer "F.Fab")
		)
		(fp_line
			(start 0.5305 1)
			(end -0.5305 1)
			(stroke
				(width 0.15)
				(type solid)
			)
			(layer "F.Fab")
		)
		(fp_text user "Author: Antmicro"
			(at -0.527 7.105 0)
			(layer "F.Fab")
			(effects
				(font
					(size 0.7 0.7)
					(thickness 0.15)
				)
				(justify left bottom)
			)
		)
		(fp_text user "License: Apache-2.0"
			(at -0.527 8.306 0)
			(layer "F.Fab")
			(effects
				(font
					(size 0.7 0.7)
					(thickness 0.15)
				)
				(justify left bottom)
			)
		)
		(fp_text user "${REFERENCE}"
			(at -0.527 5.905 0)
			(layer "F.Fab")
			(effects
				(font
					(size 0.7 0.7)
					(thickness 0.15)
				)
				(justify left bottom)
			)
		)
		(pad "1" smd roundrect
			(at -0.45 -0.75 180)
			(size 0.6 0.3)
			(layers "F.Cu" "F.Mask" "F.Paste")
			(roundrect_rratio 0.25)
			(net 619 "/FPGA GPIO/I^{2}C0.SDA")
			(pinfunction "B_{2}")
			(pintype "bidirectional")
		)
		(pad "2" smd roundrect
			(at -0.45 -0.25 180)
			(size 0.6 0.25)
			(layers "F.Cu" "F.Mask" "F.Paste")
			(roundrect_rratio 0.25)
			(net 417 "GND")
			(pinfunction "GND")
			(pintype "power_in")
		)
		(pad "3" smd roundrect
			(at -0.45 0.25 180)
			(size 0.6 0.25)
			(layers "F.Cu" "F.Mask" "F.Paste")
			(roundrect_rratio 0.25)
			(net 649 "VDD")
			(pinfunction "VCC_{A}")
			(pintype "power_in")
		)
		(pad "4" smd roundrect
			(at -0.45 0.75 180)
			(size 0.6 0.3)
			(layers "F.Cu" "F.Mask" "F.Paste")
			(roundrect_rratio 0.25)
			(net 509 "/FPGA GPIO/SDA0_PF")
			(pinfunction "A_{2}")
			(pintype "bidirectional")
		)
		(pad "5" smd roundrect
			(at 0.45 0.75 180)
			(size 0.6 0.3)
			(layers "F.Cu" "F.Mask" "F.Paste")
			(roundrect_rratio 0.25)
			(net 350 "/FPGA GPIO/SCL0_PF")
			(pinfunction "A_{1}")
			(pintype "bidirectional")
		)
		(pad "6" smd roundrect
			(at 0.45 0.25 180)
			(size 0.6 0.25)
			(layers "F.Cu" "F.Mask" "F.Paste")
			(roundrect_rratio 0.25)
			(net 649 "VDD")
			(pinfunction "OE")
			(pintype "input")
		)
		(pad "7" smd roundrect
			(at 0.45 -0.25 180)
			(size 0.6 0.25)
			(layers "F.Cu" "F.Mask" "F.Paste")
			(roundrect_rratio 0.25)
			(net 50 "+3V3")
			(pinfunction "VCC_{B}")
			(pintype "power_in")
		)
		(pad "8" smd roundrect
			(at 0.45 -0.75 180)
			(size 0.6 0.3)
			(layers "F.Cu" "F.Mask" "F.Paste")
			(roundrect_rratio 0.25)
			(net 623 "/FPGA GPIO/I^{2}C0.SCL")
			(pinfunction "B_{1}")
			(pintype "bidirectional")
		)
	)
	(footprint "antmicro-footprints:TQFN-30-1EP_2.5x4.5mm_P0.4mm_Layout5x10"
		(layer "F.Cu")
		(at 194.39 147.15 -90)
		(descr "2.5mm x 4.5mm ")
		(property "Reference" "U15"
			(at -0.11 -3.54 90)
			(layer "F.SilkS")
			(effects
				(font
					(size 0.7 0.7)
					(thickness 0.15)
				)
				(justify right bottom)
			)
		)
		(property "Value" "PI3HDX511DZLE"
			(at 0 3.7 90)
			(layer "F.Fab")
			(hide yes)
			(effects
				(font
					(size 0.7 0.7)
					(thickness 0.15)
				)
				(justify right bottom)
			)
		)
		(property "Datasheet" "https://eu.mouser.com/datasheet/2/115/diodes_inc_diod-s-a0004145302-1-1749206.pdf"
			(at 0 0 90)
			(layer "F.Fab")
			(hide yes)
			(effects
				(font
					(size 1.27 1.27)
					(thickness 0.15)
				)
			)
		)
		(property "Description" "Video ICs Active HDMI TQFN-30"
			(at 0 0 90)
			(layer "F.Fab")
			(hide yes)
			(effects
				(font
					(size 1.27 1.27)
					(thickness 0.15)
				)
			)
		)
		(property "Author" "Antmicro"
			(at 47.24 341.54 0)
			(layer "F.Fab")
			(hide yes)
			(effects
				(font
					(size 1 1)
					(thickness 0.15)
				)
			)
		)
		(property "License" "Apache-2.0"
			(at 47.24 341.54 0)
			(layer "F.Fab")
			(hide yes)
			(effects
				(font
					(size 1 1)
					(thickness 0.15)
				)
			)
		)
		(property "MPN" "PI3HDX511DZLE"
			(at 47.24 341.54 0)
			(layer "F.Fab")
			(hide yes)
			(effects
				(font
					(size 1 1)
					(thickness 0.15)
				)
			)
		)
		(property "Manufacturer" "Diodes Incorporated"
			(at 47.24 341.54 0)
			(layer "F.Fab")
			(hide yes)
			(effects
				(font
					(size 1 1)
					(thickness 0.15)
				)
			)
		)
		(sheetname "/HDMI/")
		(sheetfile "hdmi.kicad_sch")
		(attr smd)
		(fp_line
			(start 1.033 2.27)
			(end 1.267 2.27)
			(stroke
				(width 0.1)
				(type default)
			)
			(layer "F.SilkS")
		)
		(fp_line
			(start 1.267 2.27)
			(end 1.267 2.016)
			(stroke
				(width 0.1)
				(type default)
			)
			(layer "F.SilkS")
		)
		(fp_line
			(start -1.27 2.269)
			(end -1.016 2.269)
			(stroke
				(width 0.1)
				(type default)
			)
			(layer "F.SilkS")
		)
		(fp_line
			(start -1.27 2.051)
			(end -1.27 2.269)
			(stroke
				(width 0.1)
				(type default)
			)
			(layer "F.SilkS")
		)
		(fp_line
			(start 1.033 -2.27)
			(end 1.267 -2.27)
			(stroke
				(width 0.1)
				(type default)
			)
			(layer "F.SilkS")
		)
		(fp_line
			(start 1.267 -2.27)
			(end 1.267 -2.016)
			(stroke
				(width 0.1)
				(type default)
			)
			(layer "F.SilkS")
		)
		(fp_line
			(start -1.27 -2.274)
			(end -1.27 -2.02)
			(stroke
				(width 0.1)
				(type default)
			)
			(layer "F.SilkS")
		)
		(fp_line
			(start -1.036 -2.274)
			(end -1.27 -2.274)
			(stroke
				(width 0.1)
				(type default)
			)
			(layer "F.SilkS")
		)
		(fp_circle
			(center -1.45 -2.1)
			(end -1.4 -2.1)
			(stroke
				(width 0.15)
				(type solid)
			)
			(fill yes)
			(layer "F.SilkS")
		)
		(fp_rect
			(start -1.6 -2.6)
			(end 1.6 2.6)
			(stroke
				(width 0.05)
				(type solid)
			)
			(fill no)
			(layer "F.CrtYd")
		)
		(fp_text user "${REFERENCE}"
			(at -2.2 7.518 270)
			(layer "F.Fab")
			(effects
				(font
					(size 0.7 0.7)
					(thickness 0.15)
				)
				(justify left bottom)
			)
		)
		(fp_text user "License: Apache-2.0"
			(at -2.2 6.318 270)
			(layer "F.Fab")
			(effects
				(font
					(size 0.7 0.7)
					(thickness 0.15)
				)
				(justify left bottom)
			)
		)
		(fp_text user "Author: Antmicro"
			(at -2.2 8.718 270)
			(layer "F.Fab")
			(effects
				(font
					(size 0.7 0.7)
					(thickness 0.15)
				)
				(justify left bottom)
			)
		)
		(pad "1" smd roundrect
			(at -1.25 -1.8 270)
			(size 0.6 0.2)
			(layers "F.Cu" "F.Mask" "F.Paste")
			(roundrect_rratio 0.06)
			(chamfer_ratio 0.5)
			(chamfer top_right)
			(net 554 "Net-(U15-CEXT)")
			(pinfunction "CEXT")
			(pintype "power_in")
		)
		(pad "2" smd roundrect
			(at -1.25 -1.4 270)
			(size 0.6 0.2)
			(layers "F.Cu" "F.Mask" "F.Paste")
			(roundrect_rratio 0.4)
			(chamfer_ratio 0)
			(chamfer top_left bottom_left)
			(net 549 "/HDMI/PI3HDX_C_TX2_N")
			(pinfunction "IN_D2_N")
			(pintype "input")
		)
		(pad "3" smd roundrect
			(at -1.25 -1 270)
			(size 0.6 0.2)
			(layers "F.Cu" "F.Mask" "F.Paste")
			(roundrect_rratio 0.4)
			(chamfer_ratio 0)
			(chamfer top_left bottom_left)
			(net 57 "/HDMI/PI3HDX_C_TX2_P")
			(pinfunction "IN_D2_P")
			(pintype "input")
		)
		(pad "4" smd roundrect
			(at -1.25 -0.6 270)
			(size 0.6 0.2)
			(layers "F.Cu" "F.Mask" "F.Paste")
			(roundrect_rratio 0.4)
			(chamfer_ratio 0)
			(chamfer top_left bottom_left)
			(net 550 "/HDMI/PI3HDX_C_TX1_N")
			(pinfunction "IN_D1_N")
			(pintype "input")
		)
		(pad "5" smd roundrect
			(at -1.25 -0.2 270)
			(size 0.6 0.2)
			(layers "F.Cu" "F.Mask" "F.Paste")
			(roundrect_rratio 0.4)
			(chamfer_ratio 0)
			(chamfer top_left bottom_left)
			(net 546 "/HDMI/PI3HDX_C_TX1_P")
			(pinfunction "IN_D1_P")
			(pintype "input")
		)
		(pad "6" smd roundrect
			(at -1.25 0.2 270)
			(size 0.6 0.2)
			(layers "F.Cu" "F.Mask" "F.Paste")
			(roundrect_rratio 0.4)
			(chamfer_ratio 0)
			(chamfer top_left bottom_left)
			(net 551 "/HDMI/PI3HDX_C_TX0_N")
			(pinfunction "IN_D0_N")
			(pintype "input")
		)
		(pad "7" smd roundrect
			(at -1.25 0.6 270)
			(size 0.6 0.2)
			(layers "F.Cu" "F.Mask" "F.Paste")
			(roundrect_rratio 0.4)
			(chamfer_ratio 0)
			(chamfer top_left bottom_left)
			(net 547 "/HDMI/PI3HDX_C_TX0_P")
			(pinfunction "IN_D0_P")
			(pintype "input")
		)
		(pad "8" smd roundrect
			(at -1.25 1 270)
			(size 0.6 0.2)
			(layers "F.Cu" "F.Mask" "F.Paste")
			(roundrect_rratio 0.4)
			(chamfer_ratio 0)
			(chamfer top_left bottom_left)
			(net 552 "/HDMI/PI3HDX_C_CLK_N")
			(pinfunction "IN_CLK_N")
			(pintype "input")
		)
		(pad "9" smd roundrect
			(at -1.25 1.4 270)
			(size 0.6 0.2)
			(layers "F.Cu" "F.Mask" "F.Paste")
			(roundrect_rratio 0.4)
			(chamfer_ratio 0)
			(chamfer top_left bottom_left)
			(net 548 "/HDMI/PI3HDX_C_CLK_P")
			(pinfunction "IN_CLK_P")
			(pintype "input")
		)
		(pad "10" smd roundrect
			(at -1.25 1.8 270)
			(size 0.6 0.2)
			(layers "F.Cu" "F.Mask" "F.Paste")
			(roundrect_rratio 0.06)
			(chamfer_ratio 0.5)
			(chamfer bottom_right)
			(net 505 "PI3HDX511F_HOTPLUG")
			(pinfunction "HPD_SRC")
			(pintype "output")
		)
		(pad "11" smd roundrect
			(at -0.8 2.25)
			(size 0.6 0.2)
			(layers "F.Cu" "F.Mask" "F.Paste")
			(roundrect_rratio 0.06)
			(chamfer_ratio 0.5)
			(chamfer top_right)
			(net 622 "/FPGA GPIO/PI3HDX511F.SDA")
			(pinfunction "SDA_SRC")
			(pintype "bidirectional")
		)
		(pad "12" smd roundrect
			(at -0.4 2.25)
			(size 0.6 0.2)
			(layers "F.Cu" "F.Mask" "F.Paste")
			(roundrect_rratio 0.4)
			(chamfer_ratio 0)
			(chamfer top_left bottom_left)
			(net 283 "/FPGA GPIO/PI3HDX511F.SCL")
			(pinfunction "SCL_SRC")
			(pintype "bidirectional")
		)
		(pad "13" smd roundrect
			(at 0 2.25)
			(size 0.6 0.2)
			(layers "F.Cu" "F.Mask" "F.Paste")
			(roundrect_rratio 0.4)
			(chamfer_ratio 0)
			(chamfer top_left bottom_left)
			(net 417 "GND")
			(pinfunction "GND")
			(pintype "passive")
		)
		(pad "14" smd roundrect
			(at 0.4 2.25)
			(size 0.6 0.2)
			(layers "F.Cu" "F.Mask" "F.Paste")
			(roundrect_rratio 0.4)
			(chamfer_ratio 0)
			(chamfer top_left bottom_left)
			(net 555 "Net-(U15-OC_S0)")
			(pinfunction "OC_S0")
			(pintype "input")
		)
		(pad "15" smd roundrect
			(at 0.8 2.25)
			(size 0.6 0.2)
			(layers "F.Cu" "F.Mask" "F.Paste")
			(roundrect_rratio 0.4)
			(chamfer_ratio 0)
			(chamfer top_left bottom_left)
			(net 557 "Net-(U15-EQ_S0)")
			(pinfunction "EQ_S0")
			(pintype "input")
		)
		(pad "16" smd roundrect
			(at 1.25 1.8 270)
			(size 0.6 0.2)
			(layers "F.Cu" "F.Mask" "F.Paste")
			(roundrect_rratio 0.06)
			(chamfer_ratio 0.5)
			(chamfer bottom_left)
			(net 163 "/Bottom Connector/HDMI0.CLK_P")
			(pinfunction "OUT_CLK_P")
			(pintype "output")
		)
		(pad "17" smd roundrect
			(at 1.25 1.4 270)
			(size 0.6 0.2)
			(layers "F.Cu" "F.Mask" "F.Paste")
			(roundrect_rratio 0.4)
			(chamfer_ratio 0)
			(chamfer top_right bottom_right)
			(net 196 "/Bottom Connector/HDMI0.CLK_N")
			(pinfunction "OUT_CLK_N")
			(pintype "output")
		)
		(pad "18" smd roundrect
			(at 1.25 1 270)
			(size 0.6 0.2)
			(layers "F.Cu" "F.Mask" "F.Paste")
			(roundrect_rratio 0.4)
			(chamfer_ratio 0)
			(chamfer top_right bottom_right)
			(net 159 "/Bottom Connector/HDMI0.TX0_P")
			(pinfunction "OUT_D0_P")
			(pintype "output")
		)
		(pad "19" smd roundrect
			(at 1.25 0.6 270)
			(size 0.6 0.2)
			(layers "F.Cu" "F.Mask" "F.Paste")
			(roundrect_rratio 0.4)
			(chamfer_ratio 0)
			(chamfer top_right bottom_right)
			(net 161 "/Bottom Connector/HDMI0.TX0_N")
			(pinfunction "OUT_D0_N")
			(pintype "output")
		)
		(pad "20" smd roundrect
			(at 1.25 0.2 270)
			(size 0.6 0.2)
			(layers "F.Cu" "F.Mask" "F.Paste")
			(roundrect_rratio 0.4)
			(chamfer_ratio 0)
			(chamfer top_right bottom_right)
			(net 553 "/HDMI/HDMI_3V3")
			(pinfunction "VDD")
			(pintype "power_in")
		)
		(pad "21" smd roundrect
			(at 1.25 -0.2 270)
			(size 0.6 0.2)
			(layers "F.Cu" "F.Mask" "F.Paste")
			(roundrect_rratio 0.4)
			(chamfer_ratio 0)
			(chamfer top_right bottom_right)
			(net 147 "/Bottom Connector/HDMI0.TX1_P")
			(pinfunction "OUT_D1_P")
			(pintype "output")
		)
		(pad "22" smd roundrect
			(at 1.25 -0.6 270)
			(size 0.6 0.2)
			(layers "F.Cu" "F.Mask" "F.Paste")
			(roundrect_rratio 0.4)
			(chamfer_ratio 0)
			(chamfer top_right bottom_right)
			(net 157 "/Bottom Connector/HDMI0.TX1_N")
			(pinfunction "OUT_D1_N")
			(pintype "output")
		)
		(pad "23" smd roundrect
			(at 1.25 -1 270)
			(size 0.6 0.2)
			(layers "F.Cu" "F.Mask" "F.Paste")
			(roundrect_rratio 0.4)
			(chamfer_ratio 0)
			(chamfer top_right bottom_right)
			(net 143 "/Bottom Connector/HDMI0.TX2_P")
			(pinfunction "OUT_D2_P")
			(pintype "output")
		)
		(pad "24" smd roundrect
			(at 1.25 -1.4 270)
			(size 0.6 0.2)
			(layers "F.Cu" "F.Mask" "F.Paste")
			(roundrect_rratio 0.4)
			(chamfer_ratio 0)
			(chamfer top_right bottom_right)
			(net 144 "/Bottom Connector/HDMI0.TX2_N")
			(pinfunction "OUT_D2_N")
			(pintype "output")
		)
		(pad "25" smd roundrect
			(at 1.25 -1.8 270)
			(size 0.6 0.2)
			(layers "F.Cu" "F.Mask" "F.Paste")
			(roundrect_rratio 0.06)
			(chamfer_ratio 0.5)
			(chamfer top_left)
			(net 218 "/Bottom Connector/HDMI0.SCL")
			(pinfunction "SCL_SINK")
			(pintype "bidirectional")
		)
		(pad "26" smd roundrect
			(at 0.8 -2.25)
			(size 0.6 0.2)
			(layers "F.Cu" "F.Mask" "F.Paste")
			(roundrect_rratio 0.06)
			(chamfer_ratio 0.5)
			(chamfer bottom_left)
			(net 206 "/Bottom Connector/HDMI0.SDA")
			(pinfunction "SDA_SINK")
			(pintype "bidirectional")
		)
		(pad "27" smd roundrect
			(at 0.4 -2.25)
			(size 0.6 0.2)
			(layers "F.Cu" "F.Mask" "F.Paste")
			(roundrect_rratio 0.4)
			(chamfer_ratio 0)
			(chamfer top_right bottom_right)
			(net 97 "HDMI0_HOTPLUG")
			(pinfunction "HPD_SINK")
			(pintype "input")
		)
		(pad "28" smd roundrect
			(at 0 -2.25)
			(size 0.6 0.2)
			(layers "F.Cu" "F.Mask" "F.Paste")
			(roundrect_rratio 0.4)
			(chamfer_ratio 0)
			(chamfer top_right bottom_right)
			(net 417 "GND")
			(pinfunction "GND")
			(pintype "power_in")
		)
		(pad "29" smd roundrect
			(at -0.4 -2.25)
			(size 0.6 0.2)
			(layers "F.Cu" "F.Mask" "F.Paste")
			(roundrect_rratio 0.4)
			(chamfer_ratio 0)
			(chamfer top_right bottom_right)
			(net 556 "Net-(U15-OEB)")
			(pinfunction "OEB")
			(pintype "input")
		)
		(pad "30" smd roundrect
			(at -0.8 -2.25)
			(size 0.6 0.2)
			(layers "F.Cu" "F.Mask" "F.Paste")
			(roundrect_rratio 0.06)
			(chamfer_ratio 0.5)
			(chamfer top_left)
			(net 553 "/HDMI/HDMI_3V3")
			(pinfunction "VDD")
			(pintype "passive")
		)
		(pad "31" smd roundrect
			(at 0 0)
			(size 3.2 1.2)
			(layers "F.Cu" "F.Mask" "F.Paste")
			(roundrect_rratio 0)
			(chamfer_ratio 0.3)
			(chamfer top_right)
			(net 417 "GND")
			(pinfunction "EP")
			(pintype "power_in")
		)
	)
	(footprint "antmicro-footprints:TP_SMD_0.75mm"
		(layer "F.Cu")
		(at 222.364999 149.23)
		(property "Reference" "TP13"
			(at 12.505001 6.11 90)
			(layer "F.SilkS")
			(hide yes)
			(effects
				(font
					(size 0.7 0.7)
					(thickness 0.15)
				)
				(justify left bottom)
			)
		)
		(property "Value" "TP_0.75mm_SMD"
			(at 0 1.2 0)
			(layer "F.Fab")
			(hide yes)
			(effects
				(font
					(size 0.7 0.7)
					(thickness 0.15)
				)
				(justify left bottom)
			)
		)
		(property "Description" "SMT test point"
			(at 0 0 0)
			(layer "F.Fab")
			(hide yes)
			(effects
				(font
					(size 1.27 1.27)
					(thickness 0.15)
				)
			)
		)
		(property "Author" "Antmicro"
			(at 0 0 0)
			(layer "F.Fab")
			(hide yes)
			(effects
				(font
					(size 1 1)
					(thickness 0.15)
				)
			)
		)
		(property "License" "Apache-2.0"
			(at 0 0 0)
			(layer "F.Fab")
			(hide yes)
			(effects
				(font
					(size 1 1)
					(thickness 0.15)
				)
			)
		)
		(property "MPN" ""
			(at 0 0 0)
			(layer "F.Fab")
			(hide yes)
			(effects
				(font
					(size 1 1)
					(thickness 0.15)
				)
			)
		)
		(property "Manufacturer" ""
			(at 0 0 0)
			(layer "F.Fab")
			(hide yes)
			(effects
				(font
					(size 1 1)
					(thickness 0.15)
				)
			)
		)
		(property "Public" "False"
			(at 0 0 0)
			(layer "F.Fab")
			(hide yes)
			(effects
				(font
					(size 1 1)
					(thickness 0.15)
				)
			)
		)
		(sheetname "/WiFi_Bluetooth/")
		(sheetfile "wifi_bt.kicad_sch")
		(attr exclude_from_pos_files exclude_from_bom)
		(fp_circle
			(center 0 0)
			(end 0.475 0)
			(stroke
				(width 0.05)
				(type default)
			)
			(fill no)
			(layer "F.CrtYd")
		)
		(fp_text user "Author: Antmicro"
			(at -0.4 3.901 0)
			(layer "F.Fab")
			(effects
				(font
					(size 0.7 0.7)
					(thickness 0.15)
				)
				(justify left bottom)
			)
		)
		(fp_text user "License: Apache-2.0"
			(at -0.4 5.101 0)
			(layer "F.Fab")
			(effects
				(font
					(size 0.7 0.7)
					(thickness 0.15)
				)
				(justify left bottom)
			)
		)
		(fp_text user "${REFERENCE}"
			(at -0.4 2.7 0)
			(layer "F.Fab")
			(effects
				(font
					(size 0.7 0.7)
					(thickness 0.15)
				)
				(justify left bottom)
			)
		)
		(pad "1" smd circle
			(at 0 0)
			(size 0.75 0.75)
			(layers "F.Cu" "F.Mask")
			(net 507 "Net-(U26A-BT_PCM_IN)")
			(pinfunction "1")
			(pintype "passive")
		)
	)
	(footprint "antmicro-footprints:R_0402_1005Metric"
		(layer "F.Cu")
		(at 203.35 120.75 90)
		(descr "Resistor SMD 0402")
		(tags "resistor SMD 0402")
		(property "Reference" "R17"
			(at -1.85 4 90)
			(layer "F.SilkS")
			(effects
				(font
					(size 0.7 0.7)
					(thickness 0.15)
				)
				(justify left bottom)
			)
		)
		(property "Value" "R_0R_0402"
			(at -1.011843 1.772047 90)
			(layer "F.Fab")
			(hide yes)
			(effects
				(font
					(size 0.7 0.7)
					(thickness 0.15)
				)
				(justify left bottom)
			)
		)
		(property "Datasheet" "https://industrial.panasonic.com/cdbs/www-data/pdf/RDA0000/AOA0000C301.pdf"
			(at 0 0 90)
			(layer "F.Fab")
			(hide yes)
			(effects
				(font
					(size 1.27 1.27)
					(thickness 0.15)
				)
			)
		)
		(property "Description" "SMD Chip Resistor, Jumper, 0 ohm, 100 mW, 0402 [1005 Metric], Thick Film, General Purpose"
			(at 0 0 90)
			(layer "F.Fab")
			(hide yes)
			(effects
				(font
					(size 1.27 1.27)
					(thickness 0.15)
				)
			)
		)
		(property "Author" "Antmicro"
			(at 324.1 -82.6 0)
			(layer "F.Fab")
			(hide yes)
			(effects
				(font
					(size 1 1)
					(thickness 0.15)
				)
			)
		)
		(property "Current" "1A"
			(at 324.1 -82.6 0)
			(layer "F.Fab")
			(hide yes)
			(effects
				(font
					(size 1 1)
					(thickness 0.15)
				)
			)
		)
		(property "License" "Apache-2.0"
			(at 324.1 -82.6 0)
			(layer "F.Fab")
			(hide yes)
			(effects
				(font
					(size 1 1)
					(thickness 0.15)
				)
			)
		)
		(property "MPN" "ERJ2GE0R00X"
			(at 324.1 -82.6 0)
			(layer "F.Fab")
			(hide yes)
			(effects
				(font
					(size 1 1)
					(thickness 0.15)
				)
			)
		)
		(property "Manufacturer" "Panasonic"
			(at 324.1 -82.6 0)
			(layer "F.Fab")
			(hide yes)
			(effects
				(font
					(size 1 1)
					(thickness 0.15)
				)
			)
		)
		(property "Public" ""
			(at 324.1 -82.6 0)
			(layer "F.Fab")
			(hide yes)
			(effects
				(font
					(size 1 1)
					(thickness 0.15)
				)
			)
		)
		(property "Tolerance" "~"
			(at 324.1 -82.6 0)
			(layer "F.Fab")
			(hide yes)
			(effects
				(font
					(size 1 1)
					(thickness 0.15)
				)
			)
		)
		(property "Val" "0R"
			(at 324.1 -82.6 0)
			(layer "F.Fab")
			(hide yes)
			(effects
				(font
					(size 1 1)
					(thickness 0.15)
				)
			)
		)
		(sheetname "/FPGA MSSIO/")
		(sheetfile "fpga-mssio.kicad_sch")
		(attr smd)
		(fp_rect
			(start -0.925 -0.47)
			(end 0.925 0.47)
			(stroke
				(width 0.05)
				(type default)
			)
			(fill no)
			(layer "F.CrtYd")
		)
		(fp_rect
			(start -0.5 -0.25)
			(end 0.5 0.25)
			(stroke
				(width 0.15)
				(type solid)
			)
			(fill no)
			(layer "F.Fab")
		)
		(fp_text user "Author: Antmicro"
			(at -0.95 4.169 90)
			(layer "F.Fab")
			(effects
				(font
					(size 0.7 0.7)
					(thickness 0.15)
				)
				(justify left bottom)
			)
		)
		(fp_text user "License: Apache-2.0"
			(at -0.95 5.169 90)
			(layer "F.Fab")
			(effects
				(font
					(size 0.7 0.7)
					(thickness 0.15)
				)
				(justify left bottom)
			)
		)
		(fp_text user "${REFERENCE}"
			(at -0.95 3.168 90)
			(layer "F.Fab")
			(effects
				(font
					(size 0.7 0.7)
					(thickness 0.15)
				)
				(justify left bottom)
			)
		)
		(pad "1" smd roundrect
			(at -0.48 0 90)
			(size 0.59 0.64)
			(layers "F.Cu" "F.Mask" "F.Paste")
			(roundrect_rratio 0.25)
			(net 92 "/FPGA MSSIO/SUPPLY.SCL")
			(pintype "passive")
		)
		(pad "2" smd roundrect
			(at 0.48 0 90)
			(size 0.59 0.64)
			(layers "F.Cu" "F.Mask" "F.Paste")
			(roundrect_rratio 0.25)
			(net 94 "/FPGA MSSIO/ID.SCL")
			(pintype "passive")
		)
	)
	(footprint "antmicro-footprints:FB_0402_1005Metric"
		(layer "F.Cu")
		(at 208.085 148.75)
		(descr "Ferrite Bead SMD 0402")
		(tags "ferrite bead SMD 0402")
		(property "Reference" "FB8"
			(at -3.185 5.565 90)
			(layer "F.SilkS")
			(effects
				(font
					(size 0.7 0.7)
					(thickness 0.15)
				)
				(justify left bottom)
			)
		)
		(property "Value" "FB_120Z_1.2A_TDK-MPZ_0402"
			(at 0 1.4 0)
			(layer "F.Fab")
			(hide yes)
			(effects
				(font
					(size 0.7 0.7)
					(thickness 0.15)
				)
				(justify left bottom)
			)
		)
		(property "Datasheet" "https://product.tdk.com/en/search/emc/emc/beads/info?part_no=MPZ1005S121CT000"
			(at 0 0 0)
			(layer "F.Fab")
			(hide yes)
			(effects
				(font
					(size 1.27 1.27)
					(thickness 0.15)
				)
			)
		)
		(property "Description" "Ferrite Bead, 0402 [1005 Metric], 120 ohm, 1.2A, MPZ, 0.06 ohm, ± 25%, DC Power line"
			(at 0 0 0)
			(layer "F.Fab")
			(hide yes)
			(effects
				(font
					(size 1.27 1.27)
					(thickness 0.15)
				)
			)
		)
		(property "Author" "Antmicro"
			(at 0 0 0)
			(layer "F.Fab")
			(hide yes)
			(effects
				(font
					(size 1 1)
					(thickness 0.15)
				)
			)
		)
		(property "Current" ""
			(at 0 0 0)
			(layer "F.Fab")
			(hide yes)
			(effects
				(font
					(size 1 1)
					(thickness 0.15)
				)
			)
		)
		(property "License" "Apache-2.0"
			(at 0 0 0)
			(layer "F.Fab")
			(hide yes)
			(effects
				(font
					(size 1 1)
					(thickness 0.15)
				)
			)
		)
		(property "MPN" "MPZ1005S121CT000"
			(at 0 0 0)
			(layer "F.Fab")
			(hide yes)
			(effects
				(font
					(size 1 1)
					(thickness 0.15)
				)
			)
		)
		(property "Manufacturer" "TDK"
			(at 0 0 0)
			(layer "F.Fab")
			(hide yes)
			(effects
				(font
					(size 1 1)
					(thickness 0.15)
				)
			)
		)
		(property "Public" ""
			(at 0 0 0)
			(layer "F.Fab")
			(hide yes)
			(effects
				(font
					(size 1 1)
					(thickness 0.15)
				)
			)
		)
		(property "Val" "120Z/1.2A"
			(at 0 0 0)
			(layer "F.Fab")
			(hide yes)
			(effects
				(font
					(size 1 1)
					(thickness 0.15)
				)
			)
		)
		(sheetname "/MIPI CrossLink/")
		(sheetfile "crosslink.kicad_sch")
		(attr smd)
		(fp_rect
			(start -0.925 -0.47)
			(end 0.925 0.47)
			(stroke
				(width 0.05)
				(type default)
			)
			(fill no)
			(layer "F.CrtYd")
		)
		(fp_rect
			(start -0.5 -0.25)
			(end 0.5 0.25)
			(stroke
				(width 0.15)
				(type solid)
			)
			(fill no)
			(layer "F.Fab")
		)
		(fp_text user "${REFERENCE}"
			(at -0.95 3.168 0)
			(layer "F.Fab")
			(effects
				(font
					(size 0.7 0.7)
					(thickness 0.15)
				)
				(justify left bottom)
			)
		)
		(fp_text user "Author: Antmicro"
			(at -0.95 4.169 0)
			(layer "F.Fab")
			(effects
				(font
					(size 0.7 0.7)
					(thickness 0.15)
				)
				(justify left bottom)
			)
		)
		(fp_text user "License: Apache-2.0"
			(at -0.95 5.169 0)
			(layer "F.Fab")
			(effects
				(font
					(size 0.7 0.7)
					(thickness 0.15)
				)
				(justify left bottom)
			)
		)
		(pad "1" smd roundrect
			(at -0.48 0)
			(size 0.59 0.64)
			(layers "F.Cu" "F.Mask" "F.Paste")
			(roundrect_rratio 0.25)
			(net 205 "/MIPI CrossLink/CL_VCCA_DPHY1")
			(pintype "passive")
		)
		(pad "2" smd roundrect
			(at 0.48 0)
			(size 0.59 0.64)
			(layers "F.Cu" "F.Mask" "F.Paste")
			(roundrect_rratio 0.25)
			(net 96 "+1V2")
			(pintype "passive")
		)
	)
	(footprint "antmicro-footprints:C_0402_1005Metric"
		(layer "F.Cu")
		(at 181.75 138.3175 -90)
		(descr "Capacitor SMD 0402")
		(tags "capacitor SMD 0402")
		(property "Reference" "C101"
			(at -1.2975 -6.39 180)
			(layer "F.SilkS")
			(effects
				(font
					(size 0.7 0.7)
					(thickness 0.15)
				)
				(justify right bottom)
			)
		)
		(property "Value" "C_10u_10V_0402"
			(at -1.022927 2.155213 90)
			(layer "F.Fab")
			(hide yes)
			(effects
				(font
					(size 0.7 0.7)
					(thickness 0.15)
				)
				(justify right bottom)
			)
		)
		(property "Datasheet" "https://www.murata.com/products/productdetail?partno=GRM155R61A106ME11%23"
			(at 0 0 270)
			(layer "F.Fab")
			(hide yes)
			(effects
				(font
					(size 1.27 1.27)
					(thickness 0.15)
				)
			)
		)
		(property "Description" "Multilayer Ceramic Capacitors MLCC - SMD/SMT 10 uF 10 VDC 20% 0402 X5R"
			(at 0 0 270)
			(layer "F.Fab")
			(hide yes)
			(effects
				(font
					(size 1.27 1.27)
					(thickness 0.15)
				)
			)
		)
		(property "Author" "Antmicro"
			(at 43.4325 320.0675 0)
			(layer "F.Fab")
			(hide yes)
			(effects
				(font
					(size 1 1)
					(thickness 0.15)
				)
			)
		)
		(property "Dielectric" "X5R"
			(at 43.4325 320.0675 0)
			(layer "F.Fab")
			(hide yes)
			(effects
				(font
					(size 1 1)
					(thickness 0.15)
				)
			)
		)
		(property "License" "Apache-2.0"
			(at 43.4325 320.0675 0)
			(layer "F.Fab")
			(hide yes)
			(effects
				(font
					(size 1 1)
					(thickness 0.15)
				)
			)
		)
		(property "MPN" "GRM155R61A106ME11D"
			(at 43.4325 320.0675 0)
			(layer "F.Fab")
			(hide yes)
			(effects
				(font
					(size 1 1)
					(thickness 0.15)
				)
			)
		)
		(property "Manufacturer" "Murata"
			(at 43.4325 320.0675 0)
			(layer "F.Fab")
			(hide yes)
			(effects
				(font
					(size 1 1)
					(thickness 0.15)
				)
			)
		)
		(property "Public" ""
			(at 43.4325 320.0675 0)
			(layer "F.Fab")
			(hide yes)
			(effects
				(font
					(size 1 1)
					(thickness 0.15)
				)
			)
		)
		(property "Val" "10u"
			(at 43.4325 320.0675 0)
			(layer "F.Fab")
			(hide yes)
			(effects
				(font
					(size 1 1)
					(thickness 0.15)
				)
			)
		)
		(property "Voltage" "10V"
			(at 43.4325 320.0675 0)
			(layer "F.Fab")
			(hide yes)
			(effects
				(font
					(size 1 1)
					(thickness 0.15)
				)
			)
		)
		(sheetname "/Supply/")
		(sheetfile "supply.kicad_sch")
		(attr smd)
		(fp_rect
			(start -0.925 -0.47)
			(end 0.925 0.47)
			(stroke
				(width 0.05)
				(type default)
			)
			(fill no)
			(layer "F.CrtYd")
		)
		(fp_line
			(start -0.494 0.248)
			(end -0.494 -0.25)
			(stroke
				(width 0.15)
				(type solid)
			)
			(layer "F.Fab")
		)
		(fp_line
			(start 0.504 0.248)
			(end -0.494 0.248)
			(stroke
				(width 0.15)
				(type solid)
			)
			(layer "F.Fab")
		)
		(fp_line
			(start -0.494 -0.25)
			(end 0.504 -0.25)
			(stroke
				(width 0.15)
				(type solid)
			)
			(layer "F.Fab")
		)
		(fp_line
			(start 0.504 -0.25)
			(end 0.504 0.248)
			(stroke
				(width 0.15)
				(type solid)
			)
			(layer "F.Fab")
		)
		(fp_text user "${REFERENCE}"
			(at -0.939 4.599 270)
			(layer "F.Fab")
			(effects
				(font
					(size 0.7 0.7)
					(thickness 0.15)
				)
				(justify left bottom)
			)
		)
		(fp_text user "License: Apache-2.0"
			(at -0.939 5.799 270)
			(layer "F.Fab")
			(effects
				(font
					(size 0.7 0.7)
					(thickness 0.15)
				)
				(justify left bottom)
			)
		)
		(fp_text user "Author: Antmicro"
			(at -0.939 3.399 270)
			(layer "F.Fab")
			(effects
				(font
					(size 0.7 0.7)
					(thickness 0.15)
				)
				(justify left bottom)
			)
		)
		(pad "1" smd roundrect
			(at -0.48 0 270)
			(size 0.59 0.64)
			(layers "F.Cu" "F.Mask" "F.Paste")
			(roundrect_rratio 0.25)
			(net 417 "GND")
			(pintype "passive")
		)
		(pad "2" smd roundrect
			(at 0.48 0 270)
			(size 0.59 0.64)
			(layers "F.Cu" "F.Mask" "F.Paste")
			(roundrect_rratio 0.25)
			(net 632 "Net-(U7-OUT2)")
			(pintype "passive")
		)
	)
	(footprint "antmicro-footprints:C_0402_1005Metric"
		(layer "F.Cu")
		(at 185.209404 154.273281)
		(descr "Capacitor SMD 0402")
		(tags "capacitor SMD 0402")
		(property "Reference" "C95"
			(at 0.840596 0.456719 0)
			(layer "F.SilkS")
			(effects
				(font
					(size 0.7 0.7)
					(thickness 0.15)
				)
				(justify left bottom)
			)
		)
		(property "Value" "C_100n_0402"
			(at -1.022927 2.155213 0)
			(layer "F.Fab")
			(hide yes)
			(effects
				(font
					(size 0.7 0.7)
					(thickness 0.15)
				)
				(justify left bottom)
			)
		)
		(property "Datasheet" "https://www.murata.com/products/productdetail?partno=GRM155R61H104KE14%23"
			(at 0 0 0)
			(layer "F.Fab")
			(hide yes)
			(effects
				(font
					(size 1.27 1.27)
					(thickness 0.15)
				)
			)
		)
		(property "Description" "SMD Multilayer Ceramic Capacitor, 0.1 µF, 50 V, 0402 [1005 Metric], ± 10%, X5R, GRM Series"
			(at 0 0 0)
			(layer "F.Fab")
			(hide yes)
			(effects
				(font
					(size 1.27 1.27)
					(thickness 0.15)
				)
			)
		)
		(property "Author" "Antmicro"
			(at 0 0 0)
			(layer "F.Fab")
			(hide yes)
			(effects
				(font
					(size 1 1)
					(thickness 0.15)
				)
			)
		)
		(property "Dielectric" "X5R"
			(at 0 0 0)
			(layer "F.Fab")
			(hide yes)
			(effects
				(font
					(size 1 1)
					(thickness 0.15)
				)
			)
		)
		(property "License" "Apache-2.0"
			(at 0 0 0)
			(layer "F.Fab")
			(hide yes)
			(effects
				(font
					(size 1 1)
					(thickness 0.15)
				)
			)
		)
		(property "MPN" "GRM155R61H104KE14D"
			(at 0 0 0)
			(layer "F.Fab")
			(hide yes)
			(effects
				(font
					(size 1 1)
					(thickness 0.15)
				)
			)
		)
		(property "Manufacturer" "Murata"
			(at 0 0 0)
			(layer "F.Fab")
			(hide yes)
			(effects
				(font
					(size 1 1)
					(thickness 0.15)
				)
			)
		)
		(property "Public" ""
			(at 0 0 0)
			(layer "F.Fab")
			(hide yes)
			(effects
				(font
					(size 1 1)
					(thickness 0.15)
				)
			)
		)
		(property "Val" "100n"
			(at 0 0 0)
			(layer "F.Fab")
			(hide yes)
			(effects
				(font
					(size 1 1)
					(thickness 0.15)
				)
			)
		)
		(property "Voltage" "50V"
			(at 0 0 0)
			(layer "F.Fab")
			(hide yes)
			(effects
				(font
					(size 1 1)
					(thickness 0.15)
				)
			)
		)
		(sheetname "/Supply/")
		(sheetfile "supply.kicad_sch")
		(attr smd)
		(fp_rect
			(start -0.925 -0.47)
			(end 0.925 0.47)
			(stroke
				(width 0.05)
				(type default)
			)
			(fill no)
			(layer "F.CrtYd")
		)
		(fp_line
			(start -0.494 -0.25)
			(end 0.504 -0.25)
			(stroke
				(width 0.15)
				(type solid)
			)
			(layer "F.Fab")
		)
		(fp_line
			(start -0.494 0.248)
			(end -0.494 -0.25)
			(stroke
				(width 0.15)
				(type solid)
			)
			(layer "F.Fab")
		)
		(fp_line
			(start 0.504 -0.25)
			(end 0.504 0.248)
			(stroke
				(width 0.15)
				(type solid)
			)
			(layer "F.Fab")
		)
		(fp_line
			(start 0.504 0.248)
			(end -0.494 0.248)
			(stroke
				(width 0.15)
				(type solid)
			)
			(layer "F.Fab")
		)
		(fp_text user "License: Apache-2.0"
			(at -0.939 5.799 0)
			(layer "F.Fab")
			(effects
				(font
					(size 0.7 0.7)
					(thickness 0.15)
				)
				(justify left bottom)
			)
		)
		(fp_text user "Author: Antmicro"
			(at -0.939 3.399 0)
			(layer "F.Fab")
			(effects
				(font
					(size 0.7 0.7)
					(thickness 0.15)
				)
				(justify left bottom)
			)
		)
		(fp_text user "${REFERENCE}"
			(at -0.939 4.599 0)
			(layer "F.Fab")
			(effects
				(font
					(size 0.7 0.7)
					(thickness 0.15)
				)
				(justify left bottom)
			)
		)
		(pad "1" smd roundrect
			(at -0.48 0)
			(size 0.59 0.64)
			(layers "F.Cu" "F.Mask" "F.Paste")
			(roundrect_rratio 0.25)
			(net 149 "/Supply/1V05_BS")
			(pintype "passive")
		)
		(pad "2" smd roundrect
			(at 0.48 0)
			(size 0.59 0.64)
			(layers "F.Cu" "F.Mask" "F.Paste")
			(roundrect_rratio 0.25)
			(net 150 "/Supply/1V05_SW")
			(pintype "passive")
		)
	)
	(footprint "antmicro-footprints:MP_NPTH_Drill2.7mm"
		(locked yes)
		(layer "F.Cu")
		(at 178.01803 119.33703)
		(property "Reference" "MP1"
			(at 0 -1.8 0)
			(layer "F.SilkS")
			(hide yes)
			(effects
				(font
					(size 0.7 0.7)
					(thickness 0.15)
				)
				(justify left bottom)
			)
		)
		(property "Value" "MP_NPTH_Drill2.7mm"
			(at 0 2.3 0)
			(layer "F.Fab")
			(hide yes)
			(effects
				(font
					(size 0.7 0.7)
					(thickness 0.15)
				)
				(justify left bottom)
			)
		)
		(property "Description" "Mechanical part"
			(at 0 0 0)
			(layer "F.Fab")
			(hide yes)
			(effects
				(font
					(size 1.27 1.27)
					(thickness 0.15)
				)
			)
		)
		(property "Author" "Antmicro"
			(at 0 0 0)
			(layer "F.Fab")
			(hide yes)
			(effects
				(font
					(size 1 1)
					(thickness 0.15)
				)
			)
		)
		(property "License" "Apache-2.0"
			(at 0 0 0)
			(layer "F.Fab")
			(hide yes)
			(effects
				(font
					(size 1 1)
					(thickness 0.15)
				)
			)
		)
		(property "exclude_from_bom" ""
			(at 0 0 0)
			(layer "F.Fab")
			(hide yes)
			(effects
				(font
					(size 1 1)
					(thickness 0.15)
				)
			)
		)
		(sheetfile "polarfire-som.kicad_sch")
		(attr board_only exclude_from_pos_files exclude_from_bom)
		(fp_circle
			(center 0 0)
			(end 1.45 0)
			(stroke
				(width 0.05)
				(type default)
			)
			(fill no)
			(layer "F.CrtYd")
		)
		(fp_text user "${REFERENCE}"
			(at 0 4.749 0)
			(layer "F.Fab")
			(effects
				(font
					(size 0.7 0.7)
					(thickness 0.15)
				)
				(justify left bottom)
			)
		)
		(fp_text user "Author: Antmicro"
			(at 0 5.95 0)
			(layer "F.Fab")
			(effects
				(font
					(size 0.7 0.7)
					(thickness 0.15)
				)
				(justify left bottom)
			)
		)
		(fp_text user "License: Apache-2.0"
			(at 0 7.15 0)
			(layer "F.Fab")
			(effects
				(font
					(size 0.7 0.7)
					(thickness 0.15)
				)
				(justify left bottom)
			)
		)
		(pad "" np_thru_hole circle
			(at 0 0)
			(size 2.7 2.7)
			(drill 2.7)
			(layers "F&B.Cu" "*.Mask")
		)
	)
	(footprint "antmicro-footprints:Oscillator_SMD_ECS_2016MV_2x1.6x0.85mm"
		(layer "F.Cu")
		(at 210.9 144.65 90)
		(property "Reference" "Y1"
			(at 0.81 1.74 180)
			(layer "F.SilkS")
			(effects
				(font
					(size 0.7 0.7)
					(thickness 0.15)
				)
				(justify right bottom)
			)
		)
		(property "Value" "Oscillator_24MHz_ESC_2016MV"
			(at 0 2.2 90)
			(layer "F.Fab")
			(hide yes)
			(effects
				(font
					(size 0.7 0.7)
					(thickness 0.15)
				)
				(justify left bottom)
			)
		)
		(property "Datasheet" "https://ecsxtal.com/store/pdf/ECS-2016MV.pdf"
			(at 0 0 90)
			(layer "F.Fab")
			(hide yes)
			(effects
				(font
					(size 1.27 1.27)
					(thickness 0.15)
				)
			)
		)
		(property "Description" "Oscillator, 24 MHz XO (Standard) CMOS 1.6V ~ 3.6V Enable/Disable 4-SMD, No Lead"
			(at 0 0 90)
			(layer "F.Fab")
			(hide yes)
			(effects
				(font
					(size 1.27 1.27)
					(thickness 0.15)
				)
			)
		)
		(property "Author" "Antmicro"
			(at 355.55 -66.25 0)
			(layer "F.Fab")
			(hide yes)
			(effects
				(font
					(size 1 1)
					(thickness 0.15)
				)
			)
		)
		(property "License" "Apache-2.0"
			(at 355.55 -66.25 0)
			(layer "F.Fab")
			(hide yes)
			(effects
				(font
					(size 1 1)
					(thickness 0.15)
				)
			)
		)
		(property "MPN" "ECS-2016MV-240-CN-TR"
			(at 355.55 -66.25 0)
			(layer "F.Fab")
			(hide yes)
			(effects
				(font
					(size 1 1)
					(thickness 0.15)
				)
			)
		)
		(property "Manufacturer" "ECS Inc. International"
			(at 355.55 -66.25 0)
			(layer "F.Fab")
			(hide yes)
			(effects
				(font
					(size 1 1)
					(thickness 0.15)
				)
			)
		)
		(property "Public" ""
			(at 355.55 -66.25 0)
			(layer "F.Fab")
			(hide yes)
			(effects
				(font
					(size 1 1)
					(thickness 0.15)
				)
			)
		)
		(property "Val" "24 MHz"
			(at 355.55 -66.25 0)
			(layer "F.Fab")
			(hide yes)
			(effects
				(font
					(size 1 1)
					(thickness 0.15)
				)
			)
		)
		(sheetname "/USB/")
		(sheetfile "usb.kicad_sch")
		(attr smd)
		(fp_line
			(start -0.4 -1.15)
			(end 0.4 -1.15)
			(stroke
				(width 0.15)
				(type solid)
			)
			(layer "F.SilkS")
		)
		(fp_line
			(start 0.95 0.4)
			(end 0.95 -0.4)
			(stroke
				(width 0.15)
				(type solid)
			)
			(layer "F.SilkS")
		)
		(fp_line
			(start -0.95 0.4)
			(end -0.95 -0.4)
			(stroke
				(width 0.15)
				(type solid)
			)
			(layer "F.SilkS")
		)
		(fp_line
			(start -0.4 1.15)
			(end 0.4 1.15)
			(stroke
				(width 0.15)
				(type solid)
			)
			(layer "F.SilkS")
		)
		(fp_circle
			(center -0.95 -1.15)
			(end -0.9 -1.15)
			(stroke
				(width 0.15)
				(type solid)
			)
			(fill yes)
			(layer "F.SilkS")
		)
		(fp_rect
			(start -1.05 -1.25)
			(end 1.05 1.24)
			(stroke
				(width 0.05)
				(type solid)
			)
			(fill no)
			(layer "F.CrtYd")
		)
		(fp_rect
			(start -0.85 -1.054)
			(end 0.852 1.054)
			(stroke
				(width 0.15)
				(type solid)
			)
			(fill no)
			(layer "F.Fab")
		)
		(fp_text user "${REFERENCE}"
			(at -1.05 3.4 90)
			(layer "F.Fab")
			(effects
				(font
					(size 0.7 0.7)
					(thickness 0.15)
				)
				(justify left bottom)
			)
		)
		(fp_text user "Author: Antmicro"
			(at -1.05 4.6 90)
			(layer "F.Fab")
			(effects
				(font
					(size 0.7 0.7)
					(thickness 0.15)
				)
				(justify left bottom)
			)
		)
		(fp_text user "License: Apache-2.0"
			(at -1.05 5.8 90)
			(layer "F.Fab")
			(effects
				(font
					(size 0.7 0.7)
					(thickness 0.15)
				)
				(justify left bottom)
			)
		)
		(pad "1" smd rect
			(at -0.486 -0.637 90)
			(size 0.6858 0.7874)
			(layers "F.Cu" "F.Mask" "F.Paste")
			(net 50 "+3V3")
			(pinfunction "EN")
			(pintype "input")
		)
		(pad "2" smd rect
			(at -0.486 0.636 90)
			(size 0.6858 0.7874)
			(layers "F.Cu" "F.Mask" "F.Paste")
			(net 417 "GND")
			(pinfunction "GND")
			(pintype "power_in")
		)
		(pad "3" smd rect
			(at 0.487 0.636 90)
			(size 0.6858 0.7874)
			(layers "F.Cu" "F.Mask" "F.Paste")
			(net 500 "/USB/REF_CLK")
			(pinfunction "OUT")
			(pintype "output")
		)
		(pad "4" smd rect
			(at 0.487 -0.637 90)
			(size 0.6858 0.7874)
			(layers "F.Cu" "F.Mask" "F.Paste")
			(net 50 "+3V3")
			(pinfunction "VDD")
			(pintype "power_in")
		)
	)
	(footprint "antmicro-footprints:R_0402_1005Metric"
		(layer "F.Cu")
		(at 204.35 120.75 90)
		(descr "Resistor SMD 0402")
		(tags "resistor SMD 0402")
		(property "Reference" "R57"
			(at -1.85 4 90)
			(layer "F.SilkS")
			(effects
				(font
					(size 0.7 0.7)
					(thickness 0.15)
				)
				(justify left bottom)
			)
		)
		(property "Value" "R_0R_0402"
			(at -1.011843 1.772047 90)
			(layer "F.Fab")
			(hide yes)
			(effects
				(font
					(size 0.7 0.7)
					(thickness 0.15)
				)
				(justify left bottom)
			)
		)
		(property "Datasheet" "https://industrial.panasonic.com/cdbs/www-data/pdf/RDA0000/AOA0000C301.pdf"
			(at 0 0 90)
			(layer "F.Fab")
			(hide yes)
			(effects
				(font
					(size 1.27 1.27)
					(thickness 0.15)
				)
			)
		)
		(property "Description" "SMD Chip Resistor, Jumper, 0 ohm, 100 mW, 0402 [1005 Metric], Thick Film, General Purpose"
			(at 0 0 90)
			(layer "F.Fab")
			(hide yes)
			(effects
				(font
					(size 1.27 1.27)
					(thickness 0.15)
				)
			)
		)
		(property "Author" "Antmicro"
			(at 325.1 -83.6 0)
			(layer "F.Fab")
			(hide yes)
			(effects
				(font
					(size 1 1)
					(thickness 0.15)
				)
			)
		)
		(property "Current" "1A"
			(at 325.1 -83.6 0)
			(layer "F.Fab")
			(hide yes)
			(effects
				(font
					(size 1 1)
					(thickness 0.15)
				)
			)
		)
		(property "License" "Apache-2.0"
			(at 325.1 -83.6 0)
			(layer "F.Fab")
			(hide yes)
			(effects
				(font
					(size 1 1)
					(thickness 0.15)
				)
			)
		)
		(property "MPN" "ERJ2GE0R00X"
			(at 325.1 -83.6 0)
			(layer "F.Fab")
			(hide yes)
			(effects
				(font
					(size 1 1)
					(thickness 0.15)
				)
			)
		)
		(property "Manufacturer" "Panasonic"
			(at 325.1 -83.6 0)
			(layer "F.Fab")
			(hide yes)
			(effects
				(font
					(size 1 1)
					(thickness 0.15)
				)
			)
		)
		(property "Public" ""
			(at 325.1 -83.6 0)
			(layer "F.Fab")
			(hide yes)
			(effects
				(font
					(size 1 1)
					(thickness 0.15)
				)
			)
		)
		(property "Tolerance" "~"
			(at 325.1 -83.6 0)
			(layer "F.Fab")
			(hide yes)
			(effects
				(font
					(size 1 1)
					(thickness 0.15)
				)
			)
		)
		(property "Val" "0R"
			(at 325.1 -83.6 0)
			(layer "F.Fab")
			(hide yes)
			(effects
				(font
					(size 1 1)
					(thickness 0.15)
				)
			)
		)
		(sheetname "/FPGA MSSIO/")
		(sheetfile "fpga-mssio.kicad_sch")
		(attr smd)
		(fp_rect
			(start -0.925 -0.47)
			(end 0.925 0.47)
			(stroke
				(width 0.05)
				(type default)
			)
			(fill no)
			(layer "F.CrtYd")
		)
		(fp_rect
			(start -0.5 -0.25)
			(end 0.5 0.25)
			(stroke
				(width 0.15)
				(type solid)
			)
			(fill no)
			(layer "F.Fab")
		)
		(fp_text user "Author: Antmicro"
			(at -0.95 4.169 90)
			(layer "F.Fab")
			(effects
				(font
					(size 0.7 0.7)
					(thickness 0.15)
				)
				(justify left bottom)
			)
		)
		(fp_text user "${REFERENCE}"
			(at -0.95 3.168 90)
			(layer "F.Fab")
			(effects
				(font
					(size 0.7 0.7)
					(thickness 0.15)
				)
				(justify left bottom)
			)
		)
		(fp_text user "License: Apache-2.0"
			(at -0.95 5.169 90)
			(layer "F.Fab")
			(effects
				(font
					(size 0.7 0.7)
					(thickness 0.15)
				)
				(justify left bottom)
			)
		)
		(pad "1" smd roundrect
			(at -0.48 0 90)
			(size 0.59 0.64)
			(layers "F.Cu" "F.Mask" "F.Paste")
			(roundrect_rratio 0.25)
			(net 100 "/FPGA MSSIO/SUPPLY.SDA")
			(pintype "passive")
		)
		(pad "2" smd roundrect
			(at 0.48 0 90)
			(size 0.59 0.64)
			(layers "F.Cu" "F.Mask" "F.Paste")
			(roundrect_rratio 0.25)
			(net 101 "/FPGA MSSIO/ID.SDA")
			(pintype "passive")
		)
	)
	(footprint "antmicro-footprints:TP_SMD_0.75mm"
		(layer "F.Cu")
		(at 227.2 148.45)
		(property "Reference" "TP8"
			(at 10.51 3.29 0)
			(layer "F.SilkS")
			(hide yes)
			(effects
				(font
					(size 0.7 0.7)
					(thickness 0.15)
				)
				(justify left bottom)
			)
		)
		(property "Value" "TP_0.75mm_SMD"
			(at 0 1.2 0)
			(layer "F.Fab")
			(hide yes)
			(effects
				(font
					(size 0.7 0.7)
					(thickness 0.15)
				)
				(justify left bottom)
			)
		)
		(property "Description" "SMT test point"
			(at 0 0 0)
			(layer "F.Fab")
			(hide yes)
			(effects
				(font
					(size 1.27 1.27)
					(thickness 0.15)
				)
			)
		)
		(property "Author" "Antmicro"
			(at 0 0 0)
			(layer "F.Fab")
			(hide yes)
			(effects
				(font
					(size 1 1)
					(thickness 0.15)
				)
			)
		)
		(property "License" "Apache-2.0"
			(at 0 0 0)
			(layer "F.Fab")
			(hide yes)
			(effects
				(font
					(size 1 1)
					(thickness 0.15)
				)
			)
		)
		(property "MPN" ""
			(at 0 0 0)
			(layer "F.Fab")
			(hide yes)
			(effects
				(font
					(size 1 1)
					(thickness 0.15)
				)
			)
		)
		(property "Manufacturer" ""
			(at 0 0 0)
			(layer "F.Fab")
			(hide yes)
			(effects
				(font
					(size 1 1)
					(thickness 0.15)
				)
			)
		)
		(property "Public" "False"
			(at 0 0 0)
			(layer "F.Fab")
			(hide yes)
			(effects
				(font
					(size 1 1)
					(thickness 0.15)
				)
			)
		)
		(sheetname "/WiFi_Bluetooth/")
		(sheetfile "wifi_bt.kicad_sch")
		(attr exclude_from_pos_files exclude_from_bom)
		(fp_circle
			(center 0 0)
			(end 0.475 0)
			(stroke
				(width 0.05)
				(type default)
			)
			(fill no)
			(layer "F.CrtYd")
		)
		(fp_text user "${REFERENCE}"
			(at -0.4 2.7 0)
			(layer "F.Fab")
			(effects
				(font
					(size 0.7 0.7)
					(thickness 0.15)
				)
				(justify left bottom)
			)
		)
		(fp_text user "License: Apache-2.0"
			(at -0.4 5.101 0)
			(layer "F.Fab")
			(effects
				(font
					(size 0.7 0.7)
					(thickness 0.15)
				)
				(justify left bottom)
			)
		)
		(fp_text user "Author: Antmicro"
			(at -0.4 3.901 0)
			(layer "F.Fab")
			(effects
				(font
					(size 0.7 0.7)
					(thickness 0.15)
				)
				(justify left bottom)
			)
		)
		(pad "1" smd circle
			(at 0 0)
			(size 0.75 0.75)
			(layers "F.Cu" "F.Mask")
			(net 297 "Net-(U26A-BT_UART_CTS_N)")
			(pinfunction "1")
			(pintype "passive")
		)
	)
	(footprint "antmicro-footprints:L_0806_2016Metric"
		(layer "F.Cu")
		(at 183.375 139.903695 90)
		(property "Reference" "L3"
			(at 1.683695 -0.665 180)
			(layer "F.SilkS")
			(effects
				(font
					(size 0.7 0.7)
					(thickness 0.15)
				)
				(justify left bottom)
			)
		)
		(property "Value" "L_1u5_2.8A_0806"
			(at 0 2 90)
			(layer "F.Fab")
			(hide yes)
			(effects
				(font
					(size 0.7 0.7)
					(thickness 0.15)
				)
				(justify left bottom)
			)
		)
		(property "Datasheet" "https://abracon.com/datasheets/AOTA-B201610S.pdf"
			(at 0 0 90)
			(layer "F.Fab")
			(hide yes)
			(effects
				(font
					(size 1.27 1.27)
					(thickness 0.15)
				)
			)
		)
		(property "Description" "Power Inductor (SMT), 1.5 µH, 0.074 ohm, 2.8 A, AOTA-B201610S"
			(at 0 0 90)
			(layer "F.Fab")
			(hide yes)
			(effects
				(font
					(size 1.27 1.27)
					(thickness 0.15)
				)
			)
		)
		(property "Author" "Antmicro"
			(at 323.278695 -43.471305 0)
			(layer "F.Fab")
			(hide yes)
			(effects
				(font
					(size 1 1)
					(thickness 0.15)
				)
			)
		)
		(property "IMax" "2.8 A"
			(at 323.278695 -43.471305 0)
			(layer "F.Fab")
			(hide yes)
			(effects
				(font
					(size 1 1)
					(thickness 0.15)
				)
			)
		)
		(property "ISat" "3.5 A"
			(at 323.278695 -43.471305 0)
			(layer "F.Fab")
			(hide yes)
			(effects
				(font
					(size 1 1)
					(thickness 0.15)
				)
			)
		)
		(property "License" "Apache-2.0"
			(at 323.278695 -43.471305 0)
			(layer "F.Fab")
			(hide yes)
			(effects
				(font
					(size 1 1)
					(thickness 0.15)
				)
			)
		)
		(property "MPN" "AOTA-B201610S1R5MT"
			(at 323.278695 -43.471305 0)
			(layer "F.Fab")
			(hide yes)
			(effects
				(font
					(size 1 1)
					(thickness 0.15)
				)
			)
		)
		(property "Manufacturer" "Abracon"
			(at 323.278695 -43.471305 0)
			(layer "F.Fab")
			(hide yes)
			(effects
				(font
					(size 1 1)
					(thickness 0.15)
				)
			)
		)
		(property "Public" ""
			(at 323.278695 -43.471305 0)
			(layer "F.Fab")
			(hide yes)
			(effects
				(font
					(size 1 1)
					(thickness 0.15)
				)
			)
		)
		(property "Size" "2.0x1.6"
			(at 323.278695 -43.471305 0)
			(layer "F.Fab")
			(hide yes)
			(effects
				(font
					(size 1 1)
					(thickness 0.15)
				)
			)
		)
		(property "Val" "1.5u/2.8A"
			(at 323.278695 -43.471305 0)
			(layer "F.Fab")
			(hide yes)
			(effects
				(font
					(size 1 1)
					(thickness 0.15)
				)
			)
		)
		(sheetname "/Supply/")
		(sheetfile "supply.kicad_sch")
		(attr smd)
		(fp_line
			(start -0.3 -0.9)
			(end 0.298 -0.9)
			(stroke
				(width 0.15)
				(type solid)
			)
			(layer "F.SilkS")
		)
		(fp_line
			(start -0.301 0.9)
			(end 0.299 0.9)
			(stroke
				(width 0.15)
				(type solid)
			)
			(layer "F.SilkS")
		)
		(fp_rect
			(start -1.75 -1.05)
			(end 1.75 1.05)
			(stroke
				(width 0.05)
				(type solid)
			)
			(fill no)
			(layer "F.CrtYd")
		)
		(fp_rect
			(start -0.951 -0.882)
			(end 0.949 0.875)
			(stroke
				(width 0.15)
				(type solid)
			)
			(fill no)
			(layer "F.Fab")
		)
		(fp_text user "${REFERENCE}"
			(at -1.9 3.1 90)
			(layer "F.Fab")
			(effects
				(font
					(size 0.7 0.7)
					(thickness 0.15)
				)
				(justify left bottom)
			)
		)
		(fp_text user "Author: Antmicro"
			(at -1.9 4.4 90)
			(layer "F.Fab")
			(effects
				(font
					(size 0.7 0.7)
					(thickness 0.15)
				)
				(justify left bottom)
			)
		)
		(fp_text user "License: Apache-2.0"
			(at -1.9 5.75 90)
			(layer "F.Fab")
			(effects
				(font
					(size 0.7 0.7)
					(thickness 0.15)
				)
				(justify left bottom)
			)
		)
		(pad "1" smd roundrect
			(at -1.1 -0.001 90)
			(size 1 1.8)
			(layers "F.Cu" "F.Mask" "F.Paste")
			(roundrect_rratio 0.15)
			(net 175 "Net-(U7-SW2)")
			(pintype "passive")
		)
		(pad "2" smd roundrect
			(at 1.1 -0.001 90)
			(size 1 1.8)
			(layers "F.Cu" "F.Mask" "F.Paste")
			(roundrect_rratio 0.15)
			(net 272 "/Supply/SENSE3_P")
			(pintype "passive")
		)
	)
	(footprint "antmicro-footprints:C_0402_1005Metric"
		(layer "F.Cu")
		(at 194.85 120.95 -90)
		(descr "Capacitor SMD 0402")
		(tags "capacitor SMD 0402")
		(property "Reference" "C131"
			(at -1.18 -4.37 90)
			(layer "F.SilkS")
			(effects
				(font
					(size 0.7 0.7)
					(thickness 0.15)
				)
				(justify right bottom)
			)
		)
		(property "Value" "C_100n_0402"
			(at -1.022927 2.155213 90)
			(layer "F.Fab")
			(hide yes)
			(effects
				(font
					(size 0.7 0.7)
					(thickness 0.15)
				)
				(justify right bottom)
			)
		)
		(property "Datasheet" "https://www.murata.com/products/productdetail?partno=GRM155R61H104KE14%23"
			(at 0 0 270)
			(layer "F.Fab")
			(hide yes)
			(effects
				(font
					(size 1.27 1.27)
					(thickness 0.15)
				)
			)
		)
		(property "Description" "SMD Multilayer Ceramic Capacitor, 0.1 µF, 50 V, 0402 [1005 Metric], ± 10%, X5R, GRM Series"
			(at 0 0 270)
			(layer "F.Fab")
			(hide yes)
			(effects
				(font
					(size 1.27 1.27)
					(thickness 0.15)
				)
			)
		)
		(property "Author" "Antmicro"
			(at 73.9 315.8 0)
			(layer "F.Fab")
			(hide yes)
			(effects
				(font
					(size 1 1)
					(thickness 0.15)
				)
			)
		)
		(property "Dielectric" "X5R"
			(at 73.9 315.8 0)
			(layer "F.Fab")
			(hide yes)
			(effects
				(font
					(size 1 1)
					(thickness 0.15)
				)
			)
		)
		(property "License" "Apache-2.0"
			(at 73.9 315.8 0)
			(layer "F.Fab")
			(hide yes)
			(effects
				(font
					(size 1 1)
					(thickness 0.15)
				)
			)
		)
		(property "MPN" "GRM155R61H104KE14D"
			(at 73.9 315.8 0)
			(layer "F.Fab")
			(hide yes)
			(effects
				(font
					(size 1 1)
					(thickness 0.15)
				)
			)
		)
		(property "Manufacturer" "Murata"
			(at 73.9 315.8 0)
			(layer "F.Fab")
			(hide yes)
			(effects
				(font
					(size 1 1)
					(thickness 0.15)
				)
			)
		)
		(property "Public" ""
			(at 73.9 315.8 0)
			(layer "F.Fab")
			(hide yes)
			(effects
				(font
					(size 1 1)
					(thickness 0.15)
				)
			)
		)
		(property "Val" "100n"
			(at 73.9 315.8 0)
			(layer "F.Fab")
			(hide yes)
			(effects
				(font
					(size 1 1)
					(thickness 0.15)
				)
			)
		)
		(property "Voltage" "50V"
			(at 73.9 315.8 0)
			(layer "F.Fab")
			(hide yes)
			(effects
				(font
					(size 1 1)
					(thickness 0.15)
				)
			)
		)
		(sheetname "/FPGA GPIO/")
		(sheetfile "fpga-gpio.kicad_sch")
		(attr smd)
		(fp_rect
			(start -0.925 -0.47)
			(end 0.925 0.47)
			(stroke
				(width 0.05)
				(type default)
			)
			(fill no)
			(layer "F.CrtYd")
		)
		(fp_line
			(start -0.494 0.248)
			(end -0.494 -0.25)
			(stroke
				(width 0.15)
				(type solid)
			)
			(layer "F.Fab")
		)
		(fp_line
			(start 0.504 0.248)
			(end -0.494 0.248)
			(stroke
				(width 0.15)
				(type solid)
			)
			(layer "F.Fab")
		)
		(fp_line
			(start -0.494 -0.25)
			(end 0.504 -0.25)
			(stroke
				(width 0.15)
				(type solid)
			)
			(layer "F.Fab")
		)
		(fp_line
			(start 0.504 -0.25)
			(end 0.504 0.248)
			(stroke
				(width 0.15)
				(type solid)
			)
			(layer "F.Fab")
		)
		(fp_text user "License: Apache-2.0"
			(at -0.939 5.799 270)
			(layer "F.Fab")
			(effects
				(font
					(size 0.7 0.7)
					(thickness 0.15)
				)
				(justify left bottom)
			)
		)
		(fp_text user "${REFERENCE}"
			(at -0.939 4.599 270)
			(layer "F.Fab")
			(effects
				(font
					(size 0.7 0.7)
					(thickness 0.15)
				)
				(justify left bottom)
			)
		)
		(fp_text user "Author: Antmicro"
			(at -0.939 3.399 270)
			(layer "F.Fab")
			(effects
				(font
					(size 0.7 0.7)
					(thickness 0.15)
				)
				(justify left bottom)
			)
		)
		(pad "1" smd roundrect
			(at -0.48 0 270)
			(size 0.59 0.64)
			(layers "F.Cu" "F.Mask" "F.Paste")
			(roundrect_rratio 0.25)
			(net 50 "+3V3")
			(pintype "passive")
		)
		(pad "2" smd roundrect
			(at 0.48 0 270)
			(size 0.59 0.64)
			(layers "F.Cu" "F.Mask" "F.Paste")
			(roundrect_rratio 0.25)
			(net 417 "GND")
			(pintype "passive")
		)
	)
	(footprint "antmicro-footprints:D_0402_1005Metric"
		(layer "F.Cu")
		(at 210.198712 151.829798 -90)
		(property "Reference" "D3"
			(at -1.169798 -1.381288 90)
			(layer "F.SilkS")
			(effects
				(font
					(size 0.7 0.7)
					(thickness 0.15)
				)
				(justify right bottom)
			)
		)
		(property "Value" "AXGD10402KR"
			(at -2.54 2.54 90)
			(layer "F.Fab")
			(hide yes)
			(effects
				(font
					(size 0.7 0.7)
					(thickness 0.15)
				)
				(justify right bottom)
			)
		)
		(property "Datasheet" "https://www.littelfuse.com/media?resourcetype=datasheets&itemid=020b2bf2-064c-4ff1-a898-b4ec805b2fea&filename=littelfuse-xtremeguard-axgd-datasheet"
			(at 0 0 270)
			(layer "F.Fab")
			(hide yes)
			(effects
				(font
					(size 1.27 1.27)
					(thickness 0.15)
				)
			)
		)
		(property "Description" "Bidirectional TVS, 30 kV,  0402, 24 V, 0.04 pF"
			(at 0 0 270)
			(layer "F.Fab")
			(hide yes)
			(effects
				(font
					(size 1.27 1.27)
					(thickness 0.15)
				)
			)
		)
		(property "Author" "Antmicro"
			(at 58.368914 362.02851 0)
			(layer "F.Fab")
			(hide yes)
			(effects
				(font
					(size 1 1)
					(thickness 0.15)
				)
			)
		)
		(property "License" "Apache-2.0"
			(at 58.368914 362.02851 0)
			(layer "F.Fab")
			(hide yes)
			(effects
				(font
					(size 1 1)
					(thickness 0.15)
				)
			)
		)
		(property "MPN" "AXGD10402KR"
			(at 58.368914 362.02851 0)
			(layer "F.Fab")
			(hide yes)
			(effects
				(font
					(size 1 1)
					(thickness 0.15)
				)
			)
		)
		(property "Manufacturer" "Littelfuse"
			(at 58.368914 362.02851 0)
			(layer "F.Fab")
			(hide yes)
			(effects
				(font
					(size 1 1)
					(thickness 0.15)
				)
			)
		)
		(property "Public" ""
			(at 58.368914 362.02851 0)
			(layer "F.Fab")
			(hide yes)
			(effects
				(font
					(size 1 1)
					(thickness 0.15)
				)
			)
		)
		(sheetname "/USB/")
		(sheetfile "usb.kicad_sch")
		(attr smd)
		(fp_line
			(start -0.1 0.255)
			(end 0.1 0.255)
			(stroke
				(width 0.15)
				(type solid)
			)
			(layer "F.SilkS")
		)
		(fp_line
			(start -0.875 -0.25)
			(end -0.875 0.25)
			(stroke
				(width 0.15)
				(type solid)
			)
			(layer "F.SilkS")
		)
		(fp_line
			(start 0.1 -0.255)
			(end -0.1 -0.255)
			(stroke
				(width 0.15)
				(type solid)
			)
			(layer "F.SilkS")
		)
		(fp_rect
			(start -0.925 -0.47)
			(end 0.925 0.47)
			(stroke
				(width 0.05)
				(type default)
			)
			(fill no)
			(layer "F.CrtYd")
		)
		(fp_line
			(start -0.51 0.255)
			(end -0.51 -0.255)
			(stroke
				(width 0.15)
				(type solid)
			)
			(layer "F.Fab")
		)
		(fp_line
			(start 0.51 0.255)
			(end -0.51 0.255)
			(stroke
				(width 0.15)
				(type solid)
			)
			(layer "F.Fab")
		)
		(fp_line
			(start -0.2 -0.25)
			(end -0.5 0.05)
			(stroke
				(width 0.15)
				(type solid)
			)
			(layer "F.Fab")
		)
		(fp_line
			(start -0.51 -0.255)
			(end 0.51 -0.255)
			(stroke
				(width 0.15)
				(type solid)
			)
			(layer "F.Fab")
		)
		(fp_line
			(start 0.51 -0.255)
			(end 0.51 0.255)
			(stroke
				(width 0.15)
				(type solid)
			)
			(layer "F.Fab")
		)
		(fp_text user "${REFERENCE}"
			(at -2.54 4.54 270)
			(layer "F.Fab")
			(effects
				(font
					(size 0.7 0.7)
					(thickness 0.15)
				)
				(justify left bottom)
			)
		)
		(fp_text user "Author: Antmicro"
			(at -2.54 6.94 270)
			(layer "F.Fab")
			(effects
				(font
					(size 0.7 0.7)
					(thickness 0.15)
				)
				(justify left bottom)
			)
		)
		(fp_text user "License: Apache-2.0"
			(at -2.54 5.74 270)
			(layer "F.Fab")
			(effects
				(font
					(size 0.7 0.7)
					(thickness 0.15)
				)
				(justify left bottom)
			)
		)
		(pad "1" smd roundrect
			(at -0.48 0 270)
			(size 0.59 0.64)
			(layers "F.Cu" "F.Mask" "F.Paste")
			(roundrect_rratio 0.25)
			(net 417 "GND")
			(pinfunction "C")
			(pintype "passive")
		)
		(pad "2" smd roundrect
			(at 0.48 0 270)
			(size 0.59 0.64)
			(layers "F.Cu" "F.Mask" "F.Paste")
			(roundrect_rratio 0.25)
			(net 16 "/Bottom Connector/CONN.D_P")
			(pinfunction "A")
			(pintype "passive")
		)
	)
	(footprint "antmicro-footprints:QFN-24-1EP_4x4mm_P0.5_EP2.5x2.5mm"
		(layer "F.Cu")
		(at 214.865 142.4 90)
		(property "Reference" "U13"
			(at 0.28 3.185 270)
			(layer "F.SilkS")
			(effects
				(font
					(size 0.7 0.7)
					(thickness 0.15)
				)
				(justify left bottom)
			)
		)
		(property "Value" "USB3315-CP-TR"
			(at 0 3.4 90)
			(layer "F.Fab")
			(hide yes)
			(effects
				(font
					(size 0.7 0.7)
					(thickness 0.15)
				)
				(justify left bottom)
			)
		)
		(property "Datasheet" "https://ww1.microchip.com/downloads/aemDocuments/documents/OTH/ProductDocuments/DataSheets/00002364A.pdf"
			(at 0 0 90)
			(layer "F.Fab")
			(hide yes)
			(effects
				(font
					(size 1.27 1.27)
					(thickness 0.15)
				)
			)
		)
		(property "Description" "USB Interface, USB PHY Transceiver, USB 2.0, 3 V, 5.5 V, QFN, 24 Pins"
			(at 0 0 90)
			(layer "F.Fab")
			(hide yes)
			(effects
				(font
					(size 1.27 1.27)
					(thickness 0.15)
				)
			)
		)
		(property "Author" "Antmicro"
			(at 357.265 -72.465 0)
			(layer "F.Fab")
			(hide yes)
			(effects
				(font
					(size 1 1)
					(thickness 0.15)
				)
			)
		)
		(property "License" "Apache-2.0"
			(at 357.265 -72.465 0)
			(layer "F.Fab")
			(hide yes)
			(effects
				(font
					(size 1 1)
					(thickness 0.15)
				)
			)
		)
		(property "MPN" "USB3315-CP-TR"
			(at 357.265 -72.465 0)
			(layer "F.Fab")
			(hide yes)
			(effects
				(font
					(size 1 1)
					(thickness 0.15)
				)
			)
		)
		(property "Manufacturer" "Microchip Technology"
			(at 357.265 -72.465 0)
			(layer "F.Fab")
			(hide yes)
			(effects
				(font
					(size 1 1)
					(thickness 0.15)
				)
			)
		)
		(sheetname "/USB/")
		(sheetfile "usb.kicad_sch")
		(attr smd)
		(fp_line
			(start 2.108 -2.11)
			(end 2.108 -1.635)
			(stroke
				(width 0.15)
				(type solid)
			)
			(layer "F.SilkS")
		)
		(fp_line
			(start 1.634 -2.11)
			(end 2.108 -2.11)
			(stroke
				(width 0.15)
				(type solid)
			)
			(layer "F.SilkS")
		)
		(fp_line
			(start -1.635 -2.11)
			(end -2.11 -2.11)
			(stroke
				(width 0.15)
				(type solid)
			)
			(layer "F.SilkS")
		)
		(fp_line
			(start -2.11 -1.636)
			(end -2.11 -2.11)
			(stroke
				(width 0.15)
				(type solid)
			)
			(layer "F.SilkS")
		)
		(fp_line
			(start 2.108 2.108)
			(end 2.108 1.634)
			(stroke
				(width 0.15)
				(type solid)
			)
			(layer "F.SilkS")
		)
		(fp_line
			(start 1.634 2.108)
			(end 2.108 2.108)
			(stroke
				(width 0.15)
				(type solid)
			)
			(layer "F.SilkS")
		)
		(fp_line
			(start -1.635 2.108)
			(end -2.11 2.108)
			(stroke
				(width 0.15)
				(type solid)
			)
			(layer "F.SilkS")
		)
		(fp_line
			(start -2.11 2.108)
			(end -2.11 1.634)
			(stroke
				(width 0.15)
				(type solid)
			)
			(layer "F.SilkS")
		)
		(fp_circle
			(center -2.3 -2.3)
			(end -2.25 -2.3)
			(stroke
				(width 0.15)
				(type solid)
			)
			(fill yes)
			(layer "F.SilkS")
		)
		(fp_rect
			(start -2.503 -2.503)
			(end 2.5 2.5)
			(stroke
				(width 0.05)
				(type solid)
			)
			(fill no)
			(layer "F.CrtYd")
		)
		(fp_line
			(start 1.999 -2)
			(end 1.999 1.999)
			(stroke
				(width 0.15)
				(type solid)
			)
			(layer "F.Fab")
		)
		(fp_line
			(start -1 -2)
			(end 1.999 -2)
			(stroke
				(width 0.15)
				(type solid)
			)
			(layer "F.Fab")
		)
		(fp_line
			(start -2 -1)
			(end -1 -2)
			(stroke
				(width 0.15)
				(type solid)
			)
			(layer "F.Fab")
		)
		(fp_line
			(start 1.999 1.999)
			(end -2 1.999)
			(stroke
				(width 0.15)
				(type solid)
			)
			(layer "F.Fab")
		)
		(fp_line
			(start -2 1.999)
			(end -2 -1)
			(stroke
				(width 0.15)
				(type solid)
			)
			(layer "F.Fab")
		)
		(fp_text user "Author: Antmicro"
			(at -2.503 7.8 90)
			(layer "F.Fab")
			(effects
				(font
					(size 0.7 0.7)
					(thickness 0.15)
				)
				(justify left bottom)
			)
		)
		(fp_text user "License: Apache-2.0"
			(at -2.503 6.6 90)
			(layer "F.Fab")
			(effects
				(font
					(size 0.7 0.7)
					(thickness 0.15)
				)
				(justify left bottom)
			)
		)
		(fp_text user "${REFERENCE}"
			(at -2.503 5.4 90)
			(layer "F.Fab")
			(effects
				(font
					(size 0.7 0.7)
					(thickness 0.15)
				)
				(justify left bottom)
			)
		)
		(pad "" smd roundrect
			(at -0.5 -0.5 90)
			(size 0.8 0.8)
			(layers "F.Paste")
			(roundrect_rratio 0.238095)
		)
		(pad "" smd roundrect
			(at -0.5 0.5 90)
			(size 0.8 0.8)
			(layers "F.Paste")
			(roundrect_rratio 0.238095)
		)
		(pad "" smd roundrect
			(at 0.5 -0.5 90)
			(size 0.8 0.8)
			(layers "F.Paste")
			(roundrect_rratio 0.238095)
		)
		(pad "" smd roundrect
			(at 0.5 0.5 90)
			(size 0.8 0.8)
			(layers "F.Paste")
			(roundrect_rratio 0.238095)
		)
		(pad "1" smd roundrect
			(at -1.938 -1.25 90)
			(size 0.825 0.28)
			(layers "F.Cu" "F.Mask" "F.Paste")
			(roundrect_rratio 0.25)
			(net 62 "USB_OTG_ID")
			(pinfunction "ID")
			(pintype "input")
		)
		(pad "2" smd roundrect
			(at -1.938 -0.75 90)
			(size 0.825 0.28)
			(layers "F.Cu" "F.Mask" "F.Paste")
			(roundrect_rratio 0.25)
			(net 221 "VBUS")
			(pinfunction "VBUS")
			(pintype "bidirectional")
		)
		(pad "3" smd roundrect
			(at -1.938 -0.25 90)
			(size 0.825 0.28)
			(layers "F.Cu" "F.Mask" "F.Paste")
			(roundrect_rratio 0.25)
			(net 50 "+3V3")
			(pinfunction "VBAT")
			(pintype "power_in")
		)
		(pad "4" smd roundrect
			(at -1.938 0.248 90)
			(size 0.825 0.28)
			(layers "F.Cu" "F.Mask" "F.Paste")
			(roundrect_rratio 0.25)
			(net 153 "/USB/VDD33")
			(pinfunction "VDD33")
			(pintype "power_out")
		)
		(pad "5" smd roundrect
			(at -1.938 0.748 90)
			(size 0.825 0.28)
			(layers "F.Cu" "F.Mask" "F.Paste")
			(roundrect_rratio 0.25)
			(net 498 "/USB/USB_N")
			(pinfunction "D_N")
			(pintype "bidirectional")
		)
		(pad "6" smd roundrect
			(at -1.938 1.249 90)
			(size 0.825 0.28)
			(layers "F.Cu" "F.Mask" "F.Paste")
			(roundrect_rratio 0.25)
			(net 499 "/USB/USB_P")
			(pinfunction "D_P")
			(pintype "bidirectional")
		)
		(pad "7" smd roundrect
			(at -1.25 1.937 90)
			(size 0.28 0.825)
			(layers "F.Cu" "F.Mask" "F.Paste")
			(roundrect_rratio 0.25)
			(net 330 "Net-(U13-CPEN)")
			(pinfunction "CPEN")
			(pintype "output")
		)
		(pad "8" smd roundrect
			(at -0.75 1.937 90)
			(size 0.28 0.825)
			(layers "F.Cu" "F.Mask" "F.Paste")
			(roundrect_rratio 0.25)
			(net 642 "/FPGA GPIO/ULPI.DATA7")
			(pinfunction "DATA7")
			(pintype "bidirectional")
		)
		(pad "9" smd roundrect
			(at -0.25 1.937 90)
			(size 0.28 0.825)
			(layers "F.Cu" "F.Mask" "F.Paste")
			(roundrect_rratio 0.25)
			(net 644 "/FPGA GPIO/ULPI.DATA6")
			(pinfunction "DATA6")
			(pintype "bidirectional")
		)
		(pad "10" smd roundrect
			(at 0.248 1.937 90)
			(size 0.28 0.825)
			(layers "F.Cu" "F.Mask" "F.Paste")
			(roundrect_rratio 0.25)
			(net 638 "/FPGA GPIO/ULPI.DATA5")
			(pinfunction "DATA5")
			(pintype "bidirectional")
		)
		(pad "11" smd roundrect
			(at 0.748 1.937 90)
			(size 0.28 0.825)
			(layers "F.Cu" "F.Mask" "F.Paste")
			(roundrect_rratio 0.25)
			(net 637 "/FPGA GPIO/ULPI.DATA4")
			(pinfunction "DATA4")
			(pintype "bidirectional")
		)
		(pad "12" smd roundrect
			(at 1.249 1.937 90)
			(size 0.28 0.825)
			(layers "F.Cu" "F.Mask" "F.Paste")
			(roundrect_rratio 0.25)
			(net 279 "Net-(U13-CLKOUT)")
			(pinfunction "CLKOUT")
			(pintype "output")
		)
		(pad "13" smd roundrect
			(at 1.937 1.249 90)
			(size 0.825 0.28)
			(layers "F.Cu" "F.Mask" "F.Paste")
			(roundrect_rratio 0.25)
			(net 643 "/FPGA GPIO/ULPI.DATA3")
			(pinfunction "DATA3")
			(pintype "bidirectional")
		)
		(pad "14" smd roundrect
			(at 1.937 0.748 90)
			(size 0.825 0.28)
			(layers "F.Cu" "F.Mask" "F.Paste")
			(roundrect_rratio 0.25)
			(net 645 "/FPGA GPIO/ULPI.DATA2")
			(pinfunction "DATA2")
			(pintype "bidirectional")
		)
		(pad "15" smd roundrect
			(at 1.937 0.248 90)
			(size 0.825 0.28)
			(layers "F.Cu" "F.Mask" "F.Paste")
			(roundrect_rratio 0.25)
			(net 639 "/FPGA GPIO/ULPI.DATA1")
			(pinfunction "DATA1")
			(pintype "bidirectional")
		)
		(pad "16" smd roundrect
			(at 1.937 -0.25 90)
			(size 0.825 0.28)
			(layers "F.Cu" "F.Mask" "F.Paste")
			(roundrect_rratio 0.25)
			(net 641 "/FPGA GPIO/ULPI.DATA0")
			(pinfunction "DATA0")
			(pintype "bidirectional")
		)
		(pad "17" smd roundrect
			(at 1.937 -0.75 90)
			(size 0.825 0.28)
			(layers "F.Cu" "F.Mask" "F.Paste")
			(roundrect_rratio 0.25)
			(net 152 "/USB/VDDIO")
			(pinfunction "VDDIO")
			(pintype "power_in")
		)
		(pad "18" smd roundrect
			(at 1.937 -1.25 90)
			(size 0.825 0.28)
			(layers "F.Cu" "F.Mask" "F.Paste")
			(roundrect_rratio 0.25)
			(net 647 "/FPGA GPIO/ULPI.NXT")
			(pinfunction "NXT")
			(pintype "output")
		)
		(pad "19" smd roundrect
			(at 1.249 -1.938 90)
			(size 0.28 0.825)
			(layers "F.Cu" "F.Mask" "F.Paste")
			(roundrect_rratio 0.25)
			(net 640 "/FPGA GPIO/ULPI.DIR")
			(pinfunction "DIR")
			(pintype "output")
		)
		(pad "20" smd roundrect
			(at 0.748 -1.938 90)
			(size 0.28 0.825)
			(layers "F.Cu" "F.Mask" "F.Paste")
			(roundrect_rratio 0.25)
			(net 646 "/FPGA GPIO/ULPI.STP")
			(pinfunction "STP")
			(pintype "input")
		)
		(pad "21" smd roundrect
			(at 0.248 -1.938 90)
			(size 0.28 0.825)
			(layers "F.Cu" "F.Mask" "F.Paste")
			(roundrect_rratio 0.25)
			(net 48 "+1V8")
			(pinfunction "VDD18")
			(pintype "power_out")
		)
		(pad "22" smd roundrect
			(at -0.25 -1.938 90)
			(size 0.28 0.825)
			(layers "F.Cu" "F.Mask" "F.Paste")
			(roundrect_rratio 0.25)
			(net 379 "/USB/RESETB")
			(pinfunction "RESETB")
			(pintype "input")
		)
		(pad "23" smd roundrect
			(at -0.75 -1.938 90)
			(size 0.28 0.825)
			(layers "F.Cu" "F.Mask" "F.Paste")
			(roundrect_rratio 0.25)
			(net 500 "/USB/REF_CLK")
			(pinfunction "REFCLK")
			(pintype "input")
		)
		(pad "24" smd roundrect
			(at -1.25 -1.938 90)
			(size 0.28 0.825)
			(layers "F.Cu" "F.Mask" "F.Paste")
			(roundrect_rratio 0.25)
			(net 280 "Net-(U13-RBIAS)")
			(pinfunction "RBIAS")
			(pintype "passive")
		)
		(pad "25" smd rect
			(at 0 0 90)
			(size 2.5 2.5)
			(layers "F.Cu" "F.Mask")
			(net 417 "GND")
			(pinfunction "GND")
			(pintype "power_in")
		)
	)
	(footprint "antmicro-footprints:TP_SMD_0.75mm"
		(layer "F.Cu")
		(at 227.2 147.18)
		(property "Reference" "TP27"
			(at 10.4 2.57 0)
			(layer "F.SilkS")
			(hide yes)
			(effects
				(font
					(size 0.7 0.7)
					(thickness 0.15)
				)
				(justify left bottom)
			)
		)
		(property "Value" "TP_0.75mm_SMD"
			(at 0 1.2 0)
			(layer "F.Fab")
			(hide yes)
			(effects
				(font
					(size 0.7 0.7)
					(thickness 0.15)
				)
				(justify left bottom)
			)
		)
		(property "Description" "SMT test point"
			(at 0 0 0)
			(layer "F.Fab")
			(hide yes)
			(effects
				(font
					(size 1.27 1.27)
					(thickness 0.15)
				)
			)
		)
		(property "Author" "Antmicro"
			(at 0 0 0)
			(layer "F.Fab")
			(hide yes)
			(effects
				(font
					(size 1 1)
					(thickness 0.15)
				)
			)
		)
		(property "License" "Apache-2.0"
			(at 0 0 0)
			(layer "F.Fab")
			(hide yes)
			(effects
				(font
					(size 1 1)
					(thickness 0.15)
				)
			)
		)
		(property "MPN" ""
			(at 0 0 0)
			(layer "F.Fab")
			(hide yes)
			(effects
				(font
					(size 1 1)
					(thickness 0.15)
				)
			)
		)
		(property "Manufacturer" ""
			(at 0 0 0)
			(layer "F.Fab")
			(hide yes)
			(effects
				(font
					(size 1 1)
					(thickness 0.15)
				)
			)
		)
		(property "Public" "False"
			(at 0 0 0)
			(layer "F.Fab")
			(hide yes)
			(effects
				(font
					(size 1 1)
					(thickness 0.15)
				)
			)
		)
		(sheetname "/WiFi_Bluetooth/")
		(sheetfile "wifi_bt.kicad_sch")
		(attr exclude_from_pos_files exclude_from_bom)
		(fp_circle
			(center 0 0)
			(end 0.475 0)
			(stroke
				(width 0.05)
				(type default)
			)
			(fill no)
			(layer "F.CrtYd")
		)
		(fp_text user "Author: Antmicro"
			(at -0.4 3.901 0)
			(layer "F.Fab")
			(effects
				(font
					(size 0.7 0.7)
					(thickness 0.15)
				)
				(justify left bottom)
			)
		)
		(fp_text user "${REFERENCE}"
			(at -0.4 2.7 0)
			(layer "F.Fab")
			(effects
				(font
					(size 0.7 0.7)
					(thickness 0.15)
				)
				(justify left bottom)
			)
		)
		(fp_text user "License: Apache-2.0"
			(at -0.4 5.101 0)
			(layer "F.Fab")
			(effects
				(font
					(size 0.7 0.7)
					(thickness 0.15)
				)
				(justify left bottom)
			)
		)
		(pad "1" smd circle
			(at 0 0)
			(size 0.75 0.75)
			(layers "F.Cu" "F.Mask")
			(net 524 "Net-(U26A-BT_DEV_WAKE)")
			(pinfunction "1")
			(pintype "passive")
		)
	)
	(footprint "antmicro-footprints:L_0805_2012Metric"
		(layer "F.Cu")
		(at 176.9 144.11 -90)
		(descr "Inductor  SMD 0805")
		(tags "inductor SMD 0805")
		(property "Reference" "L4"
			(at 2.596305 -0.675 0)
			(layer "F.SilkS")
			(effects
				(font
					(size 0.7 0.7)
					(thickness 0.15)
				)
				(justify right bottom)
			)
		)
		(property "Value" "L_1u_3.2A_0805"
			(at 0 1.947 90)
			(layer "F.Fab")
			(hide yes)
			(effects
				(font
					(size 0.7 0.7)
					(thickness 0.15)
				)
				(justify right bottom)
			)
		)
		(property "Datasheet" "https://abracon.com/datasheets/AOTA-B201208S.pdf"
			(at 0 0 270)
			(layer "F.Fab")
			(hide yes)
			(effects
				(font
					(size 1.27 1.27)
					(thickness 0.15)
				)
			)
		)
		(property "Description" "Power Inductor (SMT), 1 µH, 0.05 ohm, 3.2 A, AOTA-B201208S"
			(at 0 0 270)
			(layer "F.Fab")
			(hide yes)
			(effects
				(font
					(size 1.27 1.27)
					(thickness 0.15)
				)
			)
		)
		(property "Author" "Antmicro"
			(at 32.79 321.01 0)
			(layer "F.Fab")
			(hide yes)
			(effects
				(font
					(size 1 1)
					(thickness 0.15)
				)
			)
		)
		(property "IMax" "3.2 A"
			(at 32.79 321.01 0)
			(layer "F.Fab")
			(hide yes)
			(effects
				(font
					(size 1 1)
					(thickness 0.15)
				)
			)
		)
		(property "ISat" "3.5 A"
			(at 32.79 321.01 0)
			(layer "F.Fab")
			(hide yes)
			(effects
				(font
					(size 1 1)
					(thickness 0.15)
				)
			)
		)
		(property "License" "Apache-2.0"
			(at 32.79 321.01 0)
			(layer "F.Fab")
			(hide yes)
			(effects
				(font
					(size 1 1)
					(thickness 0.15)
				)
			)
		)
		(property "MPN" "AOTA-B201208S1R0MT "
			(at 32.79 321.01 0)
			(layer "F.Fab")
			(hide yes)
			(effects
				(font
					(size 1 1)
					(thickness 0.15)
				)
			)
		)
		(property "Manufacturer" "Abracon"
			(at 32.79 321.01 0)
			(layer "F.Fab")
			(hide yes)
			(effects
				(font
					(size 1 1)
					(thickness 0.15)
				)
			)
		)
		(property "Public" ""
			(at 32.79 321.01 0)
			(layer "F.Fab")
			(hide yes)
			(effects
				(font
					(size 1 1)
					(thickness 0.15)
				)
			)
		)
		(property "Size" "2x1.2"
			(at 32.79 321.01 0)
			(layer "F.Fab")
			(hide yes)
			(effects
				(font
					(size 1 1)
					(thickness 0.15)
				)
			)
		)
		(property "Val" "1u/3.2A"
			(at 32.79 321.01 0)
			(layer "F.Fab")
			(hide yes)
			(effects
				(font
					(size 1 1)
					(thickness 0.15)
				)
			)
		)
		(sheetname "/Supply/")
		(sheetfile "supply.kicad_sch")
		(attr smd)
		(fp_line
			(start -0.3 0.7)
			(end 0.3 0.7)
			(stroke
				(width 0.15)
				(type solid)
			)
			(layer "F.SilkS")
		)
		(fp_line
			(start -0.3 -0.7)
			(end 0.3 -0.7)
			(stroke
				(width 0.15)
				(type solid)
			)
			(layer "F.SilkS")
		)
		(fp_rect
			(start 1.95 -0.9)
			(end -1.95 0.9)
			(stroke
				(width 0.05)
				(type default)
			)
			(fill no)
			(layer "F.CrtYd")
		)
		(fp_rect
			(start -0.95 -0.675)
			(end 0.95 0.675)
			(stroke
				(width 0.15)
				(type solid)
			)
			(fill no)
			(layer "F.Fab")
		)
		(fp_text user "License: Apache-2.0"
			(at -1.9 4.947 270)
			(layer "F.Fab")
			(effects
				(font
					(size 0.7 0.7)
					(thickness 0.15)
				)
				(justify left bottom)
			)
		)
		(fp_text user "${REFERENCE}"
			(at -1.9 3.947 270)
			(layer "F.Fab")
			(effects
				(font
					(size 0.7 0.7)
					(thickness 0.15)
				)
				(justify left bottom)
			)
		)
		(fp_text user "Author: Antmicro"
			(at -1.9 5.947 270)
			(layer "F.Fab")
			(effects
				(font
					(size 0.7 0.7)
					(thickness 0.15)
				)
				(justify left bottom)
			)
		)
		(pad "1" smd roundrect
			(at -1.1 0 270)
			(size 1.2 1.3)
			(layers "F.Cu" "F.Mask" "F.Paste")
			(roundrect_rratio 0.25)
			(net 181 "Net-(U7-SW3)")
			(pintype "passive")
		)
		(pad "2" smd roundrect
			(at 1.1 0 270)
			(size 1.2 1.3)
			(layers "F.Cu" "F.Mask" "F.Paste")
			(roundrect_rratio 0.25)
			(net 406 "/Supply/SENSE2_P")
			(pintype "passive")
		)
	)
	(footprint "antmicro-footprints:UQFN-10_1.4x1.8x0.5mm_P0.4mm"
		(layer "F.Cu")
		(at 212.533 153.0715)
		(property "Reference" "U22"
			(at 1.527 -0.4115 90)
			(layer "F.SilkS")
			(effects
				(font
					(size 0.7 0.7)
					(thickness 0.15)
				)
				(justify left bottom)
			)
		)
		(property "Value" "PI3USB102GZLEX"
			(at 0 2.4 0)
			(layer "F.Fab")
			(hide yes)
			(effects
				(font
					(size 0.7 0.7)
					(thickness 0.15)
				)
				(justify left bottom)
			)
		)
		(property "Datasheet" "https://www.diodes.com/assets/Datasheets/PI3USB102G.pdf"
			(at 0 0 0)
			(layer "F.Fab")
			(hide yes)
			(effects
				(font
					(size 1.27 1.27)
					(thickness 0.15)
				)
			)
		)
		(property "Description" "USB Switch IC 1 Channel 10-TQFN (1.3x1.6)"
			(at 0 0 0)
			(layer "F.Fab")
			(hide yes)
			(effects
				(font
					(size 1.27 1.27)
					(thickness 0.15)
				)
			)
		)
		(property "Author" "Antmicro"
			(at 0 0 0)
			(layer "F.Fab")
			(hide yes)
			(effects
				(font
					(size 1 1)
					(thickness 0.15)
				)
			)
		)
		(property "License" "Apache-2.0"
			(at 0 0 0)
			(layer "F.Fab")
			(hide yes)
			(effects
				(font
					(size 1 1)
					(thickness 0.15)
				)
			)
		)
		(property "MPN" "PI3USB102GZLEX"
			(at 0 0 0)
			(layer "F.Fab")
			(hide yes)
			(effects
				(font
					(size 1 1)
					(thickness 0.15)
				)
			)
		)
		(property "Manufacturer" "Diodes Incorporated"
			(at 0 0 0)
			(layer "F.Fab")
			(hide yes)
			(effects
				(font
					(size 1 1)
					(thickness 0.15)
				)
			)
		)
		(property ki_fp_filters "MSOP*3x3mm*P0.5mm*")
		(sheetname "/USB/")
		(sheetfile "usb.kicad_sch")
		(attr smd)
		(fp_line
			(start -0.7305 -0.552)
			(end -1.2005 -0.552)
			(stroke
				(width 0.15)
				(type solid)
			)
			(layer "F.SilkS")
		)
		(fp_line
			(start -0.7305 -0.552)
			(end -0.7305 -0.93)
			(stroke
				(width 0.15)
				(type solid)
			)
			(layer "F.SilkS")
		)
		(fp_circle
			(center -1.0515 -1.151)
			(end -0.9805 -1.151)
			(stroke
				(width 0.15)
				(type solid)
			)
			(fill no)
			(layer "F.SilkS")
		)
		(fp_rect
			(start -1.3 -1.5)
			(end 1.3 1.5)
			(stroke
				(width 0.05)
				(type solid)
			)
			(fill no)
			(layer "F.CrtYd")
		)
		(fp_line
			(start -0.7 -0.4)
			(end -0.175 -0.925)
			(stroke
				(width 0.15)
				(type solid)
			)
			(layer "F.Fab")
		)
		(fp_line
			(start -0.7 0.93)
			(end -0.7 -0.4)
			(stroke
				(width 0.15)
				(type solid)
			)
			(layer "F.Fab")
		)
		(fp_line
			(start -0.175 -0.925)
			(end 0.7295 -0.925)
			(stroke
				(width 0.15)
				(type solid)
			)
			(layer "F.Fab")
		)
		(fp_line
			(start 0.725 0.93)
			(end -0.7 0.93)
			(stroke
				(width 0.15)
				(type solid)
			)
			(layer "F.Fab")
		)
		(fp_line
			(start 0.7295 -0.925)
			(end 0.725 0.93)
			(stroke
				(width 0.15)
				(type solid)
			)
			(layer "F.Fab")
		)
		(fp_text user "License: Apache-2.0"
			(at -0.657 6.9 0)
			(layer "F.Fab")
			(effects
				(font
					(size 0.7 0.7)
					(thickness 0.15)
				)
				(justify left bottom)
			)
		)
		(fp_text user "${REFERENCE}"
			(at -0.657 4.498 0)
			(layer "F.Fab")
			(effects
				(font
					(size 0.7 0.7)
					(thickness 0.15)
				)
				(justify left bottom)
			)
		)
		(fp_text user "Author: Antmicro"
			(at -0.657 5.7 0)
			(layer "F.Fab")
			(effects
				(font
					(size 0.7 0.7)
					(thickness 0.15)
				)
				(justify left bottom)
			)
		)
		(pad "1" smd roundrect
			(at -0.6445 -0.2)
			(size 0.81 0.22)
			(layers "F.Cu" "F.Mask" "F.Paste")
			(roundrect_rratio 0.25)
			(net 16 "/Bottom Connector/CONN.D_P")
			(pinfunction "D+")
			(pintype "bidirectional")
		)
		(pad "2" smd roundrect
			(at -0.6445 0.2)
			(size 0.81 0.22)
			(layers "F.Cu" "F.Mask" "F.Paste")
			(roundrect_rratio 0.25)
			(net 15 "/Bottom Connector/CONN.D_N")
			(pinfunction "D-")
			(pintype "bidirectional")
		)
		(pad "3" smd roundrect
			(at -0.4015 0.844 270)
			(size 0.81 0.22)
			(layers "F.Cu" "F.Mask" "F.Paste")
			(roundrect_rratio 0.25)
			(net 417 "GND")
			(pinfunction "GND")
			(pintype "power_in")
		)
		(pad "4" smd roundrect
			(at 0.0005 0.844 270)
			(size 0.81 0.22)
			(layers "F.Cu" "F.Mask" "F.Paste")
			(roundrect_rratio 0.25)
			(net 514 "/USB/USB_DN1_N")
			(pinfunction "D1-")
			(pintype "bidirectional")
		)
		(pad "5" smd roundrect
			(at 0.3995 0.844 270)
			(size 0.81 0.22)
			(layers "F.Cu" "F.Mask" "F.Paste")
			(roundrect_rratio 0.25)
			(net 515 "/USB/USB_DN1_P")
			(pinfunction "D1+")
			(pintype "bidirectional")
		)
		(pad "6" smd roundrect
			(at 0.6455 0.2)
			(size 0.81 0.22)
			(layers "F.Cu" "F.Mask" "F.Paste")
			(roundrect_rratio 0.25)
			(net 510 "/USB/USB_BYP_N")
			(pinfunction "D2-")
			(pintype "bidirectional")
		)
		(pad "7" smd roundrect
			(at 0.6455 -0.2)
			(size 0.81 0.22)
			(layers "F.Cu" "F.Mask" "F.Paste")
			(roundrect_rratio 0.25)
			(net 511 "/USB/USB_BYP_P")
			(pinfunction "D2+")
			(pintype "bidirectional")
		)
		(pad "8" smd roundrect
			(at 0.3995 -0.847 270)
			(size 0.81 0.22)
			(layers "F.Cu" "F.Mask" "F.Paste")
			(roundrect_rratio 0.25)
			(net 417 "GND")
			(pinfunction "~{OE}")
			(pintype "input")
		)
		(pad "9" smd roundrect
			(at 0.0005 -0.847 270)
			(size 0.81 0.22)
			(layers "F.Cu" "F.Mask" "F.Paste")
			(roundrect_rratio 0.25)
			(net 50 "+3V3")
			(pinfunction "V_{DD}")
			(pintype "power_in")
		)
		(pad "10" smd roundrect
			(at -0.4015 -0.847 270)
			(size 0.81 0.22)
			(layers "F.Cu" "F.Mask" "F.Paste")
			(roundrect_rratio 0.25)
			(net 62 "USB_OTG_ID")
			(pinfunction "SEL")
			(pintype "input")
		)
	)
	(footprint "antmicro-footprints:C_0402_1005Metric"
		(layer "F.Cu")
		(at 175.475 142.9675 -90)
		(descr "Capacitor SMD 0402")
		(tags "capacitor SMD 0402")
		(property "Reference" "C102"
			(at 0.8825 -0.465 90)
			(layer "F.SilkS")
			(effects
				(font
					(size 0.7 0.7)
					(thickness 0.15)
				)
				(justify right bottom)
			)
		)
		(property "Value" "C_22u_0402"
			(at -1.022927 2.155213 90)
			(layer "F.Fab")
			(hide yes)
			(effects
				(font
					(size 0.7 0.7)
					(thickness 0.15)
				)
				(justify right bottom)
			)
		)
		(property "Datasheet" "https://www.murata.com/products/productdetail?partno=GRM158R60J226ME01%23"
			(at 0 0 270)
			(layer "F.Fab")
			(hide yes)
			(effects
				(font
					(size 1.27 1.27)
					(thickness 0.15)
				)
			)
		)
		(property "Description" "SMD Multilayer Ceramic Capacitor, 22 uF, 4 V, 0402 [1005 Metric], X6S"
			(at 0 0 270)
			(layer "F.Fab")
			(hide yes)
			(effects
				(font
					(size 1.27 1.27)
					(thickness 0.15)
				)
			)
		)
		(property "Author" "Antmicro"
			(at 32.5075 318.4425 0)
			(layer "F.Fab")
			(hide yes)
			(effects
				(font
					(size 1 1)
					(thickness 0.15)
				)
			)
		)
		(property "Dielectric" ""
			(at 32.5075 318.4425 0)
			(layer "F.Fab")
			(hide yes)
			(effects
				(font
					(size 1 1)
					(thickness 0.15)
				)
			)
		)
		(property "License" "Apache-2.0"
			(at 32.5075 318.4425 0)
			(layer "F.Fab")
			(hide yes)
			(effects
				(font
					(size 1 1)
					(thickness 0.15)
				)
			)
		)
		(property "MPN" "GRM158R60J226ME01D"
			(at 32.5075 318.4425 0)
			(layer "F.Fab")
			(hide yes)
			(effects
				(font
					(size 1 1)
					(thickness 0.15)
				)
			)
		)
		(property "Manufacturer" "Murata"
			(at 32.5075 318.4425 0)
			(layer "F.Fab")
			(hide yes)
			(effects
				(font
					(size 1 1)
					(thickness 0.15)
				)
			)
		)
		(property "Public" ""
			(at 32.5075 318.4425 0)
			(layer "F.Fab")
			(hide yes)
			(effects
				(font
					(size 1 1)
					(thickness 0.15)
				)
			)
		)
		(property "Val" "22u"
			(at 32.5075 318.4425 0)
			(layer "F.Fab")
			(hide yes)
			(effects
				(font
					(size 1 1)
					(thickness 0.15)
				)
			)
		)
		(property "Voltage" ""
			(at 32.5075 318.4425 0)
			(layer "F.Fab")
			(hide yes)
			(effects
				(font
					(size 1 1)
					(thickness 0.15)
				)
			)
		)
		(sheetname "/Supply/")
		(sheetfile "supply.kicad_sch")
		(attr smd)
		(fp_rect
			(start -0.925 -0.47)
			(end 0.925 0.47)
			(stroke
				(width 0.05)
				(type default)
			)
			(fill no)
			(layer "F.CrtYd")
		)
		(fp_line
			(start -0.494 0.248)
			(end -0.494 -0.25)
			(stroke
				(width 0.15)
				(type solid)
			)
			(layer "F.Fab")
		)
		(fp_line
			(start 0.504 0.248)
			(end -0.494 0.248)
			(stroke
				(width 0.15)
				(type solid)
			)
			(layer "F.Fab")
		)
		(fp_line
			(start -0.494 -0.25)
			(end 0.504 -0.25)
			(stroke
				(width 0.15)
				(type solid)
			)
			(layer "F.Fab")
		)
		(fp_line
			(start 0.504 -0.25)
			(end 0.504 0.248)
			(stroke
				(width 0.15)
				(type solid)
			)
			(layer "F.Fab")
		)
		(fp_text user "License: Apache-2.0"
			(at -0.939 5.799 270)
			(layer "F.Fab")
			(effects
				(font
					(size 0.7 0.7)
					(thickness 0.15)
				)
				(justify left bottom)
			)
		)
		(fp_text user "${REFERENCE}"
			(at -0.939 4.599 270)
			(layer "F.Fab")
			(effects
				(font
					(size 0.7 0.7)
					(thickness 0.15)
				)
				(justify left bottom)
			)
		)
		(fp_text user "Author: Antmicro"
			(at -0.939 3.399 270)
			(layer "F.Fab")
			(effects
				(font
					(size 0.7 0.7)
					(thickness 0.15)
				)
				(justify left bottom)
			)
		)
		(pad "1" smd roundrect
			(at -0.48 0 270)
			(size 0.59 0.64)
			(layers "F.Cu" "F.Mask" "F.Paste")
			(roundrect_rratio 0.25)
			(net 417 "GND")
			(pintype "passive")
		)
		(pad "2" smd roundrect
			(at 0.48 0 270)
			(size 0.59 0.64)
			(layers "F.Cu" "F.Mask" "F.Paste")
			(roundrect_rratio 0.25)
			(net 406 "/Supply/SENSE2_P")
			(pintype "passive")
		)
	)
	(footprint "antmicro-footprints:C_0402_1005Metric"
		(layer "F.Cu")
		(at 187.684904 147.897281 -90)
		(descr "Capacitor SMD 0402")
		(tags "capacitor SMD 0402")
		(property "Reference" "C105"
			(at 3.06272 -5.315096 180)
			(layer "F.SilkS")
			(effects
				(font
					(size 0.7 0.7)
					(thickness 0.15)
				)
				(justify right bottom)
			)
		)
		(property "Value" "C_22u_0402"
			(at -1.022927 2.155213 90)
			(layer "F.Fab")
			(hide yes)
			(effects
				(font
					(size 0.7 0.7)
					(thickness 0.15)
				)
				(justify right bottom)
			)
		)
		(property "Datasheet" "https://www.murata.com/products/productdetail?partno=GRM158R60J226ME01%23"
			(at 0 0 270)
			(layer "F.Fab")
			(hide yes)
			(effects
				(font
					(size 1.27 1.27)
					(thickness 0.15)
				)
			)
		)
		(property "Description" "SMD Multilayer Ceramic Capacitor, 22 uF, 4 V, 0402 [1005 Metric], X6S"
			(at 0 0 270)
			(layer "F.Fab")
			(hide yes)
			(effects
				(font
					(size 1.27 1.27)
					(thickness 0.15)
				)
			)
		)
		(property "Author" "Antmicro"
			(at 39.787623 335.582185 0)
			(layer "F.Fab")
			(hide yes)
			(effects
				(font
					(size 1 1)
					(thickness 0.15)
				)
			)
		)
		(property "Dielectric" ""
			(at 39.787623 335.582185 0)
			(layer "F.Fab")
			(hide yes)
			(effects
				(font
					(size 1 1)
					(thickness 0.15)
				)
			)
		)
		(property "License" "Apache-2.0"
			(at 39.787623 335.582185 0)
			(layer "F.Fab")
			(hide yes)
			(effects
				(font
					(size 1 1)
					(thickness 0.15)
				)
			)
		)
		(property "MPN" "GRM158R60J226ME01D"
			(at 39.787623 335.582185 0)
			(layer "F.Fab")
			(hide yes)
			(effects
				(font
					(size 1 1)
					(thickness 0.15)
				)
			)
		)
		(property "Manufacturer" "Murata"
			(at 39.787623 335.582185 0)
			(layer "F.Fab")
			(hide yes)
			(effects
				(font
					(size 1 1)
					(thickness 0.15)
				)
			)
		)
		(property "Public" ""
			(at 39.787623 335.582185 0)
			(layer "F.Fab")
			(hide yes)
			(effects
				(font
					(size 1 1)
					(thickness 0.15)
				)
			)
		)
		(property "Val" "22u"
			(at 39.787623 335.582185 0)
			(layer "F.Fab")
			(hide yes)
			(effects
				(font
					(size 1 1)
					(thickness 0.15)
				)
			)
		)
		(property "Voltage" ""
			(at 39.787623 335.582185 0)
			(layer "F.Fab")
			(hide yes)
			(effects
				(font
					(size 1 1)
					(thickness 0.15)
				)
			)
		)
		(sheetname "/Supply/")
		(sheetfile "supply.kicad_sch")
		(attr smd)
		(fp_rect
			(start -0.925 -0.47)
			(end 0.925 0.47)
			(stroke
				(width 0.05)
				(type default)
			)
			(fill no)
			(layer "F.CrtYd")
		)
		(fp_line
			(start -0.494 0.248)
			(end -0.494 -0.25)
			(stroke
				(width 0.15)
				(type solid)
			)
			(layer "F.Fab")
		)
		(fp_line
			(start 0.504 0.248)
			(end -0.494 0.248)
			(stroke
				(width 0.15)
				(type solid)
			)
			(layer "F.Fab")
		)
		(fp_line
			(start -0.494 -0.25)
			(end 0.504 -0.25)
			(stroke
				(width 0.15)
				(type solid)
			)
			(layer "F.Fab")
		)
		(fp_line
			(start 0.504 -0.25)
			(end 0.504 0.248)
			(stroke
				(width 0.15)
				(type solid)
			)
			(layer "F.Fab")
		)
		(fp_text user "Author: Antmicro"
			(at -0.939 3.399 270)
			(layer "F.Fab")
			(effects
				(font
					(size 0.7 0.7)
					(thickness 0.15)
				)
				(justify left bottom)
			)
		)
		(fp_text user "${REFERENCE}"
			(at -0.939 4.599 270)
			(layer "F.Fab")
			(effects
				(font
					(size 0.7 0.7)
					(thickness 0.15)
				)
				(justify left bottom)
			)
		)
		(fp_text user "License: Apache-2.0"
			(at -0.939 5.799 270)
			(layer "F.Fab")
			(effects
				(font
					(size 0.7 0.7)
					(thickness 0.15)
				)
				(justify left bottom)
			)
		)
		(pad "1" smd roundrect
			(at -0.48 0 270)
			(size 0.59 0.64)
			(layers "F.Cu" "F.Mask" "F.Paste")
			(roundrect_rratio 0.25)
			(net 417 "GND")
			(pintype "passive")
		)
		(pad "2" smd roundrect
			(at 0.48 0 270)
			(size 0.59 0.64)
			(layers "F.Cu" "F.Mask" "F.Paste")
			(roundrect_rratio 0.25)
			(net 522 "/Supply/1V05_REG")
			(pintype "passive")
		)
	)
	(footprint "antmicro-footprints:Coax_Conn_U.FL"
		(layer "F.Cu")
		(at 226.9 137.208)
		(descr "https://media.digikey.com/pdf/Data%20Sheets/Hirose%20PDFs/UFL%20Series.pdf")
		(property "Reference" "J3"
			(at 0.84 -2.138 0)
			(layer "F.SilkS")
			(effects
				(font
					(size 0.7 0.7)
					(thickness 0.15)
				)
				(justify left bottom)
			)
		)
		(property "Value" "U_FL-R-SMT-1"
			(at -4.13 2.52 0)
			(layer "F.Fab")
			(hide yes)
			(effects
				(font
					(size 0.7 0.7)
					(thickness 0.15)
				)
				(justify left bottom)
			)
		)
		(property "Datasheet" "https://media.digikey.com/pdf/Data%20Sheets/Hirose%20PDFs/UFL%20Series.pdf"
			(at 0 0 0)
			(layer "F.Fab")
			(hide yes)
			(effects
				(font
					(size 1.27 1.27)
					(thickness 0.15)
				)
			)
		)
		(property "Description" "U.FL (UMCC) Connector Receptacle, Male Pin 50Ohm Surface Mount Solder"
			(at 0 0 0)
			(layer "F.Fab")
			(hide yes)
			(effects
				(font
					(size 1.27 1.27)
					(thickness 0.15)
				)
			)
		)
		(property "Author" "Antmicro"
			(at 0 0 0)
			(layer "F.Fab")
			(hide yes)
			(effects
				(font
					(size 1 1)
					(thickness 0.15)
				)
			)
		)
		(property "License" "Apache-2.0"
			(at 0 0 0)
			(layer "F.Fab")
			(hide yes)
			(effects
				(font
					(size 1 1)
					(thickness 0.15)
				)
			)
		)
		(property "MPN" "U.FL-R-SMT-1(10)"
			(at 0 0 0)
			(layer "F.Fab")
			(hide yes)
			(effects
				(font
					(size 1 1)
					(thickness 0.15)
				)
			)
		)
		(property "Manufacturer" "Hirose Electric"
			(at 0 0 0)
			(layer "F.Fab")
			(hide yes)
			(effects
				(font
					(size 1 1)
					(thickness 0.15)
				)
			)
		)
		(sheetname "/WiFi_Bluetooth/")
		(sheetfile "wifi_bt.kicad_sch")
		(attr smd)
		(fp_line
			(start -1.613 -1.651)
			(end -1.613 -1.325)
			(stroke
				(width 0.15)
				(type solid)
			)
			(layer "F.SilkS")
		)
		(fp_line
			(start -1.613 -1.651)
			(end -1.113 -1.651)
			(stroke
				(width 0.15)
				(type solid)
			)
			(layer "F.SilkS")
		)
		(fp_line
			(start -1.613 1.648)
			(end -1.613 1.325)
			(stroke
				(width 0.15)
				(type solid)
			)
			(layer "F.SilkS")
		)
		(fp_line
			(start -1.613 1.648)
			(end -1.113 1.648)
			(stroke
				(width 0.15)
				(type solid)
			)
			(layer "F.SilkS")
		)
		(fp_line
			(start 1.588 -1.651)
			(end 1.088 -1.651)
			(stroke
				(width 0.15)
				(type solid)
			)
			(layer "F.SilkS")
		)
		(fp_line
			(start 1.588 -1.651)
			(end 1.588 -1.325)
			(stroke
				(width 0.15)
				(type solid)
			)
			(layer "F.SilkS")
		)
		(fp_line
			(start 1.588 1.648)
			(end 1.088 1.648)
			(stroke
				(width 0.15)
				(type solid)
			)
			(layer "F.SilkS")
		)
		(fp_line
			(start 1.588 1.648)
			(end 1.588 1.325)
			(stroke
				(width 0.15)
				(type solid)
			)
			(layer "F.SilkS")
		)
		(fp_rect
			(start -2 -2.051)
			(end 1.999 2.05)
			(stroke
				(width 0.05)
				(type solid)
			)
			(fill no)
			(layer "F.CrtYd")
		)
		(fp_line
			(start -1.512 -1.551)
			(end 1.487 -1.551)
			(stroke
				(width 0.15)
				(type solid)
			)
			(layer "F.Fab")
		)
		(fp_line
			(start -1.512 1.55)
			(end -1.512 -1.551)
			(stroke
				(width 0.15)
				(type solid)
			)
			(layer "F.Fab")
		)
		(fp_line
			(start -1.512 1.55)
			(end 1.487 1.55)
			(stroke
				(width 0.15)
				(type solid)
			)
			(layer "F.Fab")
		)
		(fp_line
			(start 1.487 1.55)
			(end 1.487 -1.551)
			(stroke
				(width 0.15)
				(type solid)
			)
			(layer "F.Fab")
		)
		(fp_text user "${REFERENCE}"
			(at -4.13 6.92 0)
			(layer "F.Fab")
			(effects
				(font
					(size 0.7 0.7)
					(thickness 0.15)
				)
				(justify left bottom)
			)
		)
		(fp_text user "Author: Antmicro"
			(at -4.13 4.52 0)
			(layer "F.Fab")
			(effects
				(font
					(size 0.7 0.7)
					(thickness 0.15)
				)
				(justify left bottom)
			)
		)
		(fp_text user "License: Apache-2.0"
			(at -4.13 5.72 0)
			(layer "F.Fab")
			(effects
				(font
					(size 0.7 0.7)
					(thickness 0.15)
				)
				(justify left bottom)
			)
		)
		(pad "1" smd rect
			(at -0.012 1.499)
			(size 1 1.05)
			(layers "F.Cu" "F.Mask" "F.Paste")
			(net 178 "Net-(J3-Pad1)")
			(pintype "passive")
		)
		(pad "SH1" smd rect
			(at 1.463 0)
			(size 1.05 2.2)
			(layers "F.Cu" "F.Mask" "F.Paste")
			(net 417 "GND")
			(pintype "passive")
		)
		(pad "SH2" smd rect
			(at -1.488 0)
			(size 1.05 2.2)
			(layers "F.Cu" "F.Mask" "F.Paste")
			(net 417 "GND")
			(pintype "passive")
		)
		(zone
			(net 0)
			(net_name "")
			(layer "F.Cu")
			(hatch edge 0.508)
			(connect_pads
				(clearance 0)
			)
			(min_thickness 0.254)
			(filled_areas_thickness no)
			(keepout
				(tracks not_allowed)
				(vias not_allowed)
				(pads not_allowed)
				(copperpour not_allowed)
				(footprints not_allowed)
			)
			(placement
				(enabled no)
				(sheetname "")
			)
			(fill
				(thermal_gap 0.508)
				(thermal_bridge_width 0.508)
			)
			(polygon
				(pts
					(xy 227.83 138.168) (xy 225.95 138.168) (xy 225.95 136.108) (xy 227.83 136.108)
				)
			)
		)
	)
	(footprint "antmicro-footprints:FB_0402_1005Metric"
		(layer "F.Cu")
		(at 208.085 143.85)
		(descr "Ferrite Bead SMD 0402")
		(tags "ferrite bead SMD 0402")
		(property "Reference" "FB5"
			(at -8.085 10.465 90)
			(layer "F.SilkS")
			(effects
				(font
					(size 0.7 0.7)
					(thickness 0.15)
				)
				(justify left bottom)
			)
		)
		(property "Value" "FB_120Z_1.2A_TDK-MPZ_0402"
			(at 0 1.4 0)
			(layer "F.Fab")
			(hide yes)
			(effects
				(font
					(size 0.7 0.7)
					(thickness 0.15)
				)
				(justify left bottom)
			)
		)
		(property "Datasheet" "https://product.tdk.com/en/search/emc/emc/beads/info?part_no=MPZ1005S121CT000"
			(at 0 0 0)
			(layer "F.Fab")
			(hide yes)
			(effects
				(font
					(size 1.27 1.27)
					(thickness 0.15)
				)
			)
		)
		(property "Description" "Ferrite Bead, 0402 [1005 Metric], 120 ohm, 1.2A, MPZ, 0.06 ohm, ± 25%, DC Power line"
			(at 0 0 0)
			(layer "F.Fab")
			(hide yes)
			(effects
				(font
					(size 1.27 1.27)
					(thickness 0.15)
				)
			)
		)
		(property "Author" "Antmicro"
			(at 0 0 0)
			(layer "F.Fab")
			(hide yes)
			(effects
				(font
					(size 1 1)
					(thickness 0.15)
				)
			)
		)
		(property "Current" ""
			(at 0 0 0)
			(layer "F.Fab")
			(hide yes)
			(effects
				(font
					(size 1 1)
					(thickness 0.15)
				)
			)
		)
		(property "License" "Apache-2.0"
			(at 0 0 0)
			(layer "F.Fab")
			(hide yes)
			(effects
				(font
					(size 1 1)
					(thickness 0.15)
				)
			)
		)
		(property "MPN" "MPZ1005S121CT000"
			(at 0 0 0)
			(layer "F.Fab")
			(hide yes)
			(effects
				(font
					(size 1 1)
					(thickness 0.15)
				)
			)
		)
		(property "Manufacturer" "TDK"
			(at 0 0 0)
			(layer "F.Fab")
			(hide yes)
			(effects
				(font
					(size 1 1)
					(thickness 0.15)
				)
			)
		)
		(property "Public" ""
			(at 0 0 0)
			(layer "F.Fab")
			(hide yes)
			(effects
				(font
					(size 1 1)
					(thickness 0.15)
				)
			)
		)
		(property "Val" "120Z/1.2A"
			(at 0 0 0)
			(layer "F.Fab")
			(hide yes)
			(effects
				(font
					(size 1 1)
					(thickness 0.15)
				)
			)
		)
		(sheetname "/MIPI CrossLink/")
		(sheetfile "crosslink.kicad_sch")
		(attr smd)
		(fp_rect
			(start -0.925 -0.47)
			(end 0.925 0.47)
			(stroke
				(width 0.05)
				(type default)
			)
			(fill no)
			(layer "F.CrtYd")
		)
		(fp_rect
			(start -0.5 -0.25)
			(end 0.5 0.25)
			(stroke
				(width 0.15)
				(type solid)
			)
			(fill no)
			(layer "F.Fab")
		)
		(fp_text user "${REFERENCE}"
			(at -0.95 3.168 0)
			(layer "F.Fab")
			(effects
				(font
					(size 0.7 0.7)
					(thickness 0.15)
				)
				(justify left bottom)
			)
		)
		(fp_text user "License: Apache-2.0"
			(at -0.95 5.169 0)
			(layer "F.Fab")
			(effects
				(font
					(size 0.7 0.7)
					(thickness 0.15)
				)
				(justify left bottom)
			)
		)
		(fp_text user "Author: Antmicro"
			(at -0.95 4.169 0)
			(layer "F.Fab")
			(effects
				(font
					(size 0.7 0.7)
					(thickness 0.15)
				)
				(justify left bottom)
			)
		)
		(pad "1" smd roundrect
			(at -0.48 0)
			(size 0.59 0.64)
			(layers "F.Cu" "F.Mask" "F.Paste")
			(roundrect_rratio 0.25)
			(net 191 "/MIPI CrossLink/CL_VCCIO2")
			(pintype "passive")
		)
		(pad "2" smd roundrect
			(at 0.48 0)
			(size 0.59 0.64)
			(layers "F.Cu" "F.Mask" "F.Paste")
			(roundrect_rratio 0.25)
			(net 237 "1V8_CL")
			(pintype "passive")
		)
	)
	(footprint "antmicro-footprints:FB_0402_1005Metric"
		(layer "F.Cu")
		(at 208.085 150.72)
		(descr "Ferrite Bead SMD 0402")
		(tags "ferrite bead SMD 0402")
		(property "Reference" "FB10"
			(at -1.214999 3.595 90)
			(layer "F.SilkS")
			(effects
				(font
					(size 0.7 0.7)
					(thickness 0.15)
				)
				(justify left bottom)
			)
		)
		(property "Value" "FB_120Z_1.2A_TDK-MPZ_0402"
			(at 0 1.4 0)
			(layer "F.Fab")
			(hide yes)
			(effects
				(font
					(size 0.7 0.7)
					(thickness 0.15)
				)
				(justify left bottom)
			)
		)
		(property "Datasheet" "https://product.tdk.com/en/search/emc/emc/beads/info?part_no=MPZ1005S121CT000"
			(at 0 0 0)
			(layer "F.Fab")
			(hide yes)
			(effects
				(font
					(size 1.27 1.27)
					(thickness 0.15)
				)
			)
		)
		(property "Description" "Ferrite Bead, 0402 [1005 Metric], 120 ohm, 1.2A, MPZ, 0.06 ohm, ± 25%, DC Power line"
			(at 0 0 0)
			(layer "F.Fab")
			(hide yes)
			(effects
				(font
					(size 1.27 1.27)
					(thickness 0.15)
				)
			)
		)
		(property "Author" "Antmicro"
			(at 0 0 0)
			(layer "F.Fab")
			(hide yes)
			(effects
				(font
					(size 1 1)
					(thickness 0.15)
				)
			)
		)
		(property "Current" ""
			(at 0 0 0)
			(layer "F.Fab")
			(hide yes)
			(effects
				(font
					(size 1 1)
					(thickness 0.15)
				)
			)
		)
		(property "License" "Apache-2.0"
			(at 0 0 0)
			(layer "F.Fab")
			(hide yes)
			(effects
				(font
					(size 1 1)
					(thickness 0.15)
				)
			)
		)
		(property "MPN" "MPZ1005S121CT000"
			(at 0 0 0)
			(layer "F.Fab")
			(hide yes)
			(effects
				(font
					(size 1 1)
					(thickness 0.15)
				)
			)
		)
		(property "Manufacturer" "TDK"
			(at 0 0 0)
			(layer "F.Fab")
			(hide yes)
			(effects
				(font
					(size 1 1)
					(thickness 0.15)
				)
			)
		)
		(property "Public" ""
			(at 0 0 0)
			(layer "F.Fab")
			(hide yes)
			(effects
				(font
					(size 1 1)
					(thickness 0.15)
				)
			)
		)
		(property "Val" "120Z/1.2A"
			(at 0 0 0)
			(layer "F.Fab")
			(hide yes)
			(effects
				(font
					(size 1 1)
					(thickness 0.15)
				)
			)
		)
		(sheetname "/MIPI CrossLink/")
		(sheetfile "crosslink.kicad_sch")
		(attr smd)
		(fp_rect
			(start -0.925 -0.47)
			(end 0.925 0.47)
			(stroke
				(width 0.05)
				(type default)
			)
			(fill no)
			(layer "F.CrtYd")
		)
		(fp_rect
			(start -0.5 -0.25)
			(end 0.5 0.25)
			(stroke
				(width 0.15)
				(type solid)
			)
			(fill no)
			(layer "F.Fab")
		)
		(fp_text user "License: Apache-2.0"
			(at -0.95 5.169 0)
			(layer "F.Fab")
			(effects
				(font
					(size 0.7 0.7)
					(thickness 0.15)
				)
				(justify left bottom)
			)
		)
		(fp_text user "Author: Antmicro"
			(at -0.95 4.169 0)
			(layer "F.Fab")
			(effects
				(font
					(size 0.7 0.7)
					(thickness 0.15)
				)
				(justify left bottom)
			)
		)
		(fp_text user "${REFERENCE}"
			(at -0.95 3.168 0)
			(layer "F.Fab")
			(effects
				(font
					(size 0.7 0.7)
					(thickness 0.15)
				)
				(justify left bottom)
			)
		)
		(pad "1" smd roundrect
			(at -0.48 0)
			(size 0.59 0.64)
			(layers "F.Cu" "F.Mask" "F.Paste")
			(roundrect_rratio 0.25)
			(net 204 "/MIPI CrossLink/CL_VCCPLL_DPHY0")
			(pintype "passive")
		)
		(pad "2" smd roundrect
			(at 0.48 0)
			(size 0.59 0.64)
			(layers "F.Cu" "F.Mask" "F.Paste")
			(roundrect_rratio 0.25)
			(net 96 "+1V2")
			(pintype "passive")
		)
	)
	(footprint "antmicro-footprints:W-PDFN-8-1EP_8x6mm_P1.27mm_EP4.3x3.4mm"
		(layer "F.Cu")
		(at 224.22 129.37 90)
		(property "Reference" "U3"
			(at 4.07 -3.67 0)
			(layer "F.SilkS")
			(effects
				(font
					(size 0.7 0.7)
					(thickness 0.15)
				)
				(justify left bottom)
			)
		)
		(property "Value" "MT25QL01GBBB1EW9-0SIT"
			(at -0.005 3.653 90)
			(layer "F.Fab")
			(hide yes)
			(effects
				(font
					(size 0.7 0.7)
					(thickness 0.15)
				)
				(justify left bottom)
			)
		)
		(property "Datasheet" "https://www.mouser.com/datasheet/2/671/mict_s_a0002234966_1-2290738.pdf"
			(at 0 0 90)
			(layer "F.Fab")
			(hide yes)
			(effects
				(font
					(size 1.27 1.27)
					(thickness 0.15)
				)
			)
		)
		(property "Description" "NOR Flash Serial-SPI 3.3V 1G-bit 1G/512M/256M x 1/2-bit/4-bit 6ns 16-Pin SOP-II T/R"
			(at 0 0 90)
			(layer "F.Fab")
			(hide yes)
			(effects
				(font
					(size 1.27 1.27)
					(thickness 0.15)
				)
			)
		)
		(property "Author" "Antmicro"
			(at 353.59 -94.85 0)
			(layer "F.Fab")
			(hide yes)
			(effects
				(font
					(size 1 1)
					(thickness 0.15)
				)
			)
		)
		(property "License" "Apache-2.0"
			(at 353.59 -94.85 0)
			(layer "F.Fab")
			(hide yes)
			(effects
				(font
					(size 1 1)
					(thickness 0.15)
				)
			)
		)
		(property "MPN" "MT25QL01GBBB1EW9-0SIT"
			(at 353.59 -94.85 0)
			(layer "F.Fab")
			(hide yes)
			(effects
				(font
					(size 1 1)
					(thickness 0.15)
				)
			)
		)
		(property "Manufacturer" "Micron Technology"
			(at 353.59 -94.85 0)
			(layer "F.Fab")
			(hide yes)
			(effects
				(font
					(size 1 1)
					(thickness 0.15)
				)
			)
		)
		(property "VSD_class" "SPI Flash"
			(at 353.59 -94.85 0)
			(layer "F.Fab")
			(hide yes)
			(effects
				(font
					(size 1 1)
					(thickness 0.15)
				)
			)
		)
		(sheetname "/FPGA Config/")
		(sheetfile "fpga-config.kicad_sch")
		(attr smd)
		(fp_line
			(start -4.3 -2.997)
			(end 3.995 -2.997)
			(stroke
				(width 0.15)
				(type solid)
			)
			(layer "F.SilkS")
		)
		(fp_line
			(start -3.995 3.003)
			(end 3.995 3.003)
			(stroke
				(width 0.15)
				(type solid)
			)
			(layer "F.SilkS")
		)
		(fp_circle
			(center -4.4 -2.6)
			(end -4.35 -2.6)
			(stroke
				(width 0.15)
				(type solid)
			)
			(fill yes)
			(layer "F.SilkS")
		)
		(fp_rect
			(start -4.38 -3.25)
			(end 4.37 3.25)
			(stroke
				(width 0.05)
				(type solid)
			)
			(fill no)
			(layer "F.CrtYd")
		)
		(fp_text user "License: Apache-2.0"
			(at -4.73 6.853 90)
			(layer "F.Fab")
			(effects
				(font
					(size 0.7 0.7)
					(thickness 0.15)
				)
				(justify left bottom)
			)
		)
		(fp_text user "${REFERENCE}"
			(at -4.73 8.053 90)
			(layer "F.Fab")
			(effects
				(font
					(size 0.7 0.7)
					(thickness 0.15)
				)
				(justify left bottom)
			)
		)
		(fp_text user "Author: Antmicro"
			(at -4.73 5.653 90)
			(layer "F.Fab")
			(effects
				(font
					(size 0.7 0.7)
					(thickness 0.15)
				)
				(justify left bottom)
			)
		)
		(pad "" smd rect
			(at -1.03 -1.47)
			(size 0.8 0.8)
			(layers "F.Paste")
		)
		(pad "" smd rect
			(at -1.03 -0.47)
			(size 0.8 0.8)
			(layers "F.Paste")
		)
		(pad "" smd rect
			(at -1.03 0.53)
			(size 0.8 0.8)
			(layers "F.Paste")
		)
		(pad "" smd rect
			(at -1.03 1.53)
			(size 0.8 0.8)
			(layers "F.Paste")
		)
		(pad "" smd rect
			(at -0.03 -1.47)
			(size 0.8 0.8)
			(layers "F.Paste")
		)
		(pad "" smd rect
			(at -0.03 -0.47)
			(size 0.8 0.8)
			(layers "F.Paste")
		)
		(pad "" smd rect
			(at -0.03 0.53)
			(size 0.8 0.8)
			(layers "F.Paste")
		)
		(pad "" smd rect
			(at -0.03 1.53)
			(size 0.8 0.8)
			(layers "F.Paste")
		)
		(pad "" smd rect
			(at 0.97 -1.47)
			(size 0.8 0.8)
			(layers "F.Paste")
		)
		(pad "" smd rect
			(at 0.97 -0.47)
			(size 0.8 0.8)
			(layers "F.Paste")
		)
		(pad "" smd rect
			(at 0.97 0.53)
			(size 0.8 0.8)
			(layers "F.Paste")
		)
		(pad "" smd rect
			(at 0.97 1.53)
			(size 0.8 0.8)
			(layers "F.Paste")
		)
		(pad "1" smd roundrect
			(at -3.905 -1.9)
			(size 0.45 0.95)
			(layers "F.Cu" "F.Mask" "F.Paste")
			(roundrect_rratio 0.25)
			(net 288 "/FPGA Config/Flash.CS")
			(pinfunction "S#")
			(pintype "input")
		)
		(pad "2" smd roundrect
			(at -3.905 -0.63)
			(size 0.45 0.95)
			(layers "F.Cu" "F.Mask" "F.Paste")
			(roundrect_rratio 0.25)
			(net 290 "/FPGA Config/Flash.MISO")
			(pinfunction "DQ1")
			(pintype "bidirectional")
		)
		(pad "3" smd roundrect
			(at -3.905 0.64)
			(size 0.45 0.95)
			(layers "F.Cu" "F.Mask" "F.Paste")
			(roundrect_rratio 0.25)
			(net 258 "Net-(U3-W#{slash}DQ2)")
			(pinfunction "W#/DQ2")
			(pintype "bidirectional")
		)
		(pad "4" smd roundrect
			(at -3.905 1.91)
			(size 0.45 0.95)
			(layers "F.Cu" "F.Mask" "F.Paste")
			(roundrect_rratio 0.25)
			(net 417 "GND")
			(pinfunction "GND")
			(pintype "power_in")
		)
		(pad "5" smd roundrect
			(at 3.895 1.91)
			(size 0.45 0.95)
			(layers "F.Cu" "F.Mask" "F.Paste")
			(roundrect_rratio 0.25)
			(net 287 "/FPGA Config/Flash.MOSI")
			(pinfunction "DQ0")
			(pintype "bidirectional")
		)
		(pad "6" smd roundrect
			(at 3.895 0.64)
			(size 0.45 0.95)
			(layers "F.Cu" "F.Mask" "F.Paste")
			(roundrect_rratio 0.25)
			(net 286 "/FPGA Config/Flash.CLK")
			(pinfunction "C")
			(pintype "input")
		)
		(pad "7" smd roundrect
			(at 3.895 -0.63)
			(size 0.45 0.95)
			(layers "F.Cu" "F.Mask" "F.Paste")
			(roundrect_rratio 0.25)
			(net 259 "Net-(U3-HOLD#{slash}DQ3)")
			(pinfunction "HOLD#/DQ3")
			(pintype "bidirectional")
		)
		(pad "8" smd roundrect
			(at 3.895 -1.9)
			(size 0.45 0.95)
			(layers "F.Cu" "F.Mask" "F.Paste")
			(roundrect_rratio 0.25)
			(net 50 "+3V3")
			(pinfunction "VCC")
			(pintype "power_in")
		)
		(pad "9" smd roundrect
			(at -0.005 0.005)
			(size 4.3 3.4)
			(layers "F.Cu" "F.Mask")
			(roundrect_rratio 0)
			(chamfer_ratio 0.1)
			(chamfer bottom_left)
		)
	)
	(footprint "antmicro-footprints:Fiducial_1mm_Mask2mm"
		(layer "F.Cu")
		(at 228.05 122)
		(descr "Circular Fiducial, 1mm bare copper, 3mm soldermask opening")
		(tags "fiducial")
		(property "Reference" "FD3"
			(at 0 -1.4 0)
			(layer "F.SilkS")
			(hide yes)
			(effects
				(font
					(size 0.7 0.7)
					(thickness 0.15)
				)
				(justify left bottom)
			)
		)
		(property "Value" "Fiducial_1mm_Mask2mm"
			(at 0 2.2 0)
			(layer "F.Fab")
			(hide yes)
			(effects
				(font
					(size 0.7 0.7)
					(thickness 0.15)
				)
				(justify left bottom)
			)
		)
		(property "Description" "Fiducial mask "
			(at 0 0 0)
			(layer "F.Fab")
			(hide yes)
			(effects
				(font
					(size 1.27 1.27)
					(thickness 0.15)
				)
			)
		)
		(property "Author" "Antmicro"
			(at 0 0 0)
			(layer "F.Fab")
			(hide yes)
			(effects
				(font
					(size 1 1)
					(thickness 0.15)
				)
			)
		)
		(property "License" "Apache-2.0"
			(at 0 0 0)
			(layer "F.Fab")
			(hide yes)
			(effects
				(font
					(size 1 1)
					(thickness 0.15)
				)
			)
		)
		(property "exclude_from_bom" ""
			(at 0 0 0)
			(layer "F.Fab")
			(hide yes)
			(effects
				(font
					(size 1 1)
					(thickness 0.15)
				)
			)
		)
		(sheetfile "polarfire-som.kicad_sch")
		(attr board_only exclude_from_pos_files exclude_from_bom)
		(fp_circle
			(center 0 0)
			(end 1.24 0)
			(stroke
				(width 0.05)
				(type solid)
			)
			(fill no)
			(layer "F.CrtYd")
		)
		(fp_circle
			(center 0 0)
			(end 0.999 0)
			(stroke
				(width 0.15)
				(type solid)
			)
			(fill no)
			(layer "F.Fab")
		)
		(fp_text user "License: Apache-2.0"
			(at -1.25 7.003 0)
			(layer "F.Fab")
			(effects
				(font
					(size 0.7 0.7)
					(thickness 0.15)
				)
				(justify left bottom)
			)
		)
		(fp_text user "${REFERENCE}"
			(at -1.25 4.603 0)
			(layer "F.Fab")
			(effects
				(font
					(size 0.7 0.7)
					(thickness 0.15)
				)
				(justify left bottom)
			)
		)
		(fp_text user "Author: Antmicro"
			(at -1.25 5.803 0)
			(layer "F.Fab")
			(effects
				(font
					(size 0.7 0.7)
					(thickness 0.15)
				)
				(justify left bottom)
			)
		)
		(pad "" smd circle
			(at 0 0)
			(size 1 1)
			(layers "F.Cu" "F.Mask")
			(solder_mask_margin 0.5)
			(clearance 0.5)
		)
	)
	(footprint "antmicro-footprints:L_0805_2012Metric"
		(layer "F.Cu")
		(at 176.9 139.75 90)
		(descr "Inductor  SMD 0805")
		(tags "inductor SMD 0805")
		(property "Reference" "L2"
			(at 1.813695 -0.715 180)
			(layer "F.SilkS")
			(effects
				(font
					(size 0.7 0.7)
					(thickness 0.15)
				)
				(justify left bottom)
			)
		)
		(property "Value" "L_1u_3.2A_0805"
			(at 0 1.947 90)
			(layer "F.Fab")
			(hide yes)
			(effects
				(font
					(size 0.7 0.7)
					(thickness 0.15)
				)
				(justify left bottom)
			)
		)
		(property "Datasheet" "https://abracon.com/datasheets/AOTA-B201208S.pdf"
			(at 0 0 90)
			(layer "F.Fab")
			(hide yes)
			(effects
				(font
					(size 1.27 1.27)
					(thickness 0.15)
				)
			)
		)
		(property "Description" "Power Inductor (SMT), 1 µH, 0.05 ohm, 3.2 A, AOTA-B201208S"
			(at 0 0 90)
			(layer "F.Fab")
			(hide yes)
			(effects
				(font
					(size 1.27 1.27)
					(thickness 0.15)
				)
			)
		)
		(property "Author" "Antmicro"
			(at 316.65 -37.15 0)
			(layer "F.Fab")
			(hide yes)
			(effects
				(font
					(size 1 1)
					(thickness 0.15)
				)
			)
		)
		(property "IMax" "3.2 A"
			(at 316.65 -37.15 0)
			(layer "F.Fab")
			(hide yes)
			(effects
				(font
					(size 1 1)
					(thickness 0.15)
				)
			)
		)
		(property "ISat" "3.5 A"
			(at 316.65 -37.15 0)
			(layer "F.Fab")
			(hide yes)
			(effects
				(font
					(size 1 1)
					(thickness 0.15)
				)
			)
		)
		(property "License" "Apache-2.0"
			(at 316.65 -37.15 0)
			(layer "F.Fab")
			(hide yes)
			(effects
				(font
					(size 1 1)
					(thickness 0.15)
				)
			)
		)
		(property "MPN" "AOTA-B201208S1R0MT "
			(at 316.65 -37.15 0)
			(layer "F.Fab")
			(hide yes)
			(effects
				(font
					(size 1 1)
					(thickness 0.15)
				)
			)
		)
		(property "Manufacturer" "Abracon"
			(at 316.65 -37.15 0)
			(layer "F.Fab")
			(hide yes)
			(effects
				(font
					(size 1 1)
					(thickness 0.15)
				)
			)
		)
		(property "Public" ""
			(at 316.65 -37.15 0)
			(layer "F.Fab")
			(hide yes)
			(effects
				(font
					(size 1 1)
					(thickness 0.15)
				)
			)
		)
		(property "Size" "2x1.2"
			(at 316.65 -37.15 0)
			(layer "F.Fab")
			(hide yes)
			(effects
				(font
					(size 1 1)
					(thickness 0.15)
				)
			)
		)
		(property "Val" "1u/3.2A"
			(at 316.65 -37.15 0)
			(layer "F.Fab")
			(hide yes)
			(effects
				(font
					(size 1 1)
					(thickness 0.15)
				)
			)
		)
		(sheetname "/Supply/")
		(sheetfile "supply.kicad_sch")
		(attr smd)
		(fp_line
			(start -0.3 -0.7)
			(end 0.3 -0.7)
			(stroke
				(width 0.15)
				(type solid)
			)
			(layer "F.SilkS")
		)
		(fp_line
			(start -0.3 0.7)
			(end 0.3 0.7)
			(stroke
				(width 0.15)
				(type solid)
			)
			(layer "F.SilkS")
		)
		(fp_rect
			(start 1.95 -0.9)
			(end -1.95 0.9)
			(stroke
				(width 0.05)
				(type default)
			)
			(fill no)
			(layer "F.CrtYd")
		)
		(fp_rect
			(start -0.95 -0.675)
			(end 0.95 0.675)
			(stroke
				(width 0.15)
				(type solid)
			)
			(fill no)
			(layer "F.Fab")
		)
		(fp_text user "Author: Antmicro"
			(at -1.9 5.947 90)
			(layer "F.Fab")
			(effects
				(font
					(size 0.7 0.7)
					(thickness 0.15)
				)
				(justify left bottom)
			)
		)
		(fp_text user "${REFERENCE}"
			(at -1.9 3.947 90)
			(layer "F.Fab")
			(effects
				(font
					(size 0.7 0.7)
					(thickness 0.15)
				)
				(justify left bottom)
			)
		)
		(fp_text user "License: Apache-2.0"
			(at -1.9 4.947 90)
			(layer "F.Fab")
			(effects
				(font
					(size 0.7 0.7)
					(thickness 0.15)
				)
				(justify left bottom)
			)
		)
		(pad "1" smd roundrect
			(at -1.1 0 90)
			(size 1.2 1.3)
			(layers "F.Cu" "F.Mask" "F.Paste")
			(roundrect_rratio 0.25)
			(net 168 "Net-(U7-SW1)")
			(pintype "passive")
		)
		(pad "2" smd roundrect
			(at 1.1 0 90)
			(size 1.2 1.3)
			(layers "F.Cu" "F.Mask" "F.Paste")
			(roundrect_rratio 0.25)
			(net 209 "/Supply/SENSE1_P")
			(pintype "passive")
		)
	)
	(footprint "antmicro-footprints:TP_SMD_0.75mm"
		(layer "F.Cu")
		(at 212.25 140.425 90)
		(property "Reference" "TP11"
			(at 0 -0.6 90)
			(layer "F.SilkS")
			(hide yes)
			(effects
				(font
					(size 0.7 0.7)
					(thickness 0.15)
				)
				(justify left bottom)
			)
		)
		(property "Value" "TP_0.75mm_SMD"
			(at 0 1.2 90)
			(layer "F.Fab")
			(hide yes)
			(effects
				(font
					(size 0.7 0.7)
					(thickness 0.15)
				)
				(justify left bottom)
			)
		)
		(property "Description" "SMT test point"
			(at 0 0 90)
			(layer "F.Fab")
			(hide yes)
			(effects
				(font
					(size 1.27 1.27)
					(thickness 0.15)
				)
			)
		)
		(property "Author" "Antmicro"
			(at 352.675 -71.825 0)
			(layer "F.Fab")
			(hide yes)
			(effects
				(font
					(size 1 1)
					(thickness 0.15)
				)
			)
		)
		(property "License" "Apache-2.0"
			(at 352.675 -71.825 0)
			(layer "F.Fab")
			(hide yes)
			(effects
				(font
					(size 1 1)
					(thickness 0.15)
				)
			)
		)
		(property "MPN" ""
			(at 352.675 -71.825 0)
			(layer "F.Fab")
			(hide yes)
			(effects
				(font
					(size 1 1)
					(thickness 0.15)
				)
			)
		)
		(property "Manufacturer" ""
			(at 352.675 -71.825 0)
			(layer "F.Fab")
			(hide yes)
			(effects
				(font
					(size 1 1)
					(thickness 0.15)
				)
			)
		)
		(property "Public" "False"
			(at 352.675 -71.825 0)
			(layer "F.Fab")
			(hide yes)
			(effects
				(font
					(size 1 1)
					(thickness 0.15)
				)
			)
		)
		(sheetname "/USB/")
		(sheetfile "usb.kicad_sch")
		(attr exclude_from_pos_files exclude_from_bom)
		(fp_circle
			(center 0 0)
			(end 0.475 0)
			(stroke
				(width 0.05)
				(type default)
			)
			(fill no)
			(layer "F.CrtYd")
		)
		(fp_text user "Author: Antmicro"
			(at -0.4 3.901 90)
			(layer "F.Fab")
			(effects
				(font
					(size 0.7 0.7)
					(thickness 0.15)
				)
				(justify left bottom)
			)
		)
		(fp_text user "License: Apache-2.0"
			(at -0.4 5.101 90)
			(layer "F.Fab")
			(effects
				(font
					(size 0.7 0.7)
					(thickness 0.15)
				)
				(justify left bottom)
			)
		)
		(fp_text user "${REFERENCE}"
			(at -0.4 2.7 90)
			(layer "F.Fab")
			(effects
				(font
					(size 0.7 0.7)
					(thickness 0.15)
				)
				(justify left bottom)
			)
		)
		(pad "1" smd circle
			(at 0 0 90)
			(size 0.75 0.75)
			(layers "F.Cu" "F.Mask")
			(net 221 "VBUS")
			(pinfunction "1")
			(pintype "passive")
		)
	)
	(footprint "antmicro-footprints:C_0402_1005Metric"
		(layer "F.Cu")
		(at 218.21 154.14 180)
		(descr "Capacitor SMD 0402")
		(tags "capacitor SMD 0402")
		(property "Reference" "C68"
			(at 2.86 -0.36 0)
			(layer "F.SilkS")
			(effects
				(font
					(size 0.7 0.7)
					(thickness 0.15)
				)
				(justify right bottom)
			)
		)
		(property "Value" "C_100n_0402"
			(at -1.022927 2.155213 0)
			(layer "F.Fab")
			(hide yes)
			(effects
				(font
					(size 0.7 0.7)
					(thickness 0.15)
				)
				(justify right bottom)
			)
		)
		(property "Datasheet" "https://www.murata.com/products/productdetail?partno=GRM155R61H104KE14%23"
			(at 0 0 180)
			(layer "F.Fab")
			(hide yes)
			(effects
				(font
					(size 1.27 1.27)
					(thickness 0.15)
				)
			)
		)
		(property "Description" "SMD Multilayer Ceramic Capacitor, 0.1 µF, 50 V, 0402 [1005 Metric], ± 10%, X5R, GRM Series"
			(at 0 0 180)
			(layer "F.Fab")
			(hide yes)
			(effects
				(font
					(size 1.27 1.27)
					(thickness 0.15)
				)
			)
		)
		(property "Author" "Antmicro"
			(at 436.42 308.28 0)
			(layer "F.Fab")
			(hide yes)
			(effects
				(font
					(size 1 1)
					(thickness 0.15)
				)
			)
		)
		(property "Dielectric" "X5R"
			(at 436.42 308.28 0)
			(layer "F.Fab")
			(hide yes)
			(effects
				(font
					(size 1 1)
					(thickness 0.15)
				)
			)
		)
		(property "License" "Apache-2.0"
			(at 436.42 308.28 0)
			(layer "F.Fab")
			(hide yes)
			(effects
				(font
					(size 1 1)
					(thickness 0.15)
				)
			)
		)
		(property "MPN" "GRM155R61H104KE14D"
			(at 436.42 308.28 0)
			(layer "F.Fab")
			(hide yes)
			(effects
				(font
					(size 1 1)
					(thickness 0.15)
				)
			)
		)
		(property "Manufacturer" "Murata"
			(at 436.42 308.28 0)
			(layer "F.Fab")
			(hide yes)
			(effects
				(font
					(size 1 1)
					(thickness 0.15)
				)
			)
		)
		(property "Public" ""
			(at 436.42 308.28 0)
			(layer "F.Fab")
			(hide yes)
			(effects
				(font
					(size 1 1)
					(thickness 0.15)
				)
			)
		)
		(property "Val" "100n"
			(at 436.42 308.28 0)
			(layer "F.Fab")
			(hide yes)
			(effects
				(font
					(size 1 1)
					(thickness 0.15)
				)
			)
		)
		(property "Voltage" "50V"
			(at 436.42 308.28 0)
			(layer "F.Fab")
			(hide yes)
			(effects
				(font
					(size 1 1)
					(thickness 0.15)
				)
			)
		)
		(sheetname "/PCIe/")
		(sheetfile "pcie.kicad_sch")
		(attr smd)
		(fp_rect
			(start -0.925 -0.47)
			(end 0.925 0.47)
			(stroke
				(width 0.05)
				(type default)
			)
			(fill no)
			(layer "F.CrtYd")
		)
		(fp_line
			(start 0.504 0.248)
			(end -0.494 0.248)
			(stroke
				(width 0.15)
				(type solid)
			)
			(layer "F.Fab")
		)
		(fp_line
			(start 0.504 -0.25)
			(end 0.504 0.248)
			(stroke
				(width 0.15)
				(type solid)
			)
			(layer "F.Fab")
		)
		(fp_line
			(start -0.494 0.248)
			(end -0.494 -0.25)
			(stroke
				(width 0.15)
				(type solid)
			)
			(layer "F.Fab")
		)
		(fp_line
			(start -0.494 -0.25)
			(end 0.504 -0.25)
			(stroke
				(width 0.15)
				(type solid)
			)
			(layer "F.Fab")
		)
		(fp_text user "${REFERENCE}"
			(at -0.939 4.599 180)
			(layer "F.Fab")
			(effects
				(font
					(size 0.7 0.7)
					(thickness 0.15)
				)
				(justify left bottom)
			)
		)
		(fp_text user "License: Apache-2.0"
			(at -0.939 5.799 180)
			(layer "F.Fab")
			(effects
				(font
					(size 0.7 0.7)
					(thickness 0.15)
				)
				(justify left bottom)
			)
		)
		(fp_text user "Author: Antmicro"
			(at -0.939 3.399 180)
			(layer "F.Fab")
			(effects
				(font
					(size 0.7 0.7)
					(thickness 0.15)
				)
				(justify left bottom)
			)
		)
		(pad "1" smd roundrect
			(at -0.48 0 180)
			(size 0.59 0.64)
			(layers "F.Cu" "F.Mask" "F.Paste")
			(roundrect_rratio 0.25)
			(net 315 "Net-(U17-CLK1+)")
			(pintype "passive")
		)
		(pad "2" smd roundrect
			(at 0.48 0 180)
			(size 0.59 0.64)
			(layers "F.Cu" "F.Mask" "F.Paste")
			(roundrect_rratio 0.25)
			(net 5 "/Bottom Connector/PCIE.CLK_P")
			(pintype "passive")
		)
	)
	(footprint "antmicro-footprints:QFN-24-1EP_4x4mm_P0.5mm_EP2.6x2.6mm"
		(layer "F.Cu")
		(at 214.865 148.05)
		(descr "QFN, 24 Pin (http://ww1.microchip.com/downloads/en/PackagingSpec/00000049BQ.pdf#page=278), generated with kicad-footprint-generator ipc_noLead_generator.py")
		(tags "QFN NoLead")
		(property "Reference" "U28"
			(at 3.185 -0.3 270)
			(layer "F.SilkS")
			(effects
				(font
					(size 0.7 0.7)
					(thickness 0.15)
				)
				(justify left bottom)
			)
		)
		(property "Value" "USB2422-I/MJ"
			(at 0 3.4 0)
			(layer "F.Fab")
			(hide yes)
			(effects
				(font
					(size 0.7 0.7)
					(thickness 0.15)
				)
				(justify left bottom)
			)
		)
		(property "Datasheet" "https://ww1.microchip.com/downloads/aemDocuments/documents/OTH/ProductDocuments/DataSheets/00001726B.pdf"
			(at 0 0 0)
			(layer "F.Fab")
			(hide yes)
			(effects
				(font
					(size 1.27 1.27)
					(thickness 0.15)
				)
			)
		)
		(property "Description" "USB Interface, USB Hub Controller, USB 2.0, 3 V, 3.6 V, SQFN, 24 Pins"
			(at 0 0 0)
			(layer "F.Fab")
			(hide yes)
			(effects
				(font
					(size 1.27 1.27)
					(thickness 0.15)
				)
			)
		)
		(property "Author" "Antmicro"
			(at 0 0 0)
			(layer "F.Fab")
			(hide yes)
			(effects
				(font
					(size 1 1)
					(thickness 0.15)
				)
			)
		)
		(property "License" "Apache-2.0"
			(at 0 0 0)
			(layer "F.Fab")
			(hide yes)
			(effects
				(font
					(size 1 1)
					(thickness 0.15)
				)
			)
		)
		(property "MPN" "USB2422-I/MJ"
			(at 0 0 0)
			(layer "F.Fab")
			(hide yes)
			(effects
				(font
					(size 1 1)
					(thickness 0.15)
				)
			)
		)
		(property "Manufacturer" "Microchip Technology"
			(at 0 0 0)
			(layer "F.Fab")
			(hide yes)
			(effects
				(font
					(size 1 1)
					(thickness 0.15)
				)
			)
		)
		(sheetname "/USB/")
		(sheetfile "usb.kicad_sch")
		(attr smd)
		(fp_line
			(start -2.11 -1.636)
			(end -2.11 -2.11)
			(stroke
				(width 0.15)
				(type solid)
			)
			(layer "F.SilkS")
		)
		(fp_line
			(start -2.11 2.108)
			(end -2.11 1.634)
			(stroke
				(width 0.15)
				(type solid)
			)
			(layer "F.SilkS")
		)
		(fp_line
			(start -1.635 -2.11)
			(end -2.11 -2.11)
			(stroke
				(width 0.15)
				(type solid)
			)
			(layer "F.SilkS")
		)
		(fp_line
			(start -1.635 2.108)
			(end -2.11 2.108)
			(stroke
				(width 0.15)
				(type solid)
			)
			(layer "F.SilkS")
		)
		(fp_line
			(start 1.634 -2.11)
			(end 2.108 -2.11)
			(stroke
				(width 0.15)
				(type solid)
			)
			(layer "F.SilkS")
		)
		(fp_line
			(start 1.634 2.108)
			(end 2.108 2.108)
			(stroke
				(width 0.15)
				(type solid)
			)
			(layer "F.SilkS")
		)
		(fp_line
			(start 2.108 -2.11)
			(end 2.108 -1.635)
			(stroke
				(width 0.15)
				(type solid)
			)
			(layer "F.SilkS")
		)
		(fp_line
			(start 2.108 2.108)
			(end 2.108 1.634)
			(stroke
				(width 0.15)
				(type solid)
			)
			(layer "F.SilkS")
		)
		(fp_circle
			(center -2.3 -2.3)
			(end -2.25 -2.3)
			(stroke
				(width 0.15)
				(type solid)
			)
			(fill yes)
			(layer "F.SilkS")
		)
		(fp_rect
			(start -2.503 -2.503)
			(end 2.5 2.5)
			(stroke
				(width 0.05)
				(type solid)
			)
			(fill no)
			(layer "F.CrtYd")
		)
		(fp_line
			(start -2 -1)
			(end -1 -2)
			(stroke
				(width 0.15)
				(type solid)
			)
			(layer "F.Fab")
		)
		(fp_line
			(start -2 1.999)
			(end -2 -1)
			(stroke
				(width 0.15)
				(type solid)
			)
			(layer "F.Fab")
		)
		(fp_line
			(start -1 -2)
			(end 1.999 -2)
			(stroke
				(width 0.15)
				(type solid)
			)
			(layer "F.Fab")
		)
		(fp_line
			(start 1.999 -2)
			(end 1.999 1.999)
			(stroke
				(width 0.15)
				(type solid)
			)
			(layer "F.Fab")
		)
		(fp_line
			(start 1.999 1.999)
			(end -2 1.999)
			(stroke
				(width 0.15)
				(type solid)
			)
			(layer "F.Fab")
		)
		(fp_text user "License: Apache-2.0"
			(at -2.503 6.6 0)
			(layer "F.Fab")
			(effects
				(font
					(size 0.7 0.7)
					(thickness 0.15)
				)
				(justify left bottom)
			)
		)
		(fp_text user "${REFERENCE}"
			(at -2.503 5.4 0)
			(layer "F.Fab")
			(effects
				(font
					(size 0.7 0.7)
					(thickness 0.15)
				)
				(justify left bottom)
			)
		)
		(fp_text user "Author: Antmicro"
			(at -2.503 7.8 0)
			(layer "F.Fab")
			(effects
				(font
					(size 0.7 0.7)
					(thickness 0.15)
				)
				(justify left bottom)
			)
		)
		(pad "" smd roundrect
			(at -0.652 -0.652)
			(size 1.05 1.05)
			(layers "F.Paste")
			(roundrect_rratio 0.238095)
		)
		(pad "" smd roundrect
			(at -0.652 0.65)
			(size 1.05 1.05)
			(layers "F.Paste")
			(roundrect_rratio 0.238095)
		)
		(pad "" smd roundrect
			(at 0.65 -0.652)
			(size 1.05 1.05)
			(layers "F.Paste")
			(roundrect_rratio 0.238095)
		)
		(pad "" smd roundrect
			(at 0.65 0.65)
			(size 1.05 1.05)
			(layers "F.Paste")
			(roundrect_rratio 0.238095)
		)
		(pad "1" smd roundrect
			(at -1.938 -1.25)
			(size 0.825 0.25)
			(layers "F.Cu" "F.Mask" "F.Paste")
			(roundrect_rratio 0.25)
			(net 50 "+3V3")
			(pinfunction "3V3")
			(pintype "power_in")
		)
		(pad "2" smd roundrect
			(at -1.938 -0.75)
			(size 0.825 0.25)
			(layers "F.Cu" "F.Mask" "F.Paste")
			(roundrect_rratio 0.25)
			(net 122 "/USB/WL_BT.D_N")
			(pinfunction "DN1_D-")
			(pintype "bidirectional")
		)
		(pad "3" smd roundrect
			(at -1.938 -0.25)
			(size 0.825 0.25)
			(layers "F.Cu" "F.Mask" "F.Paste")
			(roundrect_rratio 0.25)
			(net 190 "/USB/WL_BT.D_P")
			(pinfunction "DN1_D+")
			(pintype "bidirectional")
		)
		(pad "4" smd roundrect
			(at -1.938 0.248)
			(size 0.825 0.25)
			(layers "F.Cu" "F.Mask" "F.Paste")
			(roundrect_rratio 0.25)
			(net 514 "/USB/USB_DN1_N")
			(pinfunction "DN2_D-")
			(pintype "bidirectional")
		)
		(pad "5" smd roundrect
			(at -1.938 0.748)
			(size 0.825 0.25)
			(layers "F.Cu" "F.Mask" "F.Paste")
			(roundrect_rratio 0.25)
			(net 515 "/USB/USB_DN1_P")
			(pinfunction "DN2_D+")
			(pintype "bidirectional")
		)
		(pad "6" smd roundrect
			(at -1.938 1.249)
			(size 0.825 0.25)
			(layers "F.Cu" "F.Mask" "F.Paste")
			(roundrect_rratio 0.25)
			(net 233 "unconnected-(U28-NC-Pad6)")
			(pinfunction "NC")
			(pintype "no_connect")
		)
		(pad "7" smd roundrect
			(at -1.25 1.937)
			(size 0.25 0.825)
			(layers "F.Cu" "F.Mask" "F.Paste")
			(roundrect_rratio 0.25)
			(net 234 "unconnected-(U28-PWR_{PRT1}-Pad7)")
			(pinfunction "PWR_{PRT1}")
			(pintype "output+no_connect")
		)
		(pad "8" smd roundrect
			(at -0.75 1.937)
			(size 0.25 0.825)
			(layers "F.Cu" "F.Mask" "F.Paste")
			(roundrect_rratio 0.25)
			(net 239 "unconnected-(U28-OSC_{N1}-Pad8)")
			(pinfunction "OSC_{N1}")
			(pintype "input+no_connect")
		)
		(pad "9" smd roundrect
			(at -0.25 1.937)
			(size 0.25 0.825)
			(layers "F.Cu" "F.Mask" "F.Paste")
			(roundrect_rratio 0.25)
			(net 50 "+3V3")
			(pinfunction "3V3")
			(pintype "passive")
		)
		(pad "10" smd roundrect
			(at 0.248 1.937)
			(size 0.25 0.825)
			(layers "F.Cu" "F.Mask" "F.Paste")
			(roundrect_rratio 0.25)
			(net 182 "Net-(U28-CRFILT)")
			(pinfunction "CRFILT")
			(pintype "passive")
		)
		(pad "11" smd roundrect
			(at 0.748 1.937)
			(size 0.25 0.825)
			(layers "F.Cu" "F.Mask" "F.Paste")
			(roundrect_rratio 0.25)
			(net 242 "unconnected-(U28-PWR_{PRT2}-Pad11)")
			(pinfunction "PWR_{PRT2}")
			(pintype "output+no_connect")
		)
		(pad "12" smd roundrect
			(at 1.249 1.937)
			(size 0.25 0.825)
			(layers "F.Cu" "F.Mask" "F.Paste")
			(roundrect_rratio 0.25)
			(net 244 "unconnected-(U28-OSC_{N2}-Pad12)")
			(pinfunction "OSC_{N2}")
			(pintype "input+no_connect")
		)
		(pad "13" smd roundrect
			(at 1.937 1.249)
			(size 0.825 0.25)
			(layers "F.Cu" "F.Mask" "F.Paste")
			(roundrect_rratio 0.25)
			(net 580 "unconnected-(U28-SMBDATA-Pad13)")
			(pinfunction "SMBDATA")
			(pintype "input+no_connect")
		)
		(pad "14" smd roundrect
			(at 1.937 0.748)
			(size 0.825 0.25)
			(layers "F.Cu" "F.Mask" "F.Paste")
			(roundrect_rratio 0.25)
			(net 581 "unconnected-(U28-SMBCLK-Pad14)")
			(pinfunction "SMBCLK")
			(pintype "input+no_connect")
		)
		(pad "15" smd roundrect
			(at 1.937 0.248)
			(size 0.825 0.25)
			(layers "F.Cu" "F.Mask" "F.Paste")
			(roundrect_rratio 0.25)
			(net 317 "/USB/~{HUB_RST}")
			(pinfunction "~{RESET}")
			(pintype "input")
		)
		(pad "16" smd roundrect
			(at 1.937 -0.25)
			(size 0.825 0.25)
			(layers "F.Cu" "F.Mask" "F.Paste")
			(roundrect_rratio 0.25)
			(net 62 "USB_OTG_ID")
			(pinfunction "VBUS_{DET}")
			(pintype "input")
		)
		(pad "17" smd roundrect
			(at 1.937 -0.75)
			(size 0.825 0.25)
			(layers "F.Cu" "F.Mask" "F.Paste")
			(roundrect_rratio 0.25)
			(net 318 "Net-(U28-SUSP_IND)")
			(pinfunction "SUSP_IND")
			(pintype "input")
		)
		(pad "18" smd roundrect
			(at 1.937 -1.25)
			(size 0.825 0.25)
			(layers "F.Cu" "F.Mask" "F.Paste")
			(roundrect_rratio 0.25)
			(net 50 "+3V3")
			(pinfunction "3V3")
			(pintype "passive")
		)
		(pad "19" smd roundrect
			(at 1.249 -1.938)
			(size 0.25 0.825)
			(layers "F.Cu" "F.Mask" "F.Paste")
			(roundrect_rratio 0.25)
			(net 512 "/USB/USB_UP_N")
			(pinfunction "UP_D-")
			(pintype "bidirectional")
		)
		(pad "20" smd roundrect
			(at 0.748 -1.938)
			(size 0.25 0.825)
			(layers "F.Cu" "F.Mask" "F.Paste")
			(roundrect_rratio 0.25)
			(net 513 "/USB/USB_UP_P")
			(pinfunction "UP_D+")
			(pintype "bidirectional")
		)
		(pad "21" smd roundrect
			(at 0.248 -1.938)
			(size 0.25 0.825)
			(layers "F.Cu" "F.Mask" "F.Paste")
			(roundrect_rratio 0.25)
			(net 247 "unconnected-(U28-XTAL_{OUT}-Pad21)")
			(pinfunction "XTAL_{OUT}")
			(pintype "input+no_connect")
		)
		(pad "22" smd roundrect
			(at -0.25 -1.938)
			(size 0.25 0.825)
			(layers "F.Cu" "F.Mask" "F.Paste")
			(roundrect_rratio 0.25)
			(net 500 "/USB/REF_CLK")
			(pinfunction "XTAL_{IN}")
			(pintype "input")
		)
		(pad "23" smd roundrect
			(at -0.75 -1.938)
			(size 0.25 0.825)
			(layers "F.Cu" "F.Mask" "F.Paste")
			(roundrect_rratio 0.25)
			(net 179 "Net-(U28-PLLFILT)")
			(pinfunction "PLLFILT")
			(pintype "passive")
		)
		(pad "24" smd roundrect
			(at -1.25 -1.938)
			(size 0.25 0.825)
			(layers "F.Cu" "F.Mask" "F.Paste")
			(roundrect_rratio 0.25)
			(net 325 "Net-(U28-R_{BIAS})")
			(pinfunction "R_{BIAS}")
			(pintype "passive")
		)
		(pad "25" smd rect
			(at 0 0)
			(size 2.6 2.6)
			(layers "F.Cu" "F.Mask")
			(net 417 "GND")
			(pinfunction "GND")
			(pintype "power_in")
		)
	)
	(footprint "antmicro-footprints:TP_SMD_0.75mm"
		(layer "F.Cu")
		(at 190.34 148.39)
		(property "Reference" "TP19"
			(at 0 -0.6 0)
			(layer "F.SilkS")
			(hide yes)
			(effects
				(font
					(size 0.7 0.7)
					(thickness 0.15)
				)
				(justify left bottom)
			)
		)
		(property "Value" "TP_0.75mm_SMD"
			(at 0 1.2 0)
			(layer "F.Fab")
			(hide yes)
			(effects
				(font
					(size 0.7 0.7)
					(thickness 0.15)
				)
				(justify left bottom)
			)
		)
		(property "Description" "SMT test point"
			(at 0 0 0)
			(layer "F.Fab")
			(hide yes)
			(effects
				(font
					(size 1.27 1.27)
					(thickness 0.15)
				)
			)
		)
		(property "Author" "Antmicro"
			(at 0 0 0)
			(layer "F.Fab")
			(hide yes)
			(effects
				(font
					(size 1 1)
					(thickness 0.15)
				)
			)
		)
		(property "License" "Apache-2.0"
			(at 0 0 0)
			(layer "F.Fab")
			(hide yes)
			(effects
				(font
					(size 1 1)
					(thickness 0.15)
				)
			)
		)
		(property "MPN" ""
			(at 0 0 0)
			(layer "F.Fab")
			(hide yes)
			(effects
				(font
					(size 1 1)
					(thickness 0.15)
				)
			)
		)
		(property "Manufacturer" ""
			(at 0 0 0)
			(layer "F.Fab")
			(hide yes)
			(effects
				(font
					(size 1 1)
					(thickness 0.15)
				)
			)
		)
		(property "Public" "False"
			(at 0 0 0)
			(layer "F.Fab")
			(hide yes)
			(effects
				(font
					(size 1 1)
					(thickness 0.15)
				)
			)
		)
		(sheetname "/HDMI/")
		(sheetfile "hdmi.kicad_sch")
		(attr exclude_from_pos_files exclude_from_bom)
		(fp_circle
			(center 0 0)
			(end 0.475 0)
			(stroke
				(width 0.05)
				(type default)
			)
			(fill no)
			(layer "F.CrtYd")
		)
		(fp_text user "${REFERENCE}"
			(at -0.4 2.7 0)
			(layer "F.Fab")
			(effects
				(font
					(size 0.7 0.7)
					(thickness 0.15)
				)
				(justify left bottom)
			)
		)
		(fp_text user "License: Apache-2.0"
			(at -0.4 5.101 0)
			(layer "F.Fab")
			(effects
				(font
					(size 0.7 0.7)
					(thickness 0.15)
				)
				(justify left bottom)
			)
		)
		(fp_text user "Author: Antmicro"
			(at -0.4 3.901 0)
			(layer "F.Fab")
			(effects
				(font
					(size 0.7 0.7)
					(thickness 0.15)
				)
				(justify left bottom)
			)
		)
		(pad "1" smd circle
			(at 0 0)
			(size 0.75 0.75)
			(layers "F.Cu" "F.Mask")
			(net 557 "Net-(U15-EQ_S0)")
			(pinfunction "1")
			(pintype "passive")
		)
	)
	(footprint "antmicro-footprints:R_0402_1005Metric"
		(layer "F.Cu")
		(at 181.15 121.45 180)
		(descr "Resistor SMD 0402")
		(tags "resistor SMD 0402")
		(property "Reference" "R12"
			(at -5.1 -6.56 270)
			(layer "F.SilkS")
			(effects
				(font
					(size 0.7 0.7)
					(thickness 0.15)
				)
				(justify left bottom)
			)
		)
		(property "Value" "R_0R_0402"
			(at -1.011843 1.772047 180)
			(layer "F.Fab")
			(hide yes)
			(effects
				(font
					(size 0.7 0.7)
					(thickness 0.15)
				)
				(justify left bottom)
			)
		)
		(property "Datasheet" "https://industrial.panasonic.com/cdbs/www-data/pdf/RDA0000/AOA0000C301.pdf"
			(at 0 0 180)
			(layer "F.Fab")
			(hide yes)
			(effects
				(font
					(size 1.27 1.27)
					(thickness 0.15)
				)
			)
		)
		(property "Description" "SMD Chip Resistor, Jumper, 0 ohm, 100 mW, 0402 [1005 Metric], Thick Film, General Purpose"
			(at 0 0 180)
			(layer "F.Fab")
			(hide yes)
			(effects
				(font
					(size 1.27 1.27)
					(thickness 0.15)
				)
			)
		)
		(property "Author" "Antmicro"
			(at 362.3 242.9 0)
			(layer "F.Fab")
			(hide yes)
			(effects
				(font
					(size 1 1)
					(thickness 0.15)
				)
			)
		)
		(property "Current" "1A"
			(at 362.3 242.9 0)
			(layer "F.Fab")
			(hide yes)
			(effects
				(font
					(size 1 1)
					(thickness 0.15)
				)
			)
		)
		(property "License" "Apache-2.0"
			(at 362.3 242.9 0)
			(layer "F.Fab")
			(hide yes)
			(effects
				(font
					(size 1 1)
					(thickness 0.15)
				)
			)
		)
		(property "MPN" "ERJ2GE0R00X"
			(at 362.3 242.9 0)
			(layer "F.Fab")
			(hide yes)
			(effects
				(font
					(size 1 1)
					(thickness 0.15)
				)
			)
		)
		(property "Manufacturer" "Panasonic"
			(at 362.3 242.9 0)
			(layer "F.Fab")
			(hide yes)
			(effects
				(font
					(size 1 1)
					(thickness 0.15)
				)
			)
		)
		(property "Public" ""
			(at 362.3 242.9 0)
			(layer "F.Fab")
			(hide yes)
			(effects
				(font
					(size 1 1)
					(thickness 0.15)
				)
			)
		)
		(property "Tolerance" "~"
			(at 362.3 242.9 0)
			(layer "F.Fab")
			(hide yes)
			(effects
				(font
					(size 1 1)
					(thickness 0.15)
				)
			)
		)
		(property "Val" "0R"
			(at 362.3 242.9 0)
			(layer "F.Fab")
			(hide yes)
			(effects
				(font
					(size 1 1)
					(thickness 0.15)
				)
			)
		)
		(sheetname "/Ethernet/")
		(sheetfile "ethernet.kicad_sch")
		(attr smd dnp)
		(fp_rect
			(start -0.925 -0.47)
			(end 0.925 0.47)
			(stroke
				(width 0.05)
				(type default)
			)
			(fill no)
			(layer "F.CrtYd")
		)
		(fp_rect
			(start -0.5 -0.25)
			(end 0.5 0.25)
			(stroke
				(width 0.15)
				(type solid)
			)
			(fill no)
			(layer "F.Fab")
		)
		(fp_text user "${REFERENCE}"
			(at -0.95 3.168 180)
			(layer "F.Fab")
			(effects
				(font
					(size 0.7 0.7)
					(thickness 0.15)
				)
				(justify left bottom)
			)
		)
		(fp_text user "Author: Antmicro"
			(at -0.95 4.169 180)
			(layer "F.Fab")
			(effects
				(font
					(size 0.7 0.7)
					(thickness 0.15)
				)
				(justify left bottom)
			)
		)
		(fp_text user "License: Apache-2.0"
			(at -0.95 5.169 180)
			(layer "F.Fab")
			(effects
				(font
					(size 0.7 0.7)
					(thickness 0.15)
				)
				(justify left bottom)
			)
		)
		(pad "1" smd roundrect
			(at -0.48 0 180)
			(size 0.59 0.64)
			(layers "F.Cu" "F.Mask" "F.Paste")
			(roundrect_rratio 0.25)
			(net 125 "JTAG_TDO")
			(pintype "passive")
		)
		(pad "2" smd roundrect
			(at 0.48 0 180)
			(size 0.59 0.64)
			(layers "F.Cu" "F.Mask" "F.Paste")
			(roundrect_rratio 0.25)
			(net 560 "Net-(U11-JTAG_TDO)")
			(pintype "passive")
		)
	)
	(footprint "antmicro-footprints:TP_SMD_0.75mm"
		(layer "F.Cu")
		(at 186.2 146.25 180)
		(property "Reference" "TP35"
			(at 16.68 -0.56 45)
			(layer "F.SilkS")
			(hide yes)
			(effects
				(font
					(size 0.7 0.7)
					(thickness 0.15)
				)
				(justify right bottom)
			)
		)
		(property "Value" "TP_0.75mm_SMD"
			(at 0 1.2 0)
			(layer "F.Fab")
			(hide yes)
			(effects
				(font
					(size 0.7 0.7)
					(thickness 0.15)
				)
				(justify right bottom)
			)
		)
		(property "Description" "SMT test point"
			(at 0 0 180)
			(layer "F.Fab")
			(hide yes)
			(effects
				(font
					(size 1.27 1.27)
					(thickness 0.15)
				)
			)
		)
		(property "Author" "Antmicro"
			(at 372.4 292.5 0)
			(layer "F.Fab")
			(hide yes)
			(effects
				(font
					(size 1 1)
					(thickness 0.15)
				)
			)
		)
		(property "License" "Apache-2.0"
			(at 372.4 292.5 0)
			(layer "F.Fab")
			(hide yes)
			(effects
				(font
					(size 1 1)
					(thickness 0.15)
				)
			)
		)
		(property "MPN" ""
			(at 372.4 292.5 0)
			(layer "F.Fab")
			(hide yes)
			(effects
				(font
					(size 1 1)
					(thickness 0.15)
				)
			)
		)
		(property "Manufacturer" ""
			(at 372.4 292.5 0)
			(layer "F.Fab")
			(hide yes)
			(effects
				(font
					(size 1 1)
					(thickness 0.15)
				)
			)
		)
		(property "Public" "False"
			(at 372.4 292.5 0)
			(layer "F.Fab")
			(hide yes)
			(effects
				(font
					(size 1 1)
					(thickness 0.15)
				)
			)
		)
		(sheetname "/Supply/")
		(sheetfile "supply.kicad_sch")
		(attr exclude_from_pos_files exclude_from_bom)
		(fp_circle
			(center 0 0)
			(end 0.475 0)
			(stroke
				(width 0.05)
				(type default)
			)
			(fill no)
			(layer "F.CrtYd")
		)
		(fp_text user "License: Apache-2.0"
			(at -0.4 5.101 180)
			(layer "F.Fab")
			(effects
				(font
					(size 0.7 0.7)
					(thickness 0.15)
				)
				(justify left bottom)
			)
		)
		(fp_text user "${REFERENCE}"
			(at -0.4 2.7 180)
			(layer "F.Fab")
			(effects
				(font
					(size 0.7 0.7)
					(thickness 0.15)
				)
				(justify left bottom)
			)
		)
		(fp_text user "Author: Antmicro"
			(at -0.4 3.901 180)
			(layer "F.Fab")
			(effects
				(font
					(size 0.7 0.7)
					(thickness 0.15)
				)
				(justify left bottom)
			)
		)
		(pad "1" smd circle
			(at 0 0 180)
			(size 0.75 0.75)
			(layers "F.Cu" "F.Mask")
			(net 47 "+1V05")
			(pinfunction "1")
			(pintype "passive")
		)
	)
	(footprint "antmicro-footprints:C_0402_1005Metric"
		(layer "F.Cu")
		(at 188.684904 147.897281 -90)
		(descr "Capacitor SMD 0402")
		(tags "capacitor SMD 0402")
		(property "Reference" "C98"
			(at 2.062719 -4.315096 180)
			(layer "F.SilkS")
			(effects
				(font
					(size 0.7 0.7)
					(thickness 0.15)
				)
				(justify right bottom)
			)
		)
		(property "Value" "C_22u_0402"
			(at -1.022927 2.155213 90)
			(layer "F.Fab")
			(hide yes)
			(effects
				(font
					(size 0.7 0.7)
					(thickness 0.15)
				)
				(justify right bottom)
			)
		)
		(property "Datasheet" "https://www.murata.com/products/productdetail?partno=GRM158R60J226ME01%23"
			(at 0 0 270)
			(layer "F.Fab")
			(hide yes)
			(effects
				(font
					(size 1.27 1.27)
					(thickness 0.15)
				)
			)
		)
		(property "Description" "SMD Multilayer Ceramic Capacitor, 22 uF, 4 V, 0402 [1005 Metric], X6S"
			(at 0 0 270)
			(layer "F.Fab")
			(hide yes)
			(effects
				(font
					(size 1.27 1.27)
					(thickness 0.15)
				)
			)
		)
		(property "Author" "Antmicro"
			(at 40.787623 336.582185 0)
			(layer "F.Fab")
			(hide yes)
			(effects
				(font
					(size 1 1)
					(thickness 0.15)
				)
			)
		)
		(property "Dielectric" ""
			(at 40.787623 336.582185 0)
			(layer "F.Fab")
			(hide yes)
			(effects
				(font
					(size 1 1)
					(thickness 0.15)
				)
			)
		)
		(property "License" "Apache-2.0"
			(at 40.787623 336.582185 0)
			(layer "F.Fab")
			(hide yes)
			(effects
				(font
					(size 1 1)
					(thickness 0.15)
				)
			)
		)
		(property "MPN" "GRM158R60J226ME01D"
			(at 40.787623 336.582185 0)
			(layer "F.Fab")
			(hide yes)
			(effects
				(font
					(size 1 1)
					(thickness 0.15)
				)
			)
		)
		(property "Manufacturer" "Murata"
			(at 40.787623 336.582185 0)
			(layer "F.Fab")
			(hide yes)
			(effects
				(font
					(size 1 1)
					(thickness 0.15)
				)
			)
		)
		(property "Public" ""
			(at 40.787623 336.582185 0)
			(layer "F.Fab")
			(hide yes)
			(effects
				(font
					(size 1 1)
					(thickness 0.15)
				)
			)
		)
		(property "Val" "22u"
			(at 40.787623 336.582185 0)
			(layer "F.Fab")
			(hide yes)
			(effects
				(font
					(size 1 1)
					(thickness 0.15)
				)
			)
		)
		(property "Voltage" ""
			(at 40.787623 336.582185 0)
			(layer "F.Fab")
			(hide yes)
			(effects
				(font
					(size 1 1)
					(thickness 0.15)
				)
			)
		)
		(sheetname "/Supply/")
		(sheetfile "supply.kicad_sch")
		(attr smd)
		(fp_rect
			(start -0.925 -0.47)
			(end 0.925 0.47)
			(stroke
				(width 0.05)
				(type default)
			)
			(fill no)
			(layer "F.CrtYd")
		)
		(fp_line
			(start -0.494 0.248)
			(end -0.494 -0.25)
			(stroke
				(width 0.15)
				(type solid)
			)
			(layer "F.Fab")
		)
		(fp_line
			(start 0.504 0.248)
			(end -0.494 0.248)
			(stroke
				(width 0.15)
				(type solid)
			)
			(layer "F.Fab")
		)
		(fp_line
			(start -0.494 -0.25)
			(end 0.504 -0.25)
			(stroke
				(width 0.15)
				(type solid)
			)
			(layer "F.Fab")
		)
		(fp_line
			(start 0.504 -0.25)
			(end 0.504 0.248)
			(stroke
				(width 0.15)
				(type solid)
			)
			(layer "F.Fab")
		)
		(fp_text user "${REFERENCE}"
			(at -0.939 4.599 270)
			(layer "F.Fab")
			(effects
				(font
					(size 0.7 0.7)
					(thickness 0.15)
				)
				(justify left bottom)
			)
		)
		(fp_text user "License: Apache-2.0"
			(at -0.939 5.799 270)
			(layer "F.Fab")
			(effects
				(font
					(size 0.7 0.7)
					(thickness 0.15)
				)
				(justify left bottom)
			)
		)
		(fp_text user "Author: Antmicro"
			(at -0.939 3.399 270)
			(layer "F.Fab")
			(effects
				(font
					(size 0.7 0.7)
					(thickness 0.15)
				)
				(justify left bottom)
			)
		)
		(pad "1" smd roundrect
			(at -0.48 0 270)
			(size 0.59 0.64)
			(layers "F.Cu" "F.Mask" "F.Paste")
			(roundrect_rratio 0.25)
			(net 417 "GND")
			(pintype "passive")
		)
		(pad "2" smd roundrect
			(at 0.48 0 270)
			(size 0.59 0.64)
			(layers "F.Cu" "F.Mask" "F.Paste")
			(roundrect_rratio 0.25)
			(net 522 "/Supply/1V05_REG")
			(pintype "passive")
		)
	)
	(footprint "antmicro-footprints:R_0402_1005Metric"
		(layer "B.Cu")
		(at 201.5 122.6 180)
		(descr "Resistor SMD 0402")
		(tags "resistor SMD 0402")
		(property "Reference" "R105"
			(at -4.71 -0.98 0)
			(layer "B.SilkS")
			(effects
				(font
					(size 0.7 0.7)
					(thickness 0.15)
				)
				(justify left bottom mirror)
			)
		)
		(property "Value" "R_4k7_0402"
			(at -1.011843 -1.772047 0)
			(layer "B.Fab")
			(hide yes)
			(effects
				(font
					(size 0.7 0.7)
					(thickness 0.15)
				)
				(justify left bottom mirror)
			)
		)
		(property "Datasheet" "https://www.bourns.com/docs/product-datasheets/cr.pdf"
			(at 0 0 180)
			(layer "F.Fab")
			(hide yes)
			(effects
				(font
					(size 1.27 1.27)
					(thickness 0.15)
				)
			)
		)
		(property "Description" "SMD Chip Resistor, 4.7 kohm, ± 1%, 62.5 mW, 0402 [1005 Metric], Thick Film, General Purpose"
			(at 0 0 180)
			(layer "F.Fab")
			(hide yes)
			(effects
				(font
					(size 1.27 1.27)
					(thickness 0.15)
				)
			)
		)
		(property "Author" "Antmicro"
			(at 403 245.2 0)
			(layer "B.Fab")
			(hide yes)
			(effects
				(font
					(size 1 1)
					(thickness 0.15)
				)
				(justify mirror)
			)
		)
		(property "License" "Apache-2.0"
			(at 403 245.2 0)
			(layer "B.Fab")
			(hide yes)
			(effects
				(font
					(size 1 1)
					(thickness 0.15)
				)
				(justify mirror)
			)
		)
		(property "MPN" "CR0402-FX-4701GLF"
			(at 403 245.2 0)
			(layer "B.Fab")
			(hide yes)
			(effects
				(font
					(size 1 1)
					(thickness 0.15)
				)
				(justify mirror)
			)
		)
		(property "Manufacturer" "Bourns"
			(at 403 245.2 0)
			(layer "B.Fab")
			(hide yes)
			(effects
				(font
					(size 1 1)
					(thickness 0.15)
				)
				(justify mirror)
			)
		)
		(property "Public" ""
			(at 403 245.2 0)
			(layer "B.Fab")
			(hide yes)
			(effects
				(font
					(size 1 1)
					(thickness 0.15)
				)
				(justify mirror)
			)
		)
		(property "Tolerance" "1%"
			(at 403 245.2 0)
			(layer "B.Fab")
			(hide yes)
			(effects
				(font
					(size 1 1)
					(thickness 0.15)
				)
				(justify mirror)
			)
		)
		(property "Val" "4k7"
			(at 403 245.2 0)
			(layer "B.Fab")
			(hide yes)
			(effects
				(font
					(size 1 1)
					(thickness 0.15)
				)
				(justify mirror)
			)
		)
		(sheetname "/FPGA MSSIO/")
		(sheetfile "fpga-mssio.kicad_sch")
		(attr smd)
		(fp_rect
			(start -0.925 0.47)
			(end 0.925 -0.47)
			(stroke
				(width 0.05)
				(type default)
			)
			(fill no)
			(layer "B.CrtYd")
		)
		(fp_rect
			(start -0.5 0.25)
			(end 0.5 -0.25)
			(stroke
				(width 0.15)
				(type solid)
			)
			(fill no)
			(layer "B.Fab")
		)
		(fp_text user "License: Apache-2.0"
			(at -0.95 -5.169 0)
			(layer "B.Fab")
			(effects
				(font
					(size 0.7 0.7)
					(thickness 0.15)
				)
				(justify left bottom mirror)
			)
		)
		(fp_text user "${REFERENCE}"
			(at -0.95 -3.168 0)
			(layer "B.Fab")
			(effects
				(font
					(size 0.7 0.7)
					(thickness 0.15)
				)
				(justify left bottom mirror)
			)
		)
		(fp_text user "Author: Antmicro"
			(at -0.95 -4.169 0)
			(layer "B.Fab")
			(effects
				(font
					(size 0.7 0.7)
					(thickness 0.15)
				)
				(justify left bottom mirror)
			)
		)
		(pad "1" smd roundrect
			(at -0.48 0 180)
			(size 0.59 0.64)
			(layers "B.Cu" "B.Mask" "B.Paste")
			(roundrect_rratio 0.25)
			(net 92 "/FPGA MSSIO/SUPPLY.SCL")
			(pintype "passive")
		)
		(pad "2" smd roundrect
			(at 0.48 0 180)
			(size 0.59 0.64)
			(layers "B.Cu" "B.Mask" "B.Paste")
			(roundrect_rratio 0.25)
			(net 649 "VDD")
			(pintype "passive")
		)
	)
	(footprint "antmicro-footprints:SOT-523"
		(layer "B.Cu")
		(at 182.65 118.65 180)
		(property "Reference" "Q10"
			(at -1.05 1.3 0)
			(layer "B.SilkS")
			(effects
				(font
					(size 0.7 0.7)
					(thickness 0.15)
				)
				(justify left bottom mirror)
			)
		)
		(property "Value" "DMG1012T-7"
			(at 0.1 -1.824 0)
			(layer "B.Fab")
			(hide yes)
			(effects
				(font
					(size 0.7 0.7)
					(thickness 0.15)
				)
				(justify left bottom mirror)
			)
		)
		(property "Datasheet" "https://www.diodes.com/assets/Datasheets/ds31783.pdf"
			(at 0 0 0)
			(layer "B.Fab")
			(hide yes)
			(effects
				(font
					(size 1.27 1.27)
					(thickness 0.15)
				)
				(justify mirror)
			)
		)
		(property "Description" "Power MOSFET, N Channel, 20 V, 630 mA, 0.3 ohm, SOT-523, Surface Mount"
			(at 0 0 0)
			(layer "B.Fab")
			(hide yes)
			(effects
				(font
					(size 1.27 1.27)
					(thickness 0.15)
				)
				(justify mirror)
			)
		)
		(property "MPN" "DMG1012T-7"
			(at 0 0 0)
			(unlocked yes)
			(layer "B.Fab")
			(hide yes)
			(effects
				(font
					(size 1 1)
					(thickness 0.15)
				)
				(justify mirror)
			)
		)
		(property "Manufacturer" "Diodes Incorporated"
			(at 0 0 0)
			(unlocked yes)
			(layer "B.Fab")
			(hide yes)
			(effects
				(font
					(size 1 1)
					(thickness 0.15)
				)
				(justify mirror)
			)
		)
		(property "Author" "Antmicro"
			(at 0 0 0)
			(unlocked yes)
			(layer "B.Fab")
			(hide yes)
			(effects
				(font
					(size 1 1)
					(thickness 0.15)
				)
				(justify mirror)
			)
		)
		(property "License" "Apache-2.0"
			(at 0 0 0)
			(unlocked yes)
			(layer "B.Fab")
			(hide yes)
			(effects
				(font
					(size 1 1)
					(thickness 0.15)
				)
				(justify mirror)
			)
		)
		(property "Public" ""
			(at 0 0 0)
			(unlocked yes)
			(layer "B.Fab")
			(hide yes)
			(effects
				(font
					(size 1 1)
					(thickness 0.15)
				)
				(justify mirror)
			)
		)
		(sheetname "/FPGA Config/")
		(sheetfile "fpga-config.kicad_sch")
		(attr smd)
		(fp_line
			(start -0.277 0.551)
			(end -0.277 0.75)
			(stroke
				(width 0.15)
				(type solid)
			)
			(layer "B.SilkS")
		)
		(fp_line
			(start -0.725 0.551)
			(end -0.277 0.551)
			(stroke
				(width 0.15)
				(type solid)
			)
			(layer "B.SilkS")
		)
		(fp_line
			(start -0.927 0.351)
			(end -0.725 0.551)
			(stroke
				(width 0.15)
				(type solid)
			)
			(layer "B.SilkS")
		)
		(fp_line
			(start -0.927 0.051)
			(end -0.927 0.351)
			(stroke
				(width 0.15)
				(type solid)
			)
			(layer "B.SilkS")
		)
		(fp_circle
			(center -0.9652 -0.9652)
			(end -0.9152 -0.9652)
			(stroke
				(width 0.15)
				(type solid)
			)
			(fill yes)
			(layer "B.SilkS")
		)
		(fp_line
			(start 1.1 1.16)
			(end 1.1 -1.15)
			(stroke
				(width 0.05)
				(type solid)
			)
			(layer "B.CrtYd")
		)
		(fp_line
			(start -1.12 1.16)
			(end 1.1 1.16)
			(stroke
				(width 0.05)
				(type solid)
			)
			(layer "B.CrtYd")
		)
		(fp_line
			(start -1.12 1.16)
			(end -1.12 -1.15)
			(stroke
				(width 0.05)
				(type solid)
			)
			(layer "B.CrtYd")
		)
		(fp_line
			(start -1.12 -1.15)
			(end 1.1 -1.15)
			(stroke
				(width 0.05)
				(type solid)
			)
			(layer "B.CrtYd")
		)
		(fp_line
			(start 0.8 0.425)
			(end 0.8 -0.424)
			(stroke
				(width 0.15)
				(type solid)
			)
			(layer "B.Fab")
		)
		(fp_line
			(start 0.8 0.425)
			(end -0.652 0.425)
			(stroke
				(width 0.15)
				(type solid)
			)
			(layer "B.Fab")
		)
		(fp_line
			(start 0.8 -0.424)
			(end -0.802 -0.424)
			(stroke
				(width 0.15)
				(type solid)
			)
			(layer "B.Fab")
		)
		(fp_line
			(start -0.652 0.425)
			(end -0.802 0.276)
			(stroke
				(width 0.15)
				(type solid)
			)
			(layer "B.Fab")
		)
		(fp_line
			(start -0.802 0.276)
			(end -0.802 -0.424)
			(stroke
				(width 0.15)
				(type solid)
			)
			(layer "B.Fab")
		)
		(fp_circle
			(center -0.9652 -0.9652)
			(end -0.9144 -0.9652)
			(stroke
				(width 0.15)
				(type solid)
			)
			(fill no)
			(layer "B.Fab")
		)
		(fp_text user "Author: Antmicro"
			(at -1.12 -6.224 0)
			(layer "B.Fab")
			(effects
				(font
					(size 0.7 0.7)
					(thickness 0.15)
				)
				(justify left bottom mirror)
			)
		)
		(fp_text user "${REFERENCE}"
			(at -1.12 -3.824 0)
			(layer "B.Fab")
			(effects
				(font
					(size 0.7 0.7)
					(thickness 0.15)
				)
				(justify left bottom mirror)
			)
		)
		(fp_text user "License: Apache-2.0"
			(at -1.12 -5.024 0)
			(layer "B.Fab")
			(effects
				(font
					(size 0.7 0.7)
					(thickness 0.15)
				)
				(justify left bottom mirror)
			)
		)
		(pad "1" smd rect
			(at -0.5 -0.65 180)
			(size 0.4 0.51)
			(layers "B.Cu" "B.Mask" "B.Paste")
			(net 230 "~{PG}")
			(pinfunction "G")
			(pintype "input")
		)
		(pad "2" smd rect
			(at 0.498 -0.65 180)
			(size 0.4 0.51)
			(layers "B.Cu" "B.Mask" "B.Paste")
			(net 417 "GND")
			(pinfunction "S")
			(pintype "passive")
		)
		(pad "3" smd rect
			(at 0 0.652 180)
			(size 0.4 0.51)
			(layers "B.Cu" "B.Mask" "B.Paste")
			(net 655 "/FPGA Config/DEVRST_N")
			(pinfunction "D")
			(pintype "passive")
		)
	)
	(footprint "antmicro-footprints:C_0402_1005Metric"
		(layer "B.Cu")
		(at 198.78 123.56)
		(descr "Capacitor SMD 0402")
		(tags "capacitor SMD 0402")
		(property "Reference" "C14"
			(at -0.855 0.115 180)
			(layer "B.SilkS")
			(effects
				(font
					(size 0.7 0.7)
					(thickness 0.15)
				)
				(justify left bottom mirror)
			)
		)
		(property "Value" "C_100n_0402"
			(at -1.022927 -2.155213 180)
			(layer "B.Fab")
			(hide yes)
			(effects
				(font
					(size 0.7 0.7)
					(thickness 0.15)
				)
				(justify left bottom mirror)
			)
		)
		(property "Datasheet" "https://www.murata.com/products/productdetail?partno=GRM155R61H104KE14%23"
			(at 0 0 0)
			(layer "F.Fab")
			(hide yes)
			(effects
				(font
					(size 1.27 1.27)
					(thickness 0.15)
				)
			)
		)
		(property "Description" "SMD Multilayer Ceramic Capacitor, 0.1 µF, 50 V, 0402 [1005 Metric], ± 10%, X5R, GRM Series"
			(at 0 0 0)
			(layer "F.Fab")
			(hide yes)
			(effects
				(font
					(size 1.27 1.27)
					(thickness 0.15)
				)
			)
		)
		(property "Author" "Antmicro"
			(at 0 0 0)
			(layer "B.Fab")
			(hide yes)
			(effects
				(font
					(size 1 1)
					(thickness 0.15)
				)
				(justify mirror)
			)
		)
		(property "Dielectric" "X5R"
			(at 0 0 0)
			(layer "B.Fab")
			(hide yes)
			(effects
				(font
					(size 1 1)
					(thickness 0.15)
				)
				(justify mirror)
			)
		)
		(property "License" "Apache-2.0"
			(at 0 0 0)
			(layer "B.Fab")
			(hide yes)
			(effects
				(font
					(size 1 1)
					(thickness 0.15)
				)
				(justify mirror)
			)
		)
		(property "MPN" "GRM155R61H104KE14D"
			(at 0 0 0)
			(layer "B.Fab")
			(hide yes)
			(effects
				(font
					(size 1 1)
					(thickness 0.15)
				)
				(justify mirror)
			)
		)
		(property "Manufacturer" "Murata"
			(at 0 0 0)
			(layer "B.Fab")
			(hide yes)
			(effects
				(font
					(size 1 1)
					(thickness 0.15)
				)
				(justify mirror)
			)
		)
		(property "Public" ""
			(at 0 0 0)
			(layer "B.Fab")
			(hide yes)
			(effects
				(font
					(size 1 1)
					(thickness 0.15)
				)
				(justify mirror)
			)
		)
		(property "Val" "100n"
			(at 0 0 0)
			(layer "B.Fab")
			(hide yes)
			(effects
				(font
					(size 1 1)
					(thickness 0.15)
				)
				(justify mirror)
			)
		)
		(property "Voltage" "50V"
			(at 0 0 0)
			(layer "B.Fab")
			(hide yes)
			(effects
				(font
					(size 1 1)
					(thickness 0.15)
				)
				(justify mirror)
			)
		)
		(sheetname "/FPGA Supply/")
		(sheetfile "fpga-supply.kicad_sch")
		(attr smd)
		(fp_rect
			(start -0.925 0.47)
			(end 0.925 -0.47)
			(stroke
				(width 0.05)
				(type default)
			)
			(fill no)
			(layer "B.CrtYd")
		)
		(fp_line
			(start -0.494 -0.248)
			(end -0.494 0.25)
			(stroke
				(width 0.15)
				(type solid)
			)
			(layer "B.Fab")
		)
		(fp_line
			(start -0.494 0.25)
			(end 0.504 0.25)
			(stroke
				(width 0.15)
				(type solid)
			)
			(layer "B.Fab")
		)
		(fp_line
			(start 0.504 -0.248)
			(end -0.494 -0.248)
			(stroke
				(width 0.15)
				(type solid)
			)
			(layer "B.Fab")
		)
		(fp_line
			(start 0.504 0.25)
			(end 0.504 -0.248)
			(stroke
				(width 0.15)
				(type solid)
			)
			(layer "B.Fab")
		)
		(fp_text user "Author: Antmicro"
			(at -0.939 -3.399 180)
			(layer "B.Fab")
			(effects
				(font
					(size 0.7 0.7)
					(thickness 0.15)
				)
				(justify left bottom mirror)
			)
		)
		(fp_text user "${REFERENCE}"
			(at -0.939 -4.599 180)
			(layer "B.Fab")
			(effects
				(font
					(size 0.7 0.7)
					(thickness 0.15)
				)
				(justify left bottom mirror)
			)
		)
		(fp_text user "License: Apache-2.0"
			(at -0.939 -5.799 180)
			(layer "B.Fab")
			(effects
				(font
					(size 0.7 0.7)
					(thickness 0.15)
				)
				(justify left bottom mirror)
			)
		)
		(pad "1" smd roundrect
			(at -0.48 0)
			(size 0.59 0.64)
			(layers "B.Cu" "B.Mask" "B.Paste")
			(roundrect_rratio 0.25)
			(net 417 "GND")
			(pintype "passive")
		)
		(pad "2" smd roundrect
			(at 0.48 0)
			(size 0.59 0.64)
			(layers "B.Cu" "B.Mask" "B.Paste")
			(roundrect_rratio 0.25)
			(net 137 "SD_VDD")
			(pintype "passive")
		)
	)
	(footprint "antmicro-footprints:C_0402_1005Metric"
		(layer "B.Cu")
		(at 186.25 140.65 -90)
		(descr "Capacitor SMD 0402")
		(tags "capacitor SMD 0402")
		(property "Reference" "C218"
			(at -3.725 -0.375 90)
			(layer "B.SilkS")
			(effects
				(font
					(size 0.7 0.7)
					(thickness 0.15)
				)
				(justify left bottom mirror)
			)
		)
		(property "Value" "C_100n_0402"
			(at -1.022927 -2.155213 90)
			(layer "B.Fab")
			(hide yes)
			(effects
				(font
					(size 0.7 0.7)
					(thickness 0.15)
				)
				(justify left bottom mirror)
			)
		)
		(property "Datasheet" "https://www.murata.com/products/productdetail?partno=GRM155R61H104KE14%23"
			(at 0 0 270)
			(layer "F.Fab")
			(hide yes)
			(effects
				(font
					(size 1.27 1.27)
					(thickness 0.15)
				)
			)
		)
		(property "Description" "SMD Multilayer Ceramic Capacitor, 0.1 µF, 50 V, 0402 [1005 Metric], ± 10%, X5R, GRM Series"
			(at 0 0 270)
			(layer "F.Fab")
			(hide yes)
			(effects
				(font
					(size 1.27 1.27)
					(thickness 0.15)
				)
			)
		)
		(property "Author" "Antmicro"
			(at 45.6 326.9 0)
			(layer "B.Fab")
			(hide yes)
			(effects
				(font
					(size 1 1)
					(thickness 0.15)
				)
				(justify mirror)
			)
		)
		(property "Dielectric" "X5R"
			(at 45.6 326.9 0)
			(layer "B.Fab")
			(hide yes)
			(effects
				(font
					(size 1 1)
					(thickness 0.15)
				)
				(justify mirror)
			)
		)
		(property "License" "Apache-2.0"
			(at 45.6 326.9 0)
			(layer "B.Fab")
			(hide yes)
			(effects
				(font
					(size 1 1)
					(thickness 0.15)
				)
				(justify mirror)
			)
		)
		(property "MPN" "GRM155R61H104KE14D"
			(at 45.6 326.9 0)
			(layer "B.Fab")
			(hide yes)
			(effects
				(font
					(size 1 1)
					(thickness 0.15)
				)
				(justify mirror)
			)
		)
		(property "Manufacturer" "Murata"
			(at 45.6 326.9 0)
			(layer "B.Fab")
			(hide yes)
			(effects
				(font
					(size 1 1)
					(thickness 0.15)
				)
				(justify mirror)
			)
		)
		(property "Public" ""
			(at 45.6 326.9 0)
			(layer "B.Fab")
			(hide yes)
			(effects
				(font
					(size 1 1)
					(thickness 0.15)
				)
				(justify mirror)
			)
		)
		(property "Val" "100n"
			(at 45.6 326.9 0)
			(layer "B.Fab")
			(hide yes)
			(effects
				(font
					(size 1 1)
					(thickness 0.15)
				)
				(justify mirror)
			)
		)
		(property "Voltage" "50V"
			(at 45.6 326.9 0)
			(layer "B.Fab")
			(hide yes)
			(effects
				(font
					(size 1 1)
					(thickness 0.15)
				)
				(justify mirror)
			)
		)
		(sheetname "/FPGA GPIO/")
		(sheetfile "fpga-gpio.kicad_sch")
		(attr smd)
		(fp_rect
			(start -0.925 0.47)
			(end 0.925 -0.47)
			(stroke
				(width 0.05)
				(type default)
			)
			(fill no)
			(layer "B.CrtYd")
		)
		(fp_line
			(start -0.494 0.25)
			(end 0.504 0.25)
			(stroke
				(width 0.15)
				(type solid)
			)
			(layer "B.Fab")
		)
		(fp_line
			(start 0.504 0.25)
			(end 0.504 -0.248)
			(stroke
				(width 0.15)
				(type solid)
			)
			(layer "B.Fab")
		)
		(fp_line
			(start -0.494 -0.248)
			(end -0.494 0.25)
			(stroke
				(width 0.15)
				(type solid)
			)
			(layer "B.Fab")
		)
		(fp_line
			(start 0.504 -0.248)
			(end -0.494 -0.248)
			(stroke
				(width 0.15)
				(type solid)
			)
			(layer "B.Fab")
		)
		(fp_text user "License: Apache-2.0"
			(at -0.939 -5.799 90)
			(layer "B.Fab")
			(effects
				(font
					(size 0.7 0.7)
					(thickness 0.15)
				)
				(justify left bottom mirror)
			)
		)
		(fp_text user "${REFERENCE}"
			(at -0.939 -4.599 90)
			(layer "B.Fab")
			(effects
				(font
					(size 0.7 0.7)
					(thickness 0.15)
				)
				(justify left bottom mirror)
			)
		)
		(fp_text user "Author: Antmicro"
			(at -0.939 -3.399 90)
			(layer "B.Fab")
			(effects
				(font
					(size 0.7 0.7)
					(thickness 0.15)
				)
				(justify left bottom mirror)
			)
		)
		(pad "1" smd roundrect
			(at -0.48 0 270)
			(size 0.59 0.64)
			(layers "B.Cu" "B.Mask" "B.Paste")
			(roundrect_rratio 0.25)
			(net 50 "+3V3")
			(pintype "passive")
		)
		(pad "2" smd roundrect
			(at 0.48 0 270)
			(size 0.59 0.64)
			(layers "B.Cu" "B.Mask" "B.Paste")
			(roundrect_rratio 0.25)
			(net 417 "GND")
			(pintype "passive")
		)
	)
	(footprint "antmicro-footprints:Conn_Plug_Hirose_DF40_2x50_DF40C-100DP-0.4V"
		(layer "B.Cu")
		(at 199.52 152.838 180)
		(property "Reference" "J4"
			(at -10.91 1.838 0)
			(layer "B.SilkS")
			(effects
				(font
					(size 0.7 0.7)
					(thickness 0.15)
				)
				(justify left bottom mirror)
			)
		)
		(property "Value" "Plug_Hirose_DF40_2x50_DF40C-100DP-0.4V"
			(at 0.001 -2.8 0)
			(layer "B.Fab")
			(hide yes)
			(effects
				(font
					(size 0.7 0.7)
					(thickness 0.15)
				)
				(justify left bottom mirror)
			)
		)
		(property "Datasheet" "https://www.hirose.com/en/product/document?clcode=CL0684-4032-1-51&productname=DF40C-100DP-0.4V(51)&series=DF40&documenttype=2DDrawing&lang=en&documentid=0001001212"
			(at 0 0 180)
			(layer "F.Fab")
			(hide yes)
			(effects
				(font
					(size 1.27 1.27)
					(thickness 0.15)
				)
			)
		)
		(property "Description" "Mezzanine Connector, Header, 0.4 mm, 2 Rows, 100 Contacts, Surface Mount, Phosphor Bronze"
			(at 0 0 180)
			(layer "F.Fab")
			(hide yes)
			(effects
				(font
					(size 1.27 1.27)
					(thickness 0.15)
				)
			)
		)
		(property "Author" "Antmicro"
			(at 399.04 305.676 0)
			(layer "B.Fab")
			(hide yes)
			(effects
				(font
					(size 1 1)
					(thickness 0.15)
				)
				(justify mirror)
			)
		)
		(property "License" "Apache-2.0"
			(at 399.04 305.676 0)
			(layer "B.Fab")
			(hide yes)
			(effects
				(font
					(size 1 1)
					(thickness 0.15)
				)
				(justify mirror)
			)
		)
		(property "MPN" "DF40C-100DP-0.4V(51)"
			(at 399.04 305.676 0)
			(layer "B.Fab")
			(hide yes)
			(effects
				(font
					(size 1 1)
					(thickness 0.15)
				)
				(justify mirror)
			)
		)
		(property "Manufacturer" "Hirose Electric"
			(at 399.04 305.676 0)
			(layer "B.Fab")
			(hide yes)
			(effects
				(font
					(size 1 1)
					(thickness 0.15)
				)
				(justify mirror)
			)
		)
		(property "Pitch" "0.4 mm"
			(at 399.04 305.676 0)
			(layer "B.Fab")
			(hide yes)
			(effects
				(font
					(size 1 1)
					(thickness 0.15)
				)
				(justify mirror)
			)
		)
		(sheetname "/Bottom Connector/")
		(sheetfile "bottom-connector.kicad_sch")
		(attr smd)
		(fp_line
			(start 10.76 0.946)
			(end 10.76 -0.9)
			(stroke
				(width 0.15)
				(type solid)
			)
			(layer "B.SilkS")
		)
		(fp_line
			(start -10.758 -0.9)
			(end -10.758 0.447)
			(stroke
				(width 0.15)
				(type solid)
			)
			(layer "B.SilkS")
		)
		(fp_circle
			(center -10 1.825)
			(end -9.95 1.825)
			(stroke
				(width 0.15)
				(type solid)
			)
			(fill yes)
			(layer "B.SilkS")
		)
		(fp_rect
			(start -11 1.9)
			(end 11.01 -1.8)
			(stroke
				(width 0.05)
				(type solid)
			)
			(fill no)
			(layer "B.CrtYd")
		)
		(fp_line
			(start 10.76 0.946)
			(end 10.76 -0.9)
			(stroke
				(width 0.15)
				(type solid)
			)
			(layer "B.Fab")
		)
		(fp_line
			(start 10.76 -0.9)
			(end -10.758 -0.9)
			(stroke
				(width 0.15)
				(type solid)
			)
			(layer "B.Fab")
		)
		(fp_line
			(start -10.258 0.946)
			(end 10.76 0.946)
			(stroke
				(width 0.15)
				(type solid)
			)
			(layer "B.Fab")
		)
		(fp_line
			(start -10.749 0.45)
			(end -10.258 0.946)
			(stroke
				(width 0.15)
				(type solid)
			)
			(layer "B.Fab")
		)
		(fp_line
			(start -10.758 -0.9)
			(end -10.749 0.45)
			(stroke
				(width 0.15)
				(type solid)
			)
			(layer "B.Fab")
		)
		(fp_text user "License: Apache-2.0"
			(at -11.76 -6.7 0)
			(layer "B.Fab")
			(effects
				(font
					(size 0.7 0.7)
					(thickness 0.15)
				)
				(justify left bottom mirror)
			)
		)
		(fp_text user "${REFERENCE}"
			(at -11.76 -7.9 0)
			(layer "B.Fab")
			(effects
				(font
					(size 0.7 0.7)
					(thickness 0.15)
				)
				(justify left bottom mirror)
			)
		)
		(fp_text user "Author: Antmicro"
			(at -11.76 -5.5 0)
			(layer "B.Fab")
			(effects
				(font
					(size 0.7 0.7)
					(thickness 0.15)
				)
				(justify left bottom mirror)
			)
		)
		(pad "1" smd rect
			(at -9.798 1.377 180)
			(size 0.23 0.66)
			(layers "B.Cu" "B.Mask" "B.Paste")
			(net 62 "USB_OTG_ID")
			(pintype "passive")
		)
		(pad "2" smd rect
			(at -9.798 -1.333 180)
			(size 0.23 0.66)
			(layers "B.Cu" "B.Mask" "B.Paste")
			(net 200 "PCIe_CLK_nREQ")
			(pintype "passive")
		)
		(pad "3" smd rect
			(at -9.399 1.377 180)
			(size 0.23 0.66)
			(layers "B.Cu" "B.Mask" "B.Paste")
			(net 15 "/Bottom Connector/CONN.D_N")
			(pintype "passive")
		)
		(pad "4" smd rect
			(at -9.399 -1.333 180)
			(size 0.23 0.66)
			(layers "B.Cu" "B.Mask" "B.Paste")
			(net 65 "unconnected-(J4-Pad4)")
			(pintype "passive+no_connect")
		)
		(pad "5" smd rect
			(at -8.998 1.377 180)
			(size 0.23 0.66)
			(layers "B.Cu" "B.Mask" "B.Paste")
			(net 16 "/Bottom Connector/CONN.D_P")
			(pintype "passive")
		)
		(pad "6" smd rect
			(at -8.998 -1.333 180)
			(size 0.23 0.66)
			(layers "B.Cu" "B.Mask" "B.Paste")
			(net 67 "unconnected-(J4-Pad6)")
			(pintype "passive+no_connect")
		)
		(pad "7" smd rect
			(at -8.598 1.377 180)
			(size 0.23 0.66)
			(layers "B.Cu" "B.Mask" "B.Paste")
			(net 417 "GND")
			(pintype "passive")
		)
		(pad "8" smd rect
			(at -8.598 -1.333 180)
			(size 0.23 0.66)
			(layers "B.Cu" "B.Mask" "B.Paste")
			(net 417 "GND")
			(pintype "passive")
		)
		(pad "9" smd rect
			(at -8.196 1.377 180)
			(size 0.23 0.66)
			(layers "B.Cu" "B.Mask" "B.Paste")
			(net 202 "PCIe_nRST")
			(pintype "passive")
		)
		(pad "10" smd rect
			(at -8.196 -1.333 180)
			(size 0.23 0.66)
			(layers "B.Cu" "B.Mask" "B.Paste")
			(net 5 "/Bottom Connector/PCIE.CLK_P")
			(pintype "passive")
		)
		(pad "11" smd rect
			(at -7.798 1.377 180)
			(size 0.23 0.66)
			(layers "B.Cu" "B.Mask" "B.Paste")
			(net 69 "unconnected-(J4-Pad11)")
			(pintype "passive+no_connect")
		)
		(pad "12" smd rect
			(at -7.798 -1.333 180)
			(size 0.23 0.66)
			(layers "B.Cu" "B.Mask" "B.Paste")
			(net 4 "/Bottom Connector/PCIE.CLK_N")
			(pintype "passive")
		)
		(pad "13" smd rect
			(at -7.399 1.377 180)
			(size 0.23 0.66)
			(layers "B.Cu" "B.Mask" "B.Paste")
			(net 417 "GND")
			(pintype "passive")
		)
		(pad "14" smd rect
			(at -7.399 -1.333 180)
			(size 0.23 0.66)
			(layers "B.Cu" "B.Mask" "B.Paste")
			(net 417 "GND")
			(pintype "passive")
		)
		(pad "15" smd rect
			(at -6.998 1.377 180)
			(size 0.23 0.66)
			(layers "B.Cu" "B.Mask" "B.Paste")
			(net 99 "/Bottom Connector/CAM1.D0_N")
			(pintype "passive")
		)
		(pad "16" smd rect
			(at -6.998 -1.333 180)
			(size 0.23 0.66)
			(layers "B.Cu" "B.Mask" "B.Paste")
			(net 102 "/Bottom Connector/PCIE.RXD0_P")
			(pintype "passive")
		)
		(pad "17" smd rect
			(at -6.598 1.377 180)
			(size 0.23 0.66)
			(layers "B.Cu" "B.Mask" "B.Paste")
			(net 104 "/Bottom Connector/CAM1.D0_P")
			(pintype "passive")
		)
		(pad "18" smd rect
			(at -6.598 -1.333 180)
			(size 0.23 0.66)
			(layers "B.Cu" "B.Mask" "B.Paste")
			(net 105 "/Bottom Connector/PCIE.RXD0_N")
			(pintype "passive")
		)
		(pad "19" smd rect
			(at -6.199 1.377 180)
			(size 0.23 0.66)
			(layers "B.Cu" "B.Mask" "B.Paste")
			(net 417 "GND")
			(pintype "passive")
		)
		(pad "20" smd rect
			(at -6.199 -1.333 180)
			(size 0.23 0.66)
			(layers "B.Cu" "B.Mask" "B.Paste")
			(net 417 "GND")
			(pintype "passive")
		)
		(pad "21" smd rect
			(at -5.798 1.377 180)
			(size 0.23 0.66)
			(layers "B.Cu" "B.Mask" "B.Paste")
			(net 106 "/Bottom Connector/CAM1.D1_N")
			(pintype "passive")
		)
		(pad "22" smd rect
			(at -5.798 -1.333 180)
			(size 0.23 0.66)
			(layers "B.Cu" "B.Mask" "B.Paste")
			(net 19 "/Bottom Connector/PCIE.TXD0_P")
			(pintype "passive")
		)
		(pad "23" smd rect
			(at -5.399 1.377 180)
			(size 0.23 0.66)
			(layers "B.Cu" "B.Mask" "B.Paste")
			(net 107 "/Bottom Connector/CAM1.D1_P")
			(pintype "passive")
		)
		(pad "24" smd rect
			(at -5.399 -1.333 180)
			(size 0.23 0.66)
			(layers "B.Cu" "B.Mask" "B.Paste")
			(net 33 "/Bottom Connector/PCIE.TXD0_N")
			(pintype "passive")
		)
		(pad "25" smd rect
			(at -4.998 1.377 180)
			(size 0.23 0.66)
			(layers "B.Cu" "B.Mask" "B.Paste")
			(net 417 "GND")
			(pintype "passive")
		)
		(pad "26" smd rect
			(at -4.998 -1.333 180)
			(size 0.23 0.66)
			(layers "B.Cu" "B.Mask" "B.Paste")
			(net 417 "GND")
			(pintype "passive")
		)
		(pad "27" smd rect
			(at -4.598 1.377 180)
			(size 0.23 0.66)
			(layers "B.Cu" "B.Mask" "B.Paste")
			(net 108 "/Bottom Connector/CAM1.C_N")
			(pintype "passive")
		)
		(pad "28" smd rect
			(at -4.598 -1.333 180)
			(size 0.23 0.66)
			(layers "B.Cu" "B.Mask" "B.Paste")
			(net 109 "/Bottom Connector/CAM0.D0_N")
			(pintype "passive")
		)
		(pad "29" smd rect
			(at -4.199 1.377 180)
			(size 0.23 0.66)
			(layers "B.Cu" "B.Mask" "B.Paste")
			(net 110 "/Bottom Connector/CAM1.C_P")
			(pintype "passive")
		)
		(pad "30" smd rect
			(at -4.199 -1.333 180)
			(size 0.23 0.66)
			(layers "B.Cu" "B.Mask" "B.Paste")
			(net 111 "/Bottom Connector/CAM0.D0_P")
			(pintype "passive")
		)
		(pad "31" smd rect
			(at -3.798 1.377 180)
			(size 0.23 0.66)
			(layers "B.Cu" "B.Mask" "B.Paste")
			(net 417 "GND")
			(pintype "passive")
		)
		(pad "32" smd rect
			(at -3.798 -1.333 180)
			(size 0.23 0.66)
			(layers "B.Cu" "B.Mask" "B.Paste")
			(net 417 "GND")
			(pintype "passive")
		)
		(pad "33" smd rect
			(at -3.397 1.377 180)
			(size 0.23 0.66)
			(layers "B.Cu" "B.Mask" "B.Paste")
			(net 112 "/Bottom Connector/CAM1.D2_N")
			(pintype "passive")
		)
		(pad "34" smd rect
			(at -3.397 -1.333 180)
			(size 0.23 0.66)
			(layers "B.Cu" "B.Mask" "B.Paste")
			(net 113 "/Bottom Connector/CAM0.D1_N")
			(pintype "passive")
		)
		(pad "35" smd rect
			(at -2.998 1.377 180)
			(size 0.23 0.66)
			(layers "B.Cu" "B.Mask" "B.Paste")
			(net 114 "/Bottom Connector/CAM1.D2_P")
			(pintype "passive")
		)
		(pad "36" smd rect
			(at -2.998 -1.333 180)
			(size 0.23 0.66)
			(layers "B.Cu" "B.Mask" "B.Paste")
			(net 115 "/Bottom Connector/CAM0.D1_P")
			(pintype "passive")
		)
		(pad "37" smd rect
			(at -2.597 1.377 180)
			(size 0.23 0.66)
			(layers "B.Cu" "B.Mask" "B.Paste")
			(net 417 "GND")
			(pintype "passive")
		)
		(pad "38" smd rect
			(at -2.597 -1.333 180)
			(size 0.23 0.66)
			(layers "B.Cu" "B.Mask" "B.Paste")
			(net 417 "GND")
			(pintype "passive")
		)
		(pad "39" smd rect
			(at -2.199 1.377 180)
			(size 0.23 0.66)
			(layers "B.Cu" "B.Mask" "B.Paste")
			(net 116 "/Bottom Connector/CAM1.D3_N")
			(pintype "passive")
		)
		(pad "40" smd rect
			(at -2.199 -1.333 180)
			(size 0.23 0.66)
			(layers "B.Cu" "B.Mask" "B.Paste")
			(net 118 "/Bottom Connector/CAM0.C_N")
			(pintype "passive")
		)
		(pad "41" smd rect
			(at -1.798 1.377 180)
			(size 0.23 0.66)
			(layers "B.Cu" "B.Mask" "B.Paste")
			(net 119 "/Bottom Connector/CAM1.D3_P")
			(pintype "passive")
		)
		(pad "42" smd rect
			(at -1.798 -1.333 180)
			(size 0.23 0.66)
			(layers "B.Cu" "B.Mask" "B.Paste")
			(net 120 "/Bottom Connector/CAM0.C_P")
			(pintype "passive")
		)
		(pad "43" smd rect
			(at -1.397 1.377 180)
			(size 0.23 0.66)
			(layers "B.Cu" "B.Mask" "B.Paste")
			(net 410 "Net-(Q3-D)")
			(pintype "passive")
		)
		(pad "44" smd rect
			(at -1.397 -1.333 180)
			(size 0.23 0.66)
			(layers "B.Cu" "B.Mask" "B.Paste")
			(net 417 "GND")
			(pintype "passive")
		)
		(pad "45" smd rect
			(at -0.998 1.377 180)
			(size 0.23 0.66)
			(layers "B.Cu" "B.Mask" "B.Paste")
			(net 410 "Net-(Q3-D)")
			(pintype "passive")
		)
		(pad "46" smd rect
			(at -0.998 -1.333 180)
			(size 0.23 0.66)
			(layers "B.Cu" "B.Mask" "B.Paste")
			(net 35 "/Bottom Connector/PCIE.TXD1_P")
			(pintype "passive")
		)
		(pad "47" smd rect
			(at -0.597 1.377 180)
			(size 0.23 0.66)
			(layers "B.Cu" "B.Mask" "B.Paste")
			(net 410 "Net-(Q3-D)")
			(pintype "passive")
		)
		(pad "48" smd rect
			(at -0.597 -1.333 180)
			(size 0.23 0.66)
			(layers "B.Cu" "B.Mask" "B.Paste")
			(net 36 "/Bottom Connector/PCIE.TXD1_N")
			(pintype "passive")
		)
		(pad "49" smd rect
			(at -0.199 1.377 180)
			(size 0.23 0.66)
			(layers "B.Cu" "B.Mask" "B.Paste")
			(net 410 "Net-(Q3-D)")
			(pintype "passive")
		)
		(pad "50" smd rect
			(at -0.199 -1.333 180)
			(size 0.23 0.66)
			(layers "B.Cu" "B.Mask" "B.Paste")
			(net 417 "GND")
			(pintype "passive")
		)
		(pad "51" smd rect
			(at 0.201 1.377 180)
			(size 0.23 0.66)
			(layers "B.Cu" "B.Mask" "B.Paste")
			(net 155 "unconnected-(J4-Pad51)")
			(pintype "passive+no_connect")
		)
		(pad "52" smd rect
			(at 0.201 -1.333 180)
			(size 0.23 0.66)
			(layers "B.Cu" "B.Mask" "B.Paste")
			(net 121 "/Bottom Connector/PCIE.RXD1_P")
			(pintype "passive")
		)
		(pad "53" smd rect
			(at 0.6 1.377 180)
			(size 0.23 0.66)
			(layers "B.Cu" "B.Mask" "B.Paste")
			(net 97 "HDMI0_HOTPLUG")
			(pintype "passive")
		)
		(pad "54" smd rect
			(at 0.6 -1.333 180)
			(size 0.23 0.66)
			(layers "B.Cu" "B.Mask" "B.Paste")
			(net 138 "/Bottom Connector/PCIE.RXD1_N")
			(pintype "passive")
		)
		(pad "55" smd rect
			(at 1 1.377 180)
			(size 0.23 0.66)
			(layers "B.Cu" "B.Mask" "B.Paste")
			(net 417 "GND")
			(pintype "passive")
		)
		(pad "56" smd rect
			(at 1 -1.333 180)
			(size 0.23 0.66)
			(layers "B.Cu" "B.Mask" "B.Paste")
			(net 417 "GND")
			(pintype "passive")
		)
		(pad "57" smd rect
			(at 1.402 1.377 180)
			(size 0.23 0.66)
			(layers "B.Cu" "B.Mask" "B.Paste")
			(net 139 "/Bottom Connector/PCIE.RXD2_N")
			(pintype "passive")
		)
		(pad "58" smd rect
			(at 1.402 -1.333 180)
			(size 0.23 0.66)
			(layers "B.Cu" "B.Mask" "B.Paste")
			(net 37 "/Bottom Connector/PCIE.TXD2_P")
			(pintype "passive")
		)
		(pad "59" smd rect
			(at 1.802 1.377 180)
			(size 0.23 0.66)
			(layers "B.Cu" "B.Mask" "B.Paste")
			(net 140 "/Bottom Connector/PCIE.RXD2_P")
			(pintype "passive")
		)
		(pad "60" smd rect
			(at 1.802 -1.333 180)
			(size 0.23 0.66)
			(layers "B.Cu" "B.Mask" "B.Paste")
			(net 38 "/Bottom Connector/PCIE.TXD2_N")
			(pintype "passive")
		)
		(pad "61" smd rect
			(at 2.203 1.377 180)
			(size 0.23 0.66)
			(layers "B.Cu" "B.Mask" "B.Paste")
			(net 417 "GND")
			(pintype "passive")
		)
		(pad "62" smd rect
			(at 2.203 -1.333 180)
			(size 0.23 0.66)
			(layers "B.Cu" "B.Mask" "B.Paste")
			(net 417 "GND")
			(pintype "passive")
		)
		(pad "63" smd rect
			(at 2.601 1.377 180)
			(size 0.23 0.66)
			(layers "B.Cu" "B.Mask" "B.Paste")
			(net 40 "/Bottom Connector/PCIE.TXD3_N")
			(pintype "passive")
		)
		(pad "64" smd rect
			(at 2.601 -1.333 180)
			(size 0.23 0.66)
			(layers "B.Cu" "B.Mask" "B.Paste")
			(net 141 "/Bottom Connector/PCIE.RXD3_P")
			(pintype "passive")
		)
		(pad "65" smd rect
			(at 3.001 1.377 180)
			(size 0.23 0.66)
			(layers "B.Cu" "B.Mask" "B.Paste")
			(net 39 "/Bottom Connector/PCIE.TXD3_P")
			(pintype "passive")
		)
		(pad "66" smd rect
			(at 3.001 -1.333 180)
			(size 0.23 0.66)
			(layers "B.Cu" "B.Mask" "B.Paste")
			(net 142 "/Bottom Connector/PCIE.RXD3_N")
			(pintype "passive")
		)
		(pad "67" smd rect
			(at 3.401 1.377 180)
			(size 0.23 0.66)
			(layers "B.Cu" "B.Mask" "B.Paste")
			(net 417 "GND")
			(pintype "passive")
		)
		(pad "68" smd rect
			(at 3.401 -1.333 180)
			(size 0.23 0.66)
			(layers "B.Cu" "B.Mask" "B.Paste")
			(net 417 "GND")
			(pintype "passive")
		)
		(pad "69" smd rect
			(at 3.802 1.377 180)
			(size 0.23 0.66)
			(layers "B.Cu" "B.Mask" "B.Paste")
			(net 238 "unconnected-(J4-Pad69)")
			(pintype "passive+no_connect")
		)
		(pad "70" smd rect
			(at 3.802 -1.333 180)
			(size 0.23 0.66)
			(layers "B.Cu" "B.Mask" "B.Paste")
			(net 143 "/Bottom Connector/HDMI0.TX2_P")
			(pintype "passive")
		)
		(pad "71" smd rect
			(at 4.202 1.377 180)
			(size 0.23 0.66)
			(layers "B.Cu" "B.Mask" "B.Paste")
			(net 241 "unconnected-(J4-Pad71)")
			(pintype "passive+no_connect")
		)
		(pad "72" smd rect
			(at 4.202 -1.333 180)
			(size 0.23 0.66)
			(layers "B.Cu" "B.Mask" "B.Paste")
			(net 144 "/Bottom Connector/HDMI0.TX2_N")
			(pintype "passive")
		)
		(pad "73" smd rect
			(at 4.6 1.377 180)
			(size 0.23 0.66)
			(layers "B.Cu" "B.Mask" "B.Paste")
			(net 417 "GND")
			(pintype "passive")
		)
		(pad "74" smd rect
			(at 4.6 -1.333 180)
			(size 0.23 0.66)
			(layers "B.Cu" "B.Mask" "B.Paste")
			(net 417 "GND")
			(pintype "passive")
		)
		(pad "75" smd rect
			(at 5.001 1.377 180)
			(size 0.23 0.66)
			(layers "B.Cu" "B.Mask" "B.Paste")
			(net 146 "/Bottom Connector/DSI1.D0_N")
			(pintype "passive")
		)
		(pad "76" smd rect
			(at 5.001 -1.333 180)
			(size 0.23 0.66)
			(layers "B.Cu" "B.Mask" "B.Paste")
			(net 147 "/Bottom Connector/HDMI0.TX1_P")
			(pintype "passive")
		)
		(pad "77" smd rect
			(at 5.401 1.377 180)
			(size 0.23 0.66)
			(layers "B.Cu" "B.Mask" "B.Paste")
			(net 156 "/Bottom Connector/DSI1.D0_P")
			(pintype "passive")
		)
		(pad "78" smd rect
			(at 5.401 -1.333 180)
			(size 0.23 0.66)
			(layers "B.Cu" "B.Mask" "B.Paste")
			(net 157 "/Bottom Connector/HDMI0.TX1_N")
			(pintype "passive")
		)
		(pad "79" smd rect
			(at 5.802 1.377 180)
			(size 0.23 0.66)
			(layers "B.Cu" "B.Mask" "B.Paste")
			(net 417 "GND")
			(pintype "passive")
		)
		(pad "80" smd rect
			(at 5.802 -1.333 180)
			(size 0.23 0.66)
			(layers "B.Cu" "B.Mask" "B.Paste")
			(net 417 "GND")
			(pintype "passive")
		)
		(pad "81" smd rect
			(at 6.202 1.377 180)
			(size 0.23 0.66)
			(layers "B.Cu" "B.Mask" "B.Paste")
			(net 158 "/Bottom Connector/DSI1.D1_N")
			(pintype "passive")
		)
		(pad "82" smd rect
			(at 6.202 -1.333 180)
			(size 0.23 0.66)
			(layers "B.Cu" "B.Mask" "B.Paste")
			(net 159 "/Bottom Connector/HDMI0.TX0_P")
			(pintype "passive")
		)
		(pad "83" smd rect
			(at 6.6 1.377 180)
			(size 0.23 0.66)
			(layers "B.Cu" "B.Mask" "B.Paste")
			(net 160 "/Bottom Connector/DSI1.D1_P")
			(pintype "passive")
		)
		(pad "84" smd rect
			(at 6.6 -1.333 180)
			(size 0.23 0.66)
			(layers "B.Cu" "B.Mask" "B.Paste")
			(net 161 "/Bottom Connector/HDMI0.TX0_N")
			(pintype "passive")
		)
		(pad "85" smd rect
			(at 7 1.377 180)
			(size 0.23 0.66)
			(layers "B.Cu" "B.Mask" "B.Paste")
			(net 417 "GND")
			(pintype "passive")
		)
		(pad "86" smd rect
			(at 7 -1.333 180)
			(size 0.23 0.66)
			(layers "B.Cu" "B.Mask" "B.Paste")
			(net 417 "GND")
			(pintype "passive")
		)
		(pad "87" smd rect
			(at 7.401 1.377 180)
			(size 0.23 0.66)
			(layers "B.Cu" "B.Mask" "B.Paste")
			(net 162 "/Bottom Connector/DSI1.C_N")
			(pintype "passive")
		)
		(pad "88" smd rect
			(at 7.401 -1.333 180)
			(size 0.23 0.66)
			(layers "B.Cu" "B.Mask" "B.Paste")
			(net 163 "/Bottom Connector/HDMI0.CLK_P")
			(pintype "passive")
		)
		(pad "89" smd rect
			(at 7.802 1.377 180)
			(size 0.23 0.66)
			(layers "B.Cu" "B.Mask" "B.Paste")
			(net 195 "/Bottom Connector/DSI1.C_P")
			(pintype "passive")
		)
		(pad "90" smd rect
			(at 7.802 -1.333 180)
			(size 0.23 0.66)
			(layers "B.Cu" "B.Mask" "B.Paste")
			(net 196 "/Bottom Connector/HDMI0.CLK_N")
			(pintype "passive")
		)
		(pad "91" smd rect
			(at 8.2 1.377 180)
			(size 0.23 0.66)
			(layers "B.Cu" "B.Mask" "B.Paste")
			(net 417 "GND")
			(pintype "passive")
		)
		(pad "92" smd rect
			(at 8.2 -1.333 180)
			(size 0.23 0.66)
			(layers "B.Cu" "B.Mask" "B.Paste")
			(net 417 "GND")
			(pintype "passive")
		)
		(pad "93" smd rect
			(at 8.6 1.377 180)
			(size 0.23 0.66)
			(layers "B.Cu" "B.Mask" "B.Paste")
			(net 197 "/Bottom Connector/DSI1.D2_N")
			(pintype "passive")
		)
		(pad "94" smd rect
			(at 8.6 -1.333 180)
			(size 0.23 0.66)
			(layers "B.Cu" "B.Mask" "B.Paste")
			(net 198 "/Bottom Connector/DSI1.D3_N")
			(pintype "passive")
		)
		(pad "95" smd rect
			(at 9 1.377 180)
			(size 0.23 0.66)
			(layers "B.Cu" "B.Mask" "B.Paste")
			(net 199 "/Bottom Connector/DSI1.D2_P")
			(pintype "passive")
		)
		(pad "96" smd rect
			(at 9 -1.333 180)
			(size 0.23 0.66)
			(layers "B.Cu" "B.Mask" "B.Paste")
			(net 201 "/Bottom Connector/DSI1.D3_P")
			(pintype "passive")
		)
		(pad "97" smd rect
			(at 9.401 1.377 180)
			(size 0.23 0.66)
			(layers "B.Cu" "B.Mask" "B.Paste")
			(net 417 "GND")
			(pintype "passive")
		)
		(pad "98" smd rect
			(at 9.401 -1.333 180)
			(size 0.23 0.66)
			(layers "B.Cu" "B.Mask" "B.Paste")
			(net 417 "GND")
			(pintype "passive")
		)
		(pad "99" smd rect
			(at 9.803 1.377 180)
			(size 0.23 0.66)
			(layers "B.Cu" "B.Mask" "B.Paste")
			(net 206 "/Bottom Connector/HDMI0.SDA")
			(pintype "passive")
		)
		(pad "100" smd rect
			(at 9.803 -1.333 180)
			(size 0.23 0.66)
			(layers "B.Cu" "B.Mask" "B.Paste")
			(net 218 "/Bottom Connector/HDMI0.SCL")
			(pintype "passive")
		)
		(pad "MP" smd rect
			(at -10.274 -1.333 180)
			(size 0.35 0.66)
			(layers "B.Cu" "B.Mask" "B.Paste")
			(net 417 "GND")
			(pinfunction "MP")
			(pintype "passive")
		)
		(pad "MP" smd rect
			(at -10.274 1.377 180)
			(size 0.35 0.66)
			(layers "B.Cu" "B.Mask" "B.Paste")
			(net 417 "GND")
			(pinfunction "MP")
			(pintype "passive")
		)
		(pad "MP" smd rect
			(at 10.276 -1.333 180)
			(size 0.35 0.66)
			(layers "B.Cu" "B.Mask" "B.Paste")
			(net 417 "GND")
			(pinfunction "MP")
			(pintype "passive")
		)
		(pad "MP" smd rect
			(at 10.276 1.377 180)
			(size 0.35 0.66)
			(layers "B.Cu" "B.Mask" "B.Paste")
			(net 417 "GND")
			(pinfunction "MP")
			(pintype "passive")
		)
	)
	(footprint "antmicro-footprints:TP_SMD_0.75mm"
		(layer "B.Cu")
		(at 188.2 147.4 180)
		(property "Reference" "TP37"
			(at -3 -0.25 0)
			(layer "B.SilkS")
			(hide yes)
			(effects
				(font
					(size 0.7 0.7)
					(thickness 0.15)
				)
				(justify left bottom mirror)
			)
		)
		(property "Value" "TP_0.75mm_SMD"
			(at 0 -1.2 0)
			(layer "B.Fab")
			(hide yes)
			(effects
				(font
					(size 0.7 0.7)
					(thickness 0.15)
				)
				(justify left bottom mirror)
			)
		)
		(property "Description" "SMT test point"
			(at 0 0 0)
			(layer "B.Fab")
			(hide yes)
			(effects
				(font
					(size 1.27 1.27)
					(thickness 0.15)
				)
				(justify mirror)
			)
		)
		(property "MPN" ""
			(at 0 0 0)
			(unlocked yes)
			(layer "B.Fab")
			(hide yes)
			(effects
				(font
					(size 1 1)
					(thickness 0.15)
				)
				(justify mirror)
			)
		)
		(property "Manufacturer" ""
			(at 0 0 0)
			(unlocked yes)
			(layer "B.Fab")
			(hide yes)
			(effects
				(font
					(size 1 1)
					(thickness 0.15)
				)
				(justify mirror)
			)
		)
		(property "Author" "Antmicro"
			(at 0 0 0)
			(unlocked yes)
			(layer "B.Fab")
			(hide yes)
			(effects
				(font
					(size 1 1)
					(thickness 0.15)
				)
				(justify mirror)
			)
		)
		(property "License" "Apache-2.0"
			(at 0 0 0)
			(unlocked yes)
			(layer "B.Fab")
			(hide yes)
			(effects
				(font
					(size 1 1)
					(thickness 0.15)
				)
				(justify mirror)
			)
		)
		(property "Public" "False"
			(at 0 0 0)
			(unlocked yes)
			(layer "B.Fab")
			(hide yes)
			(effects
				(font
					(size 1 1)
					(thickness 0.15)
				)
				(justify mirror)
			)
		)
		(sheetname "/Supply/")
		(sheetfile "supply.kicad_sch")
		(attr exclude_from_pos_files exclude_from_bom)
		(fp_circle
			(center 0 0)
			(end 0.475 0)
			(stroke
				(width 0.05)
				(type default)
			)
			(fill no)
			(layer "B.CrtYd")
		)
		(fp_text user "Author: Antmicro"
			(at -0.4 -3.901 0)
			(layer "B.Fab")
			(effects
				(font
					(size 0.7 0.7)
					(thickness 0.15)
				)
				(justify left bottom mirror)
			)
		)
		(fp_text user "License: Apache-2.0"
			(at -0.4 -5.101 0)
			(layer "B.Fab")
			(effects
				(font
					(size 0.7 0.7)
					(thickness 0.15)
				)
				(justify left bottom mirror)
			)
		)
		(fp_text user "${REFERENCE}"
			(at -0.4 -2.7 0)
			(layer "B.Fab")
			(effects
				(font
					(size 0.7 0.7)
					(thickness 0.15)
				)
				(justify left bottom mirror)
			)
		)
		(pad "1" smd circle
			(at 0 0 180)
			(size 0.75 0.75)
			(layers "B.Cu" "B.Mask")
			(net 522 "/Supply/1V05_REG")
			(pinfunction "1")
			(pintype "passive")
		)
	)
	(footprint "antmicro-footprints:R_0402_1005Metric"
		(layer "B.Cu")
		(at 213.43 144.15)
		(descr "Resistor SMD 0402")
		(tags "resistor SMD 0402")
		(property "Reference" "R18"
			(at 1.07 1.4 180)
			(layer "B.SilkS")
			(effects
				(font
					(size 0.7 0.7)
					(thickness 0.15)
				)
				(justify left bottom mirror)
			)
		)
		(property "Value" "R_8k06_0402"
			(at -1.011843 -1.772047 180)
			(layer "B.Fab")
			(hide yes)
			(effects
				(font
					(size 0.7 0.7)
					(thickness 0.15)
				)
				(justify left bottom mirror)
			)
		)
		(property "Datasheet" "https://www.bourns.com/docs/product-datasheets/cr.pdf"
			(at 0 0 0)
			(layer "F.Fab")
			(hide yes)
			(effects
				(font
					(size 1.27 1.27)
					(thickness 0.15)
				)
			)
		)
		(property "Description" "SMD Chip Resistor, 8.06 kohm, ± 1%, 63 mW, 0402 [1005 Metric], Thick Film, General Purpose"
			(at 0 0 0)
			(layer "F.Fab")
			(hide yes)
			(effects
				(font
					(size 1.27 1.27)
					(thickness 0.15)
				)
			)
		)
		(property "Author" "Antmicro"
			(at 0 0 0)
			(layer "B.Fab")
			(hide yes)
			(effects
				(font
					(size 1 1)
					(thickness 0.15)
				)
				(justify mirror)
			)
		)
		(property "License" "Apache-2.0"
			(at 0 0 0)
			(layer "B.Fab")
			(hide yes)
			(effects
				(font
					(size 1 1)
					(thickness 0.15)
				)
				(justify mirror)
			)
		)
		(property "MPN" "CR0402-FX-8061GLF"
			(at 0 0 0)
			(layer "B.Fab")
			(hide yes)
			(effects
				(font
					(size 1 1)
					(thickness 0.15)
				)
				(justify mirror)
			)
		)
		(property "Manufacturer" "Bourns"
			(at 0 0 0)
			(layer "B.Fab")
			(hide yes)
			(effects
				(font
					(size 1 1)
					(thickness 0.15)
				)
				(justify mirror)
			)
		)
		(property "Public" ""
			(at 0 0 0)
			(layer "B.Fab")
			(hide yes)
			(effects
				(font
					(size 1 1)
					(thickness 0.15)
				)
				(justify mirror)
			)
		)
		(property "Tolerance" "1%"
			(at 0 0 0)
			(layer "B.Fab")
			(hide yes)
			(effects
				(font
					(size 1 1)
					(thickness 0.15)
				)
				(justify mirror)
			)
		)
		(property "Val" "8k06"
			(at 0 0 0)
			(layer "B.Fab")
			(hide yes)
			(effects
				(font
					(size 1 1)
					(thickness 0.15)
				)
				(justify mirror)
			)
		)
		(sheetname "/USB/")
		(sheetfile "usb.kicad_sch")
		(attr smd)
		(fp_rect
			(start -0.925 0.47)
			(end 0.925 -0.47)
			(stroke
				(width 0.05)
				(type default)
			)
			(fill no)
			(layer "B.CrtYd")
		)
		(fp_rect
			(start -0.5 0.25)
			(end 0.5 -0.25)
			(stroke
				(width 0.15)
				(type solid)
			)
			(fill no)
			(layer "B.Fab")
		)
		(fp_text user "License: Apache-2.0"
			(at -0.95 -5.169 180)
			(layer "B.Fab")
			(effects
				(font
					(size 0.7 0.7)
					(thickness 0.15)
				)
				(justify left bottom mirror)
			)
		)
		(fp_text user "${REFERENCE}"
			(at -0.95 -3.168 180)
			(layer "B.Fab")
			(effects
				(font
					(size 0.7 0.7)
					(thickness 0.15)
				)
				(justify left bottom mirror)
			)
		)
		(fp_text user "Author: Antmicro"
			(at -0.95 -4.169 180)
			(layer "B.Fab")
			(effects
				(font
					(size 0.7 0.7)
					(thickness 0.15)
				)
				(justify left bottom mirror)
			)
		)
		(pad "1" smd roundrect
			(at -0.48 0)
			(size 0.59 0.64)
			(layers "B.Cu" "B.Mask" "B.Paste")
			(roundrect_rratio 0.25)
			(net 280 "Net-(U13-RBIAS)")
			(pintype "passive")
		)
		(pad "2" smd roundrect
			(at 0.48 0)
			(size 0.59 0.64)
			(layers "B.Cu" "B.Mask" "B.Paste")
			(roundrect_rratio 0.25)
			(net 417 "GND")
			(pintype "passive")
		)
	)
	(footprint "antmicro-footprints:C_0402_1005Metric"
		(layer "B.Cu")
		(at 222.75 123 -90)
		(descr "Capacitor SMD 0402")
		(tags "capacitor SMD 0402")
		(property "Reference" "C4"
			(at -1.09 0.51 270)
			(layer "B.SilkS")
			(effects
				(font
					(size 0.7 0.7)
					(thickness 0.15)
				)
				(justify left bottom mirror)
			)
		)
		(property "Value" "C_100n_0402"
			(at -1.022927 -2.155213 90)
			(layer "B.Fab")
			(hide yes)
			(effects
				(font
					(size 0.7 0.7)
					(thickness 0.15)
				)
				(justify left bottom mirror)
			)
		)
		(property "Datasheet" "https://www.murata.com/products/productdetail?partno=GRM155R61H104KE14%23"
			(at 0 0 270)
			(layer "F.Fab")
			(hide yes)
			(effects
				(font
					(size 1.27 1.27)
					(thickness 0.15)
				)
			)
		)
		(property "Description" "SMD Multilayer Ceramic Capacitor, 0.1 µF, 50 V, 0402 [1005 Metric], ± 10%, X5R, GRM Series"
			(at 0 0 270)
			(layer "F.Fab")
			(hide yes)
			(effects
				(font
					(size 1.27 1.27)
					(thickness 0.15)
				)
			)
		)
		(property "Author" "Antmicro"
			(at 99.75 345.75 0)
			(layer "B.Fab")
			(hide yes)
			(effects
				(font
					(size 1 1)
					(thickness 0.15)
				)
				(justify mirror)
			)
		)
		(property "Dielectric" "X5R"
			(at 99.75 345.75 0)
			(layer "B.Fab")
			(hide yes)
			(effects
				(font
					(size 1 1)
					(thickness 0.15)
				)
				(justify mirror)
			)
		)
		(property "License" "Apache-2.0"
			(at 99.75 345.75 0)
			(layer "B.Fab")
			(hide yes)
			(effects
				(font
					(size 1 1)
					(thickness 0.15)
				)
				(justify mirror)
			)
		)
		(property "MPN" "GRM155R61H104KE14D"
			(at 99.75 345.75 0)
			(layer "B.Fab")
			(hide yes)
			(effects
				(font
					(size 1 1)
					(thickness 0.15)
				)
				(justify mirror)
			)
		)
		(property "Manufacturer" "Murata"
			(at 99.75 345.75 0)
			(layer "B.Fab")
			(hide yes)
			(effects
				(font
					(size 1 1)
					(thickness 0.15)
				)
				(justify mirror)
			)
		)
		(property "Public" ""
			(at 99.75 345.75 0)
			(layer "B.Fab")
			(hide yes)
			(effects
				(font
					(size 1 1)
					(thickness 0.15)
				)
				(justify mirror)
			)
		)
		(property "Val" "100n"
			(at 99.75 345.75 0)
			(layer "B.Fab")
			(hide yes)
			(effects
				(font
					(size 1 1)
					(thickness 0.15)
				)
				(justify mirror)
			)
		)
		(property "Voltage" "50V"
			(at 99.75 345.75 0)
			(layer "B.Fab")
			(hide yes)
			(effects
				(font
					(size 1 1)
					(thickness 0.15)
				)
				(justify mirror)
			)
		)
		(sheetname "/FPGA MSS/")
		(sheetfile "fpga-mss.kicad_sch")
		(attr smd)
		(fp_rect
			(start -0.925 0.47)
			(end 0.925 -0.47)
			(stroke
				(width 0.05)
				(type default)
			)
			(fill no)
			(layer "B.CrtYd")
		)
		(fp_line
			(start -0.494 0.25)
			(end 0.504 0.25)
			(stroke
				(width 0.15)
				(type solid)
			)
			(layer "B.Fab")
		)
		(fp_line
			(start 0.504 0.25)
			(end 0.504 -0.248)
			(stroke
				(width 0.15)
				(type solid)
			)
			(layer "B.Fab")
		)
		(fp_line
			(start -0.494 -0.248)
			(end -0.494 0.25)
			(stroke
				(width 0.15)
				(type solid)
			)
			(layer "B.Fab")
		)
		(fp_line
			(start 0.504 -0.248)
			(end -0.494 -0.248)
			(stroke
				(width 0.15)
				(type solid)
			)
			(layer "B.Fab")
		)
		(fp_text user "License: Apache-2.0"
			(at -0.939 -5.799 90)
			(layer "B.Fab")
			(effects
				(font
					(size 0.7 0.7)
					(thickness 0.15)
				)
				(justify left bottom mirror)
			)
		)
		(fp_text user "${REFERENCE}"
			(at -0.939 -4.599 90)
			(layer "B.Fab")
			(effects
				(font
					(size 0.7 0.7)
					(thickness 0.15)
				)
				(justify left bottom mirror)
			)
		)
		(fp_text user "Author: Antmicro"
			(at -0.939 -3.399 90)
			(layer "B.Fab")
			(effects
				(font
					(size 0.7 0.7)
					(thickness 0.15)
				)
				(justify left bottom mirror)
			)
		)
		(pad "1" smd roundrect
			(at -0.48 0 270)
			(size 0.59 0.64)
			(layers "B.Cu" "B.Mask" "B.Paste")
			(roundrect_rratio 0.25)
			(net 417 "GND")
			(pintype "passive")
		)
		(pad "2" smd roundrect
			(at 0.48 0 270)
			(size 0.59 0.64)
			(layers "B.Cu" "B.Mask" "B.Paste")
			(roundrect_rratio 0.25)
			(net 50 "+3V3")
			(pintype "passive")
		)
	)
	(footprint "antmicro-footprints:C_0402_1005Metric"
		(layer "B.Cu")
		(at 197.04 136.674 90)
		(descr "Capacitor SMD 0402")
		(tags "capacitor SMD 0402")
		(property "Reference" "C59"
			(at 7.224 -9.615 270)
			(layer "B.SilkS")
			(effects
				(font
					(size 0.7 0.7)
					(thickness 0.15)
				)
				(justify left bottom mirror)
			)
		)
		(property "Value" "C_100n_0402"
			(at -1.022927 -2.155213 270)
			(layer "B.Fab")
			(hide yes)
			(effects
				(font
					(size 0.7 0.7)
					(thickness 0.15)
				)
				(justify left bottom mirror)
			)
		)
		(property "Datasheet" "https://www.murata.com/products/productdetail?partno=GRM155R61H104KE14%23"
			(at 0 0 90)
			(layer "F.Fab")
			(hide yes)
			(effects
				(font
					(size 1.27 1.27)
					(thickness 0.15)
				)
			)
		)
		(property "Description" "SMD Multilayer Ceramic Capacitor, 0.1 µF, 50 V, 0402 [1005 Metric], ± 10%, X5R, GRM Series"
			(at 0 0 90)
			(layer "F.Fab")
			(hide yes)
			(effects
				(font
					(size 1.27 1.27)
					(thickness 0.15)
				)
			)
		)
		(property "Author" "Antmicro"
			(at 333.714 -60.366 0)
			(layer "B.Fab")
			(hide yes)
			(effects
				(font
					(size 1 1)
					(thickness 0.15)
				)
				(justify mirror)
			)
		)
		(property "Dielectric" "X5R"
			(at 333.714 -60.366 0)
			(layer "B.Fab")
			(hide yes)
			(effects
				(font
					(size 1 1)
					(thickness 0.15)
				)
				(justify mirror)
			)
		)
		(property "License" "Apache-2.0"
			(at 333.714 -60.366 0)
			(layer "B.Fab")
			(hide yes)
			(effects
				(font
					(size 1 1)
					(thickness 0.15)
				)
				(justify mirror)
			)
		)
		(property "MPN" "GRM155R61H104KE14D"
			(at 333.714 -60.366 0)
			(layer "B.Fab")
			(hide yes)
			(effects
				(font
					(size 1 1)
					(thickness 0.15)
				)
				(justify mirror)
			)
		)
		(property "Manufacturer" "Murata"
			(at 333.714 -60.366 0)
			(layer "B.Fab")
			(hide yes)
			(effects
				(font
					(size 1 1)
					(thickness 0.15)
				)
				(justify mirror)
			)
		)
		(property "Public" ""
			(at 333.714 -60.366 0)
			(layer "B.Fab")
			(hide yes)
			(effects
				(font
					(size 1 1)
					(thickness 0.15)
				)
				(justify mirror)
			)
		)
		(property "Val" "100n"
			(at 333.714 -60.366 0)
			(layer "B.Fab")
			(hide yes)
			(effects
				(font
					(size 1 1)
					(thickness 0.15)
				)
				(justify mirror)
			)
		)
		(property "Voltage" "50V"
			(at 333.714 -60.366 0)
			(layer "B.Fab")
			(hide yes)
			(effects
				(font
					(size 1 1)
					(thickness 0.15)
				)
				(justify mirror)
			)
		)
		(sheetname "/FPGA Supply/")
		(sheetfile "fpga-supply.kicad_sch")
		(attr smd)
		(fp_rect
			(start -0.925 0.47)
			(end 0.925 -0.47)
			(stroke
				(width 0.05)
				(type default)
			)
			(fill no)
			(layer "B.CrtYd")
		)
		(fp_line
			(start 0.504 -0.248)
			(end -0.494 -0.248)
			(stroke
				(width 0.15)
				(type solid)
			)
			(layer "B.Fab")
		)
		(fp_line
			(start -0.494 -0.248)
			(end -0.494 0.25)
			(stroke
				(width 0.15)
				(type solid)
			)
			(layer "B.Fab")
		)
		(fp_line
			(start 0.504 0.25)
			(end 0.504 -0.248)
			(stroke
				(width 0.15)
				(type solid)
			)
			(layer "B.Fab")
		)
		(fp_line
			(start -0.494 0.25)
			(end 0.504 0.25)
			(stroke
				(width 0.15)
				(type solid)
			)
			(layer "B.Fab")
		)
		(fp_text user "${REFERENCE}"
			(at -0.939 -4.599 270)
			(layer "B.Fab")
			(effects
				(font
					(size 0.7 0.7)
					(thickness 0.15)
				)
				(justify left bottom mirror)
			)
		)
		(fp_text user "License: Apache-2.0"
			(at -0.939 -5.799 270)
			(layer "B.Fab")
			(effects
				(font
					(size 0.7 0.7)
					(thickness 0.15)
				)
				(justify left bottom mirror)
			)
		)
		(fp_text user "Author: Antmicro"
			(at -0.939 -3.399 270)
			(layer "B.Fab")
			(effects
				(font
					(size 0.7 0.7)
					(thickness 0.15)
				)
				(justify left bottom mirror)
			)
		)
		(pad "1" smd roundrect
			(at -0.48 0 90)
			(size 0.59 0.64)
			(layers "B.Cu" "B.Mask" "B.Paste")
			(roundrect_rratio 0.25)
			(net 417 "GND")
			(pintype "passive")
		)
		(pad "2" smd roundrect
			(at 0.48 0 90)
			(size 0.59 0.64)
			(layers "B.Cu" "B.Mask" "B.Paste")
			(roundrect_rratio 0.25)
			(net 47 "+1V05")
			(pintype "passive")
		)
	)
	(footprint "antmicro-footprints:C_0402_1005Metric"
		(layer "B.Cu")
		(at 198.94 136.664 90)
		(descr "Capacitor SMD 0402")
		(tags "capacitor SMD 0402")
		(property "Reference" "C48"
			(at 4.564 -9.615 90)
			(layer "B.SilkS")
			(effects
				(font
					(size 0.7 0.7)
					(thickness 0.15)
				)
				(justify right bottom mirror)
			)
		)
		(property "Value" "C_47n_0402"
			(at -1.022927 -2.155213 90)
			(layer "B.Fab")
			(hide yes)
			(effects
				(font
					(size 0.7 0.7)
					(thickness 0.15)
				)
				(justify right bottom mirror)
			)
		)
		(property "Datasheet" "https://www.murata.com/en-us/products/productdetail?partno=GRM155R61C473KA01%23"
			(at 0 0 90)
			(layer "F.Fab")
			(hide yes)
			(effects
				(font
					(size 1.27 1.27)
					(thickness 0.15)
				)
			)
		)
		(property "Description" "SMD Multilayer Ceramic Capacitor, 47000 pF, 16 V, 0402 [1005 Metric], ± 10%, X5R, MC"
			(at 0 0 90)
			(layer "F.Fab")
			(hide yes)
			(effects
				(font
					(size 1.27 1.27)
					(thickness 0.15)
				)
			)
		)
		(property "Author" "Antmicro"
			(at 335.604 -62.276 0)
			(layer "B.Fab")
			(hide yes)
			(effects
				(font
					(size 1 1)
					(thickness 0.15)
				)
				(justify mirror)
			)
		)
		(property "Dielectric" "X5R"
			(at 335.604 -62.276 0)
			(layer "B.Fab")
			(hide yes)
			(effects
				(font
					(size 1 1)
					(thickness 0.15)
				)
				(justify mirror)
			)
		)
		(property "License" "Apache-2.0"
			(at 335.604 -62.276 0)
			(layer "B.Fab")
			(hide yes)
			(effects
				(font
					(size 1 1)
					(thickness 0.15)
				)
				(justify mirror)
			)
		)
		(property "MPN" "GRM155R61C473KA01D"
			(at 335.604 -62.276 0)
			(layer "B.Fab")
			(hide yes)
			(effects
				(font
					(size 1 1)
					(thickness 0.15)
				)
				(justify mirror)
			)
		)
		(property "Manufacturer" "Murata"
			(at 335.604 -62.276 0)
			(layer "B.Fab")
			(hide yes)
			(effects
				(font
					(size 1 1)
					(thickness 0.15)
				)
				(justify mirror)
			)
		)
		(property "Public" ""
			(at 335.604 -62.276 0)
			(layer "B.Fab")
			(hide yes)
			(effects
				(font
					(size 1 1)
					(thickness 0.15)
				)
				(justify mirror)
			)
		)
		(property "Val" "47n"
			(at 335.604 -62.276 0)
			(layer "B.Fab")
			(hide yes)
			(effects
				(font
					(size 1 1)
					(thickness 0.15)
				)
				(justify mirror)
			)
		)
		(property "Voltage" "10V"
			(at 335.604 -62.276 0)
			(layer "B.Fab")
			(hide yes)
			(effects
				(font
					(size 1 1)
					(thickness 0.15)
				)
				(justify mirror)
			)
		)
		(sheetname "/FPGA Supply/")
		(sheetfile "fpga-supply.kicad_sch")
		(attr smd)
		(fp_rect
			(start -0.925 0.47)
			(end 0.925 -0.47)
			(stroke
				(width 0.05)
				(type default)
			)
			(fill no)
			(layer "B.CrtYd")
		)
		(fp_line
			(start 0.504 -0.248)
			(end -0.494 -0.248)
			(stroke
				(width 0.15)
				(type solid)
			)
			(layer "B.Fab")
		)
		(fp_line
			(start -0.494 -0.248)
			(end -0.494 0.25)
			(stroke
				(width 0.15)
				(type solid)
			)
			(layer "B.Fab")
		)
		(fp_line
			(start 0.504 0.25)
			(end 0.504 -0.248)
			(stroke
				(width 0.15)
				(type solid)
			)
			(layer "B.Fab")
		)
		(fp_line
			(start -0.494 0.25)
			(end 0.504 0.25)
			(stroke
				(width 0.15)
				(type solid)
			)
			(layer "B.Fab")
		)
		(fp_text user "Author: Antmicro"
			(at -0.939 -3.399 270)
			(layer "B.Fab")
			(effects
				(font
					(size 0.7 0.7)
					(thickness 0.15)
				)
				(justify left bottom mirror)
			)
		)
		(fp_text user "License: Apache-2.0"
			(at -0.939 -5.799 270)
			(layer "B.Fab")
			(effects
				(font
					(size 0.7 0.7)
					(thickness 0.15)
				)
				(justify left bottom mirror)
			)
		)
		(fp_text user "${REFERENCE}"
			(at -0.939 -4.599 270)
			(layer "B.Fab")
			(effects
				(font
					(size 0.7 0.7)
					(thickness 0.15)
				)
				(justify left bottom mirror)
			)
		)
		(pad "1" smd roundrect
			(at -0.48 0 90)
			(size 0.59 0.64)
			(layers "B.Cu" "B.Mask" "B.Paste")
			(roundrect_rratio 0.25)
			(net 417 "GND")
			(pintype "passive")
		)
		(pad "2" smd roundrect
			(at 0.48 0 90)
			(size 0.59 0.64)
			(layers "B.Cu" "B.Mask" "B.Paste")
			(roundrect_rratio 0.25)
			(net 47 "+1V05")
			(pintype "passive")
		)
	)
	(footprint "antmicro-footprints:C_0402_1005Metric"
		(layer "B.Cu")
		(at 212.1925 134.697)
		(descr "Capacitor SMD 0402")
		(tags "capacitor SMD 0402")
		(property "Reference" "C78"
			(at -0.4175 2.528 0)
			(layer "B.SilkS")
			(effects
				(font
					(size 0.7 0.7)
					(thickness 0.15)
				)
				(justify right bottom mirror)
			)
		)
		(property "Value" "C_100n_0402"
			(at -1.022927 -2.155213 0)
			(layer "B.Fab")
			(hide yes)
			(effects
				(font
					(size 0.7 0.7)
					(thickness 0.15)
				)
				(justify right bottom mirror)
			)
		)
		(property "Datasheet" "https://www.murata.com/products/productdetail?partno=GRM155R61H104KE14%23"
			(at 0 0 0)
			(layer "F.Fab")
			(hide yes)
			(effects
				(font
					(size 1.27 1.27)
					(thickness 0.15)
				)
			)
		)
		(property "Description" "SMD Multilayer Ceramic Capacitor, 0.1 µF, 50 V, 0402 [1005 Metric], ± 10%, X5R, GRM Series"
			(at 0 0 0)
			(layer "F.Fab")
			(hide yes)
			(effects
				(font
					(size 1.27 1.27)
					(thickness 0.15)
				)
			)
		)
		(property "Author" "Antmicro"
			(at 0 0 0)
			(layer "B.Fab")
			(hide yes)
			(effects
				(font
					(size 1 1)
					(thickness 0.15)
				)
				(justify mirror)
			)
		)
		(property "Dielectric" "X5R"
			(at 0 0 0)
			(layer "B.Fab")
			(hide yes)
			(effects
				(font
					(size 1 1)
					(thickness 0.15)
				)
				(justify mirror)
			)
		)
		(property "License" "Apache-2.0"
			(at 0 0 0)
			(layer "B.Fab")
			(hide yes)
			(effects
				(font
					(size 1 1)
					(thickness 0.15)
				)
				(justify mirror)
			)
		)
		(property "MPN" "GRM155R61H104KE14D"
			(at 0 0 0)
			(layer "B.Fab")
			(hide yes)
			(effects
				(font
					(size 1 1)
					(thickness 0.15)
				)
				(justify mirror)
			)
		)
		(property "Manufacturer" "Murata"
			(at 0 0 0)
			(layer "B.Fab")
			(hide yes)
			(effects
				(font
					(size 1 1)
					(thickness 0.15)
				)
				(justify mirror)
			)
		)
		(property "Public" ""
			(at 0 0 0)
			(layer "B.Fab")
			(hide yes)
			(effects
				(font
					(size 1 1)
					(thickness 0.15)
				)
				(justify mirror)
			)
		)
		(property "Val" "100n"
			(at 0 0 0)
			(layer "B.Fab")
			(hide yes)
			(effects
				(font
					(size 1 1)
					(thickness 0.15)
				)
				(justify mirror)
			)
		)
		(property "Voltage" "50V"
			(at 0 0 0)
			(layer "B.Fab")
			(hide yes)
			(effects
				(font
					(size 1 1)
					(thickness 0.15)
				)
				(justify mirror)
			)
		)
		(sheetname "/Memory/")
		(sheetfile "memory.kicad_sch")
		(attr smd)
		(fp_rect
			(start -0.925 0.47)
			(end 0.925 -0.47)
			(stroke
				(width 0.05)
				(type default)
			)
			(fill no)
			(layer "B.CrtYd")
		)
		(fp_line
			(start -0.494 -0.248)
			(end -0.494 0.25)
			(stroke
				(width 0.15)
				(type solid)
			)
			(layer "B.Fab")
		)
		(fp_line
			(start -0.494 0.25)
			(end 0.504 0.25)
			(stroke
				(width 0.15)
				(type solid)
			)
			(layer "B.Fab")
		)
		(fp_line
			(start 0.504 -0.248)
			(end -0.494 -0.248)
			(stroke
				(width 0.15)
				(type solid)
			)
			(layer "B.Fab")
		)
		(fp_line
			(start 0.504 0.25)
			(end 0.504 -0.248)
			(stroke
				(width 0.15)
				(type solid)
			)
			(layer "B.Fab")
		)
		(fp_text user "License: Apache-2.0"
			(at -0.939 -5.799 180)
			(layer "B.Fab")
			(effects
				(font
					(size 0.7 0.7)
					(thickness 0.15)
				)
				(justify left bottom mirror)
			)
		)
		(fp_text user "${REFERENCE}"
			(at -0.939 -4.599 180)
			(layer "B.Fab")
			(effects
				(font
					(size 0.7 0.7)
					(thickness 0.15)
				)
				(justify left bottom mirror)
			)
		)
		(fp_text user "Author: Antmicro"
			(at -0.939 -3.399 180)
			(layer "B.Fab")
			(effects
				(font
					(size 0.7 0.7)
					(thickness 0.15)
				)
				(justify left bottom mirror)
			)
		)
		(pad "1" smd roundrect
			(at -0.48 0)
			(size 0.59 0.64)
			(layers "B.Cu" "B.Mask" "B.Paste")
			(roundrect_rratio 0.25)
			(net 417 "GND")
			(pintype "passive")
		)
		(pad "2" smd roundrect
			(at 0.48 0)
			(size 0.59 0.64)
			(layers "B.Cu" "B.Mask" "B.Paste")
			(roundrect_rratio 0.25)
			(net 137 "SD_VDD")
			(pintype "passive")
		)
	)
	(footprint "antmicro-footprints:C_0603_1608Metric"
		(layer "B.Cu")
		(at 193.5 135.52)
		(descr "Capacitor SMD 0603")
		(tags "capacitor 0603")
		(property "Reference" "C29"
			(at -1.4 1.53 0)
			(layer "B.SilkS")
			(effects
				(font
					(size 0.7 0.7)
					(thickness 0.15)
				)
				(justify right bottom mirror)
			)
		)
		(property "Value" "C_47u_0603"
			(at -1.42757 -1.770288 0)
			(layer "B.Fab")
			(hide yes)
			(effects
				(font
					(size 0.7 0.7)
					(thickness 0.15)
				)
				(justify right bottom mirror)
			)
		)
		(property "Datasheet" "https://www.murata.com/products/productdetail?partno=GRM188R60J476ME15%23"
			(at 0 0 0)
			(layer "F.Fab")
			(hide yes)
			(effects
				(font
					(size 1.27 1.27)
					(thickness 0.15)
				)
			)
		)
		(property "Description" "SMD Multilayer Ceramic Capacitor, 47 µF, 6.3 V, 0603 [1608 Metric], ± 20%, X5R, GRM Series"
			(at 0 0 0)
			(layer "F.Fab")
			(hide yes)
			(effects
				(font
					(size 1.27 1.27)
					(thickness 0.15)
				)
			)
		)
		(property "Author" "Antmicro"
			(at 0 0 0)
			(layer "B.Fab")
			(hide yes)
			(effects
				(font
					(size 1 1)
					(thickness 0.15)
				)
				(justify mirror)
			)
		)
		(property "Capacitance" "47u"
			(at 0 0 0)
			(layer "B.Fab")
			(hide yes)
			(effects
				(font
					(size 1 1)
					(thickness 0.15)
				)
				(justify mirror)
			)
		)
		(property "Dielectric" "X7R"
			(at 0 0 0)
			(layer "B.Fab")
			(hide yes)
			(effects
				(font
					(size 1 1)
					(thickness 0.15)
				)
				(justify mirror)
			)
		)
		(property "License" "Apache-2.0"
			(at 0 0 0)
			(layer "B.Fab")
			(hide yes)
			(effects
				(font
					(size 1 1)
					(thickness 0.15)
				)
				(justify mirror)
			)
		)
		(property "MPN" "GRM188R60J476ME15D"
			(at 0 0 0)
			(layer "B.Fab")
			(hide yes)
			(effects
				(font
					(size 1 1)
					(thickness 0.15)
				)
				(justify mirror)
			)
		)
		(property "Manufacturer" "Murata"
			(at 0 0 0)
			(layer "B.Fab")
			(hide yes)
			(effects
				(font
					(size 1 1)
					(thickness 0.15)
				)
				(justify mirror)
			)
		)
		(property "Public" ""
			(at 0 0 0)
			(layer "B.Fab")
			(hide yes)
			(effects
				(font
					(size 1 1)
					(thickness 0.15)
				)
				(justify mirror)
			)
		)
		(property "Val" "47u"
			(at 0 0 0)
			(layer "B.Fab")
			(hide yes)
			(effects
				(font
					(size 1 1)
					(thickness 0.15)
				)
				(justify mirror)
			)
		)
		(property "Voltage" "50V"
			(at 0 0 0)
			(layer "B.Fab")
			(hide yes)
			(effects
				(font
					(size 1 1)
					(thickness 0.15)
				)
				(justify mirror)
			)
		)
		(sheetname "/FPGA Supply/")
		(sheetfile "fpga-supply.kicad_sch")
		(attr smd)
		(fp_line
			(start -0.15 -0.4)
			(end 0.15 -0.4)
			(stroke
				(width 0.15)
				(type solid)
			)
			(layer "B.SilkS")
		)
		(fp_line
			(start -0.15 0.4)
			(end 0.15 0.4)
			(stroke
				(width 0.15)
				(type solid)
			)
			(layer "B.SilkS")
		)
		(fp_rect
			(start -1.25 0.65)
			(end 1.25 -0.65)
			(stroke
				(width 0.05)
				(type solid)
			)
			(fill no)
			(layer "B.CrtYd")
		)
		(fp_rect
			(start -0.8 0.4)
			(end 0.8 -0.4)
			(stroke
				(width 0.15)
				(type solid)
			)
			(fill no)
			(layer "B.Fab")
		)
		(fp_text user "License: Apache-2.0"
			(at -1.682 -5.895 180)
			(layer "B.Fab")
			(effects
				(font
					(size 0.7 0.7)
					(thickness 0.15)
				)
				(justify left bottom mirror)
			)
		)
		(fp_text user "${REFERENCE}"
			(at -1.682 -3.895 180)
			(layer "B.Fab")
			(effects
				(font
					(size 0.7 0.7)
					(thickness 0.15)
				)
				(justify left bottom mirror)
			)
		)
		(fp_text user "Author: Antmicro"
			(at -1.682 -4.894 180)
			(layer "B.Fab")
			(effects
				(font
					(size 0.7 0.7)
					(thickness 0.15)
				)
				(justify left bottom mirror)
			)
		)
		(pad "1" smd roundrect
			(at -0.7 0)
			(size 0.8 1)
			(layers "B.Cu" "B.Mask" "B.Paste")
			(roundrect_rratio 0.2)
			(net 417 "GND")
			(pintype "passive")
		)
		(pad "2" smd roundrect
			(at 0.7 0)
			(size 0.8 1)
			(layers "B.Cu" "B.Mask" "B.Paste")
			(roundrect_rratio 0.2)
			(net 418 "+2V5")
			(pintype "passive")
		)
	)
	(footprint "antmicro-footprints:C_0402_1005Metric"
		(layer "B.Cu")
		(at 175.28 124.9 -90)
		(descr "Capacitor SMD 0402")
		(tags "capacitor SMD 0402")
		(property "Reference" "C118"
			(at -1.04 -4.23 180)
			(layer "B.SilkS")
			(effects
				(font
					(size 0.7 0.7)
					(thickness 0.15)
				)
				(justify left bottom mirror)
			)
		)
		(property "Value" "C_1u_0402"
			(at -1.022927 -2.155213 90)
			(layer "B.Fab")
			(hide yes)
			(effects
				(font
					(size 0.7 0.7)
					(thickness 0.15)
				)
				(justify left bottom mirror)
			)
		)
		(property "Datasheet" "https://product.tdk.com/en/search/capacitor/ceramic/mlcc/info?part_no=C1005X6S1A105K050BC"
			(at 0 0 270)
			(layer "F.Fab")
			(hide yes)
			(effects
				(font
					(size 1.27 1.27)
					(thickness 0.15)
				)
			)
		)
		(property "Description" "SMD Multilayer Ceramic Capacitor, 1 µF, 10 V, 0402 [1005 Metric], ± 10%, X6S, C"
			(at 0 0 270)
			(layer "F.Fab")
			(hide yes)
			(effects
				(font
					(size 1.27 1.27)
					(thickness 0.15)
				)
			)
		)
		(property "Author" "Antmicro"
			(at 50.38 300.18 0)
			(layer "B.Fab")
			(hide yes)
			(effects
				(font
					(size 1 1)
					(thickness 0.15)
				)
				(justify mirror)
			)
		)
		(property "Dielectric" "X5R"
			(at 50.38 300.18 0)
			(layer "B.Fab")
			(hide yes)
			(effects
				(font
					(size 1 1)
					(thickness 0.15)
				)
				(justify mirror)
			)
		)
		(property "License" "Apache-2.0"
			(at 50.38 300.18 0)
			(layer "B.Fab")
			(hide yes)
			(effects
				(font
					(size 1 1)
					(thickness 0.15)
				)
				(justify mirror)
			)
		)
		(property "MPN" "C1005X6S1A105K050BC"
			(at 50.38 300.18 0)
			(layer "B.Fab")
			(hide yes)
			(effects
				(font
					(size 1 1)
					(thickness 0.15)
				)
				(justify mirror)
			)
		)
		(property "Manufacturer" "TDK"
			(at 50.38 300.18 0)
			(layer "B.Fab")
			(hide yes)
			(effects
				(font
					(size 1 1)
					(thickness 0.15)
				)
				(justify mirror)
			)
		)
		(property "Public" ""
			(at 50.38 300.18 0)
			(layer "B.Fab")
			(hide yes)
			(effects
				(font
					(size 1 1)
					(thickness 0.15)
				)
				(justify mirror)
			)
		)
		(property "Val" "1u"
			(at 50.38 300.18 0)
			(layer "B.Fab")
			(hide yes)
			(effects
				(font
					(size 1 1)
					(thickness 0.15)
				)
				(justify mirror)
			)
		)
		(property "Voltage" "16V"
			(at 50.38 300.18 0)
			(layer "B.Fab")
			(hide yes)
			(effects
				(font
					(size 1 1)
					(thickness 0.15)
				)
				(justify mirror)
			)
		)
		(sheetname "/LPDDR4/")
		(sheetfile "lpddr.kicad_sch")
		(attr smd)
		(fp_rect
			(start -0.925 0.47)
			(end 0.925 -0.47)
			(stroke
				(width 0.05)
				(type default)
			)
			(fill no)
			(layer "B.CrtYd")
		)
		(fp_line
			(start -0.494 0.25)
			(end 0.504 0.25)
			(stroke
				(width 0.15)
				(type solid)
			)
			(layer "B.Fab")
		)
		(fp_line
			(start 0.504 0.25)
			(end 0.504 -0.248)
			(stroke
				(width 0.15)
				(type solid)
			)
			(layer "B.Fab")
		)
		(fp_line
			(start -0.494 -0.248)
			(end -0.494 0.25)
			(stroke
				(width 0.15)
				(type solid)
			)
			(layer "B.Fab")
		)
		(fp_line
			(start 0.504 -0.248)
			(end -0.494 -0.248)
			(stroke
				(width 0.15)
				(type solid)
			)
			(layer "B.Fab")
		)
		(fp_text user "${REFERENCE}"
			(at -0.939 -4.599 90)
			(layer "B.Fab")
			(effects
				(font
					(size 0.7 0.7)
					(thickness 0.15)
				)
				(justify left bottom mirror)
			)
		)
		(fp_text user "Author: Antmicro"
			(at -0.939 -3.399 90)
			(layer "B.Fab")
			(effects
				(font
					(size 0.7 0.7)
					(thickness 0.15)
				)
				(justify left bottom mirror)
			)
		)
		(fp_text user "License: Apache-2.0"
			(at -0.939 -5.799 90)
			(layer "B.Fab")
			(effects
				(font
					(size 0.7 0.7)
					(thickness 0.15)
				)
				(justify left bottom mirror)
			)
		)
		(pad "1" smd roundrect
			(at -0.48 0 270)
			(size 0.59 0.64)
			(layers "B.Cu" "B.Mask" "B.Paste")
			(roundrect_rratio 0.25)
			(net 417 "GND")
			(pintype "passive")
		)
		(pad "2" smd roundrect
			(at 0.48 0 270)
			(size 0.59 0.64)
			(layers "B.Cu" "B.Mask" "B.Paste")
			(roundrect_rratio 0.25)
			(net 48 "+1V8")
			(pintype "passive")
		)
	)
	(footprint "antmicro-footprints:C_0402_1005Metric"
		(layer "B.Cu")
		(at 218.725 144.8875 -90)
		(descr "Capacitor SMD 0402")
		(tags "capacitor SMD 0402")
		(property "Reference" "C231"
			(at -9.9125 -7.15 90)
			(layer "B.SilkS")
			(effects
				(font
					(size 0.7 0.7)
					(thickness 0.15)
				)
				(justify left bottom mirror)
			)
		)
		(property "Value" "C_100n_0402"
			(at -1.022927 -2.155213 90)
			(layer "B.Fab")
			(hide yes)
			(effects
				(font
					(size 0.7 0.7)
					(thickness 0.15)
				)
				(justify left bottom mirror)
			)
		)
		(property "Datasheet" "https://www.murata.com/products/productdetail?partno=GRM155R61H104KE14%23"
			(at 0 0 270)
			(layer "F.Fab")
			(hide yes)
			(effects
				(font
					(size 1.27 1.27)
					(thickness 0.15)
				)
			)
		)
		(property "Description" "SMD Multilayer Ceramic Capacitor, 0.1 µF, 50 V, 0402 [1005 Metric], ± 10%, X5R, GRM Series"
			(at 0 0 270)
			(layer "F.Fab")
			(hide yes)
			(effects
				(font
					(size 1.27 1.27)
					(thickness 0.15)
				)
			)
		)
		(property "Author" "Antmicro"
			(at 73.8375 363.6125 0)
			(layer "B.Fab")
			(hide yes)
			(effects
				(font
					(size 1 1)
					(thickness 0.15)
				)
				(justify mirror)
			)
		)
		(property "Dielectric" "X5R"
			(at 73.8375 363.6125 0)
			(layer "B.Fab")
			(hide yes)
			(effects
				(font
					(size 1 1)
					(thickness 0.15)
				)
				(justify mirror)
			)
		)
		(property "License" "Apache-2.0"
			(at 73.8375 363.6125 0)
			(layer "B.Fab")
			(hide yes)
			(effects
				(font
					(size 1 1)
					(thickness 0.15)
				)
				(justify mirror)
			)
		)
		(property "MPN" "GRM155R61H104KE14D"
			(at 73.8375 363.6125 0)
			(layer "B.Fab")
			(hide yes)
			(effects
				(font
					(size 1 1)
					(thickness 0.15)
				)
				(justify mirror)
			)
		)
		(property "Manufacturer" "Murata"
			(at 73.8375 363.6125 0)
			(layer "B.Fab")
			(hide yes)
			(effects
				(font
					(size 1 1)
					(thickness 0.15)
				)
				(justify mirror)
			)
		)
		(property "Public" ""
			(at 73.8375 363.6125 0)
			(layer "B.Fab")
			(hide yes)
			(effects
				(font
					(size 1 1)
					(thickness 0.15)
				)
				(justify mirror)
			)
		)
		(property "Val" "100n"
			(at 73.8375 363.6125 0)
			(layer "B.Fab")
			(hide yes)
			(effects
				(font
					(size 1 1)
					(thickness 0.15)
				)
				(justify mirror)
			)
		)
		(property "Voltage" "50V"
			(at 73.8375 363.6125 0)
			(layer "B.Fab")
			(hide yes)
			(effects
				(font
					(size 1 1)
					(thickness 0.15)
				)
				(justify mirror)
			)
		)
		(sheetname "/WiFi_Bluetooth/")
		(sheetfile "wifi_bt.kicad_sch")
		(attr smd)
		(fp_rect
			(start -0.925 0.47)
			(end 0.925 -0.47)
			(stroke
				(width 0.05)
				(type default)
			)
			(fill no)
			(layer "B.CrtYd")
		)
		(fp_line
			(start -0.494 0.25)
			(end 0.504 0.25)
			(stroke
				(width 0.15)
				(type solid)
			)
			(layer "B.Fab")
		)
		(fp_line
			(start 0.504 0.25)
			(end 0.504 -0.248)
			(stroke
				(width 0.15)
				(type solid)
			)
			(layer "B.Fab")
		)
		(fp_line
			(start -0.494 -0.248)
			(end -0.494 0.25)
			(stroke
				(width 0.15)
				(type solid)
			)
			(layer "B.Fab")
		)
		(fp_line
			(start 0.504 -0.248)
			(end -0.494 -0.248)
			(stroke
				(width 0.15)
				(type solid)
			)
			(layer "B.Fab")
		)
		(fp_text user "License: Apache-2.0"
			(at -0.939 -5.799 90)
			(layer "B.Fab")
			(effects
				(font
					(size 0.7 0.7)
					(thickness 0.15)
				)
				(justify left bottom mirror)
			)
		)
		(fp_text user "Author: Antmicro"
			(at -0.939 -3.399 90)
			(layer "B.Fab")
			(effects
				(font
					(size 0.7 0.7)
					(thickness 0.15)
				)
				(justify left bottom mirror)
			)
		)
		(fp_text user "${REFERENCE}"
			(at -0.939 -4.599 90)
			(layer "B.Fab")
			(effects
				(font
					(size 0.7 0.7)
					(thickness 0.15)
				)
				(justify left bottom mirror)
			)
		)
		(pad "1" smd roundrect
			(at -0.48 0 270)
			(size 0.59 0.64)
			(layers "B.Cu" "B.Mask" "B.Paste")
			(roundrect_rratio 0.25)
			(net 417 "GND")
			(pintype "passive")
		)
		(pad "2" smd roundrect
			(at 0.48 0 270)
			(size 0.59 0.64)
			(layers "B.Cu" "B.Mask" "B.Paste")
			(roundrect_rratio 0.25)
			(net 50 "+3V3")
			(pintype "passive")
		)
	)
	(footprint "antmicro-footprints:C_0402_1005Metric"
		(layer "B.Cu")
		(at 175.29 122.9395 -90)
		(descr "Capacitor SMD 0402")
		(tags "capacitor SMD 0402")
		(property "Reference" "C150"
			(at -1.2395 -1.32 90)
			(unlocked yes)
			(layer "B.SilkS")
			(effects
				(font
					(size 0.7 0.7)
					(thickness 0.15)
				)
				(justify left bottom mirror)
			)
		)
		(property "Value" "C_1u_0402"
			(at -1.022927 -2.155213 90)
			(layer "B.Fab")
			(hide yes)
			(effects
				(font
					(size 0.7 0.7)
					(thickness 0.15)
				)
				(justify left bottom mirror)
			)
		)
		(property "Datasheet" "https://product.tdk.com/en/search/capacitor/ceramic/mlcc/info?part_no=C1005X6S1A105K050BC"
			(at 0 0 270)
			(layer "F.Fab")
			(hide yes)
			(effects
				(font
					(size 1.27 1.27)
					(thickness 0.15)
				)
			)
		)
		(property "Description" "SMD Multilayer Ceramic Capacitor, 1 µF, 10 V, 0402 [1005 Metric], ± 10%, X6S, C"
			(at 0 0 270)
			(layer "F.Fab")
			(hide yes)
			(effects
				(font
					(size 1.27 1.27)
					(thickness 0.15)
				)
			)
		)
		(property "Author" "Antmicro"
			(at 52.3505 298.2295 0)
			(layer "B.Fab")
			(hide yes)
			(effects
				(font
					(size 1 1)
					(thickness 0.15)
				)
				(justify mirror)
			)
		)
		(property "Dielectric" "X5R"
			(at 52.3505 298.2295 0)
			(layer "B.Fab")
			(hide yes)
			(effects
				(font
					(size 1 1)
					(thickness 0.15)
				)
				(justify mirror)
			)
		)
		(property "License" "Apache-2.0"
			(at 52.3505 298.2295 0)
			(layer "B.Fab")
			(hide yes)
			(effects
				(font
					(size 1 1)
					(thickness 0.15)
				)
				(justify mirror)
			)
		)
		(property "MPN" "C1005X6S1A105K050BC"
			(at 52.3505 298.2295 0)
			(layer "B.Fab")
			(hide yes)
			(effects
				(font
					(size 1 1)
					(thickness 0.15)
				)
				(justify mirror)
			)
		)
		(property "Manufacturer" "TDK"
			(at 52.3505 298.2295 0)
			(layer "B.Fab")
			(hide yes)
			(effects
				(font
					(size 1 1)
					(thickness 0.15)
				)
				(justify mirror)
			)
		)
		(property "Public" ""
			(at 52.3505 298.2295 0)
			(layer "B.Fab")
			(hide yes)
			(effects
				(font
					(size 1 1)
					(thickness 0.15)
				)
				(justify mirror)
			)
		)
		(property "Val" "1u"
			(at 52.3505 298.2295 0)
			(layer "B.Fab")
			(hide yes)
			(effects
				(font
					(size 1 1)
					(thickness 0.15)
				)
				(justify mirror)
			)
		)
		(property "Voltage" "16V"
			(at 52.3505 298.2295 0)
			(layer "B.Fab")
			(hide yes)
			(effects
				(font
					(size 1 1)
					(thickness 0.15)
				)
				(justify mirror)
			)
		)
		(sheetname "/LPDDR4/")
		(sheetfile "lpddr.kicad_sch")
		(attr smd)
		(fp_rect
			(start -0.925 0.47)
			(end 0.925 -0.47)
			(stroke
				(width 0.05)
				(type default)
			)
			(fill no)
			(layer "B.CrtYd")
		)
		(fp_line
			(start -0.494 0.25)
			(end 0.504 0.25)
			(stroke
				(width 0.15)
				(type solid)
			)
			(layer "B.Fab")
		)
		(fp_line
			(start 0.504 0.25)
			(end 0.504 -0.248)
			(stroke
				(width 0.15)
				(type solid)
			)
			(layer "B.Fab")
		)
		(fp_line
			(start -0.494 -0.248)
			(end -0.494 0.25)
			(stroke
				(width 0.15)
				(type solid)
			)
			(layer "B.Fab")
		)
		(fp_line
			(start 0.504 -0.248)
			(end -0.494 -0.248)
			(stroke
				(width 0.15)
				(type solid)
			)
			(layer "B.Fab")
		)
		(fp_text user "${REFERENCE}"
			(at -0.939 -4.599 90)
			(layer "B.Fab")
			(effects
				(font
					(size 0.7 0.7)
					(thickness 0.15)
				)
				(justify left bottom mirror)
			)
		)
		(fp_text user "License: Apache-2.0"
			(at -0.939 -5.799 90)
			(layer "B.Fab")
			(effects
				(font
					(size 0.7 0.7)
					(thickness 0.15)
				)
				(justify left bottom mirror)
			)
		)
		(fp_text user "Author: Antmicro"
			(at -0.939 -3.399 90)
			(layer "B.Fab")
			(effects
				(font
					(size 0.7 0.7)
					(thickness 0.15)
				)
				(justify left bottom mirror)
			)
		)
		(pad "1" smd roundrect
			(at -0.48 0 270)
			(size 0.59 0.64)
			(layers "B.Cu" "B.Mask" "B.Paste")
			(roundrect_rratio 0.25)
			(net 417 "GND")
			(pintype "passive")
		)
		(pad "2" smd roundrect
			(at 0.48 0 270)
			(size 0.59 0.64)
			(layers "B.Cu" "B.Mask" "B.Paste")
			(roundrect_rratio 0.25)
			(net 2 "+1V1")
			(pintype "passive")
		)
	)
	(footprint "antmicro-footprints:R_0402_1005Metric"
		(layer "B.Cu")
		(at 192 123.25)
		(descr "Resistor SMD 0402")
		(tags "resistor SMD 0402")
		(property "Reference" "R74"
			(at 0.875 -0.525 180)
			(layer "B.SilkS")
			(effects
				(font
					(size 0.7 0.7)
					(thickness 0.15)
				)
				(justify left bottom mirror)
			)
		)
		(property "Value" "R_1k_0402"
			(at -1.011843 -1.772047 180)
			(layer "B.Fab")
			(hide yes)
			(effects
				(font
					(size 0.7 0.7)
					(thickness 0.15)
				)
				(justify left bottom mirror)
			)
		)
		(property "Datasheet" "https://www.bourns.com/docs/product-datasheets/cr.pdf"
			(at 0 0 0)
			(layer "F.Fab")
			(hide yes)
			(effects
				(font
					(size 1.27 1.27)
					(thickness 0.15)
				)
			)
		)
		(property "Description" "SMD Chip Resistor, 1 kohm, ± 1%, 63 mW, 0402 [1005 Metric], Thick Film, General Purpose"
			(at 0 0 0)
			(layer "F.Fab")
			(hide yes)
			(effects
				(font
					(size 1.27 1.27)
					(thickness 0.15)
				)
			)
		)
		(property "Author" "Antmicro"
			(at 0 0 0)
			(layer "B.Fab")
			(hide yes)
			(effects
				(font
					(size 1 1)
					(thickness 0.15)
				)
				(justify mirror)
			)
		)
		(property "License" "Apache-2.0"
			(at 0 0 0)
			(layer "B.Fab")
			(hide yes)
			(effects
				(font
					(size 1 1)
					(thickness 0.15)
				)
				(justify mirror)
			)
		)
		(property "MPN" "CR0402-FX-1001GLF"
			(at 0 0 0)
			(layer "B.Fab")
			(hide yes)
			(effects
				(font
					(size 1 1)
					(thickness 0.15)
				)
				(justify mirror)
			)
		)
		(property "Manufacturer" "Bourns"
			(at 0 0 0)
			(layer "B.Fab")
			(hide yes)
			(effects
				(font
					(size 1 1)
					(thickness 0.15)
				)
				(justify mirror)
			)
		)
		(property "Public" ""
			(at 0 0 0)
			(layer "B.Fab")
			(hide yes)
			(effects
				(font
					(size 1 1)
					(thickness 0.15)
				)
				(justify mirror)
			)
		)
		(property "Tolerance" "1%"
			(at 0 0 0)
			(layer "B.Fab")
			(hide yes)
			(effects
				(font
					(size 1 1)
					(thickness 0.15)
				)
				(justify mirror)
			)
		)
		(property "Val" "1k"
			(at 0 0 0)
			(layer "B.Fab")
			(hide yes)
			(effects
				(font
					(size 1 1)
					(thickness 0.15)
				)
				(justify mirror)
			)
		)
		(sheetname "/FPGA MSS/")
		(sheetfile "fpga-mss.kicad_sch")
		(attr smd)
		(fp_rect
			(start -0.925 0.47)
			(end 0.925 -0.47)
			(stroke
				(width 0.05)
				(type default)
			)
			(fill no)
			(layer "B.CrtYd")
		)
		(fp_rect
			(start -0.5 0.25)
			(end 0.5 -0.25)
			(stroke
				(width 0.15)
				(type solid)
			)
			(fill no)
			(layer "B.Fab")
		)
		(fp_text user "Author: Antmicro"
			(at -0.95 -4.169 180)
			(layer "B.Fab")
			(effects
				(font
					(size 0.7 0.7)
					(thickness 0.15)
				)
				(justify left bottom mirror)
			)
		)
		(fp_text user "License: Apache-2.0"
			(at -0.95 -5.169 180)
			(layer "B.Fab")
			(effects
				(font
					(size 0.7 0.7)
					(thickness 0.15)
				)
				(justify left bottom mirror)
			)
		)
		(fp_text user "${REFERENCE}"
			(at -0.95 -3.168 180)
			(layer "B.Fab")
			(effects
				(font
					(size 0.7 0.7)
					(thickness 0.15)
				)
				(justify left bottom mirror)
			)
		)
		(pad "1" smd roundrect
			(at -0.48 0)
			(size 0.59 0.64)
			(layers "B.Cu" "B.Mask" "B.Paste")
			(roundrect_rratio 0.25)
			(net 2 "+1V1")
			(pintype "passive")
		)
		(pad "2" smd roundrect
			(at 0.48 0)
			(size 0.59 0.64)
			(layers "B.Cu" "B.Mask" "B.Paste")
			(roundrect_rratio 0.25)
			(net 270 "Net-(U1G-MSS_DDR_VREF_IN)")
			(pintype "passive")
		)
	)
	(footprint "antmicro-footprints:C_0402_1005Metric"
		(layer "B.Cu")
		(at 197.99 132.79 90)
		(descr "Capacitor SMD 0402")
		(tags "capacitor SMD 0402")
		(property "Reference" "C40"
			(at 7.19 -9.615 270)
			(layer "B.SilkS")
			(effects
				(font
					(size 0.7 0.7)
					(thickness 0.15)
				)
				(justify left bottom mirror)
			)
		)
		(property "Value" "C_10n_0402"
			(at -1.022927 -2.155213 270)
			(layer "B.Fab")
			(hide yes)
			(effects
				(font
					(size 0.7 0.7)
					(thickness 0.15)
				)
				(justify left bottom mirror)
			)
		)
		(property "Datasheet" "https://www.murata.com/products/productdetail?partno=GRM155R71H103KA88%23"
			(at 0 0 90)
			(layer "F.Fab")
			(hide yes)
			(effects
				(font
					(size 1.27 1.27)
					(thickness 0.15)
				)
			)
		)
		(property "Description" "SMD Multilayer Ceramic Capacitor, 10000 pF, 50 V, 0402 [1005 Metric], ± 10%, X7R, GRM Series"
			(at 0 0 90)
			(layer "F.Fab")
			(hide yes)
			(effects
				(font
					(size 1.27 1.27)
					(thickness 0.15)
				)
			)
		)
		(property "Author" "Antmicro"
			(at 330.78 -65.2 0)
			(layer "B.Fab")
			(hide yes)
			(effects
				(font
					(size 1 1)
					(thickness 0.15)
				)
				(justify mirror)
			)
		)
		(property "Dielectric" "X7R"
			(at 330.78 -65.2 0)
			(layer "B.Fab")
			(hide yes)
			(effects
				(font
					(size 1 1)
					(thickness 0.15)
				)
				(justify mirror)
			)
		)
		(property "License" "Apache-2.0"
			(at 330.78 -65.2 0)
			(layer "B.Fab")
			(hide yes)
			(effects
				(font
					(size 1 1)
					(thickness 0.15)
				)
				(justify mirror)
			)
		)
		(property "MPN" "GRM155R71H103KA88D"
			(at 330.78 -65.2 0)
			(layer "B.Fab")
			(hide yes)
			(effects
				(font
					(size 1 1)
					(thickness 0.15)
				)
				(justify mirror)
			)
		)
		(property "Manufacturer" "Murata"
			(at 330.78 -65.2 0)
			(layer "B.Fab")
			(hide yes)
			(effects
				(font
					(size 1 1)
					(thickness 0.15)
				)
				(justify mirror)
			)
		)
		(property "Public" ""
			(at 330.78 -65.2 0)
			(layer "B.Fab")
			(hide yes)
			(effects
				(font
					(size 1 1)
					(thickness 0.15)
				)
				(justify mirror)
			)
		)
		(property "Val" "10n"
			(at 330.78 -65.2 0)
			(layer "B.Fab")
			(hide yes)
			(effects
				(font
					(size 1 1)
					(thickness 0.15)
				)
				(justify mirror)
			)
		)
		(property "Voltage" "50V"
			(at 330.78 -65.2 0)
			(layer "B.Fab")
			(hide yes)
			(effects
				(font
					(size 1 1)
					(thickness 0.15)
				)
				(justify mirror)
			)
		)
		(sheetname "/FPGA Supply/")
		(sheetfile "fpga-supply.kicad_sch")
		(attr smd)
		(fp_rect
			(start -0.925 0.47)
			(end 0.925 -0.47)
			(stroke
				(width 0.05)
				(type default)
			)
			(fill no)
			(layer "B.CrtYd")
		)
		(fp_line
			(start 0.504 -0.248)
			(end -0.494 -0.248)
			(stroke
				(width 0.15)
				(type solid)
			)
			(layer "B.Fab")
		)
		(fp_line
			(start -0.494 -0.248)
			(end -0.494 0.25)
			(stroke
				(width 0.15)
				(type solid)
			)
			(layer "B.Fab")
		)
		(fp_line
			(start 0.504 0.25)
			(end 0.504 -0.248)
			(stroke
				(width 0.15)
				(type solid)
			)
			(layer "B.Fab")
		)
		(fp_line
			(start -0.494 0.25)
			(end 0.504 0.25)
			(stroke
				(width 0.15)
				(type solid)
			)
			(layer "B.Fab")
		)
		(fp_text user "License: Apache-2.0"
			(at -0.939 -5.799 270)
			(layer "B.Fab")
			(effects
				(font
					(size 0.7 0.7)
					(thickness 0.15)
				)
				(justify left bottom mirror)
			)
		)
		(fp_text user "Author: Antmicro"
			(at -0.939 -3.399 270)
			(layer "B.Fab")
			(effects
				(font
					(size 0.7 0.7)
					(thickness 0.15)
				)
				(justify left bottom mirror)
			)
		)
		(fp_text user "${REFERENCE}"
			(at -0.939 -4.599 270)
			(layer "B.Fab")
			(effects
				(font
					(size 0.7 0.7)
					(thickness 0.15)
				)
				(justify left bottom mirror)
			)
		)
		(pad "1" smd roundrect
			(at -0.48 0 90)
			(size 0.59 0.64)
			(layers "B.Cu" "B.Mask" "B.Paste")
			(roundrect_rratio 0.25)
			(net 417 "GND")
			(pintype "passive")
		)
		(pad "2" smd roundrect
			(at 0.48 0 90)
			(size 0.59 0.64)
			(layers "B.Cu" "B.Mask" "B.Paste")
			(roundrect_rratio 0.25)
			(net 47 "+1V05")
			(pintype "passive")
		)
	)
	(footprint "antmicro-footprints:R_0402_1005Metric"
		(layer "B.Cu")
		(at 224.1 138.61 -90)
		(descr "Resistor SMD 0402")
		(tags "resistor SMD 0402")
		(property "Reference" "R52"
			(at -3.14 -0.39 90)
			(layer "B.SilkS")
			(effects
				(font
					(size 0.7 0.7)
					(thickness 0.15)
				)
				(justify left bottom mirror)
			)
		)
		(property "Value" "R_10k_0402"
			(at -1.011843 -1.772047 90)
			(layer "B.Fab")
			(hide yes)
			(effects
				(font
					(size 0.7 0.7)
					(thickness 0.15)
				)
				(justify left bottom mirror)
			)
		)
		(property "Datasheet" "https://www.bourns.com/docs/product-datasheets/cr.pdf"
			(at 0 0 270)
			(layer "F.Fab")
			(hide yes)
			(effects
				(font
					(size 1.27 1.27)
					(thickness 0.15)
				)
			)
		)
		(property "Description" "SMD Chip Resistor, 10 kohm, ± 1%, 62.5 mW, 0402 [1005 Metric], Thick Film, General Purpose"
			(at 0 0 270)
			(layer "F.Fab")
			(hide yes)
			(effects
				(font
					(size 1.27 1.27)
					(thickness 0.15)
				)
			)
		)
		(property "Author" "Antmicro"
			(at 85.49 362.71 0)
			(layer "B.Fab")
			(hide yes)
			(effects
				(font
					(size 1 1)
					(thickness 0.15)
				)
				(justify mirror)
			)
		)
		(property "License" "Apache-2.0"
			(at 85.49 362.71 0)
			(layer "B.Fab")
			(hide yes)
			(effects
				(font
					(size 1 1)
					(thickness 0.15)
				)
				(justify mirror)
			)
		)
		(property "MPN" "CR0402-FX-1002GLF"
			(at 85.49 362.71 0)
			(layer "B.Fab")
			(hide yes)
			(effects
				(font
					(size 1 1)
					(thickness 0.15)
				)
				(justify mirror)
			)
		)
		(property "Manufacturer" "Bourns"
			(at 85.49 362.71 0)
			(layer "B.Fab")
			(hide yes)
			(effects
				(font
					(size 1 1)
					(thickness 0.15)
				)
				(justify mirror)
			)
		)
		(property "Public" ""
			(at 85.49 362.71 0)
			(layer "B.Fab")
			(hide yes)
			(effects
				(font
					(size 1 1)
					(thickness 0.15)
				)
				(justify mirror)
			)
		)
		(property "Tolerance" "1%"
			(at 85.49 362.71 0)
			(layer "B.Fab")
			(hide yes)
			(effects
				(font
					(size 1 1)
					(thickness 0.15)
				)
				(justify mirror)
			)
		)
		(property "Val" "10k"
			(at 85.49 362.71 0)
			(layer "B.Fab")
			(hide yes)
			(effects
				(font
					(size 1 1)
					(thickness 0.15)
				)
				(justify mirror)
			)
		)
		(sheetname "/Memory/")
		(sheetfile "memory.kicad_sch")
		(attr smd)
		(fp_rect
			(start -0.925 0.47)
			(end 0.925 -0.47)
			(stroke
				(width 0.05)
				(type default)
			)
			(fill no)
			(layer "B.CrtYd")
		)
		(fp_rect
			(start -0.5 0.25)
			(end 0.5 -0.25)
			(stroke
				(width 0.15)
				(type solid)
			)
			(fill no)
			(layer "B.Fab")
		)
		(fp_text user "Author: Antmicro"
			(at -0.95 -4.169 90)
			(layer "B.Fab")
			(effects
				(font
					(size 0.7 0.7)
					(thickness 0.15)
				)
				(justify left bottom mirror)
			)
		)
		(fp_text user "License: Apache-2.0"
			(at -0.95 -5.169 90)
			(layer "B.Fab")
			(effects
				(font
					(size 0.7 0.7)
					(thickness 0.15)
				)
				(justify left bottom mirror)
			)
		)
		(fp_text user "${REFERENCE}"
			(at -0.95 -3.168 90)
			(layer "B.Fab")
			(effects
				(font
					(size 0.7 0.7)
					(thickness 0.15)
				)
				(justify left bottom mirror)
			)
		)
		(pad "1" smd roundrect
			(at -0.48 0 270)
			(size 0.59 0.64)
			(layers "B.Cu" "B.Mask" "B.Paste")
			(roundrect_rratio 0.25)
			(net 246 "SD_VDD_OVERRIDE")
			(pintype "passive")
		)
		(pad "2" smd roundrect
			(at 0.48 0 270)
			(size 0.59 0.64)
			(layers "B.Cu" "B.Mask" "B.Paste")
			(roundrect_rratio 0.25)
			(net 417 "GND")
			(pintype "passive")
		)
	)
	(footprint "antmicro-footprints:C_0402_1005Metric"
		(layer "B.Cu")
		(at 197.04 138.614 90)
		(descr "Capacitor SMD 0402")
		(tags "capacitor SMD 0402")
		(property "Reference" "C33"
			(at 4.889 -9.715 90)
			(layer "B.SilkS")
			(effects
				(font
					(size 0.7 0.7)
					(thickness 0.15)
				)
				(justify right bottom mirror)
			)
		)
		(property "Value" "C_100n_0402"
			(at -1.022927 -2.155213 90)
			(layer "B.Fab")
			(hide yes)
			(effects
				(font
					(size 0.7 0.7)
					(thickness 0.15)
				)
				(justify right bottom mirror)
			)
		)
		(property "Datasheet" "https://www.murata.com/products/productdetail?partno=GRM155R61H104KE14%23"
			(at 0 0 90)
			(layer "F.Fab")
			(hide yes)
			(effects
				(font
					(size 1.27 1.27)
					(thickness 0.15)
				)
			)
		)
		(property "Description" "SMD Multilayer Ceramic Capacitor, 0.1 µF, 50 V, 0402 [1005 Metric], ± 10%, X5R, GRM Series"
			(at 0 0 90)
			(layer "F.Fab")
			(hide yes)
			(effects
				(font
					(size 1.27 1.27)
					(thickness 0.15)
				)
			)
		)
		(property "Author" "Antmicro"
			(at 335.654 -58.426 0)
			(layer "B.Fab")
			(hide yes)
			(effects
				(font
					(size 1 1)
					(thickness 0.15)
				)
				(justify mirror)
			)
		)
		(property "Dielectric" "X5R"
			(at 335.654 -58.426 0)
			(layer "B.Fab")
			(hide yes)
			(effects
				(font
					(size 1 1)
					(thickness 0.15)
				)
				(justify mirror)
			)
		)
		(property "License" "Apache-2.0"
			(at 335.654 -58.426 0)
			(layer "B.Fab")
			(hide yes)
			(effects
				(font
					(size 1 1)
					(thickness 0.15)
				)
				(justify mirror)
			)
		)
		(property "MPN" "GRM155R61H104KE14D"
			(at 335.654 -58.426 0)
			(layer "B.Fab")
			(hide yes)
			(effects
				(font
					(size 1 1)
					(thickness 0.15)
				)
				(justify mirror)
			)
		)
		(property "Manufacturer" "Murata"
			(at 335.654 -58.426 0)
			(layer "B.Fab")
			(hide yes)
			(effects
				(font
					(size 1 1)
					(thickness 0.15)
				)
				(justify mirror)
			)
		)
		(property "Public" ""
			(at 335.654 -58.426 0)
			(layer "B.Fab")
			(hide yes)
			(effects
				(font
					(size 1 1)
					(thickness 0.15)
				)
				(justify mirror)
			)
		)
		(property "Val" "100n"
			(at 335.654 -58.426 0)
			(layer "B.Fab")
			(hide yes)
			(effects
				(font
					(size 1 1)
					(thickness 0.15)
				)
				(justify mirror)
			)
		)
		(property "Voltage" "50V"
			(at 335.654 -58.426 0)
			(layer "B.Fab")
			(hide yes)
			(effects
				(font
					(size 1 1)
					(thickness 0.15)
				)
				(justify mirror)
			)
		)
		(sheetname "/FPGA Supply/")
		(sheetfile "fpga-supply.kicad_sch")
		(attr smd)
		(fp_rect
			(start -0.925 0.47)
			(end 0.925 -0.47)
			(stroke
				(width 0.05)
				(type default)
			)
			(fill no)
			(layer "B.CrtYd")
		)
		(fp_line
			(start 0.504 -0.248)
			(end -0.494 -0.248)
			(stroke
				(width 0.15)
				(type solid)
			)
			(layer "B.Fab")
		)
		(fp_line
			(start -0.494 -0.248)
			(end -0.494 0.25)
			(stroke
				(width 0.15)
				(type solid)
			)
			(layer "B.Fab")
		)
		(fp_line
			(start 0.504 0.25)
			(end 0.504 -0.248)
			(stroke
				(width 0.15)
				(type solid)
			)
			(layer "B.Fab")
		)
		(fp_line
			(start -0.494 0.25)
			(end 0.504 0.25)
			(stroke
				(width 0.15)
				(type solid)
			)
			(layer "B.Fab")
		)
		(fp_text user "License: Apache-2.0"
			(at -0.939 -5.799 270)
			(layer "B.Fab")
			(effects
				(font
					(size 0.7 0.7)
					(thickness 0.15)
				)
				(justify left bottom mirror)
			)
		)
		(fp_text user "Author: Antmicro"
			(at -0.939 -3.399 270)
			(layer "B.Fab")
			(effects
				(font
					(size 0.7 0.7)
					(thickness 0.15)
				)
				(justify left bottom mirror)
			)
		)
		(fp_text user "${REFERENCE}"
			(at -0.939 -4.599 270)
			(layer "B.Fab")
			(effects
				(font
					(size 0.7 0.7)
					(thickness 0.15)
				)
				(justify left bottom mirror)
			)
		)
		(pad "1" smd roundrect
			(at -0.48 0 90)
			(size 0.59 0.64)
			(layers "B.Cu" "B.Mask" "B.Paste")
			(roundrect_rratio 0.25)
			(net 417 "GND")
			(pintype "passive")
		)
		(pad "2" smd roundrect
			(at 0.48 0 90)
			(size 0.59 0.64)
			(layers "B.Cu" "B.Mask" "B.Paste")
			(roundrect_rratio 0.25)
			(net 418 "+2V5")
			(pintype "passive")
		)
	)
	(footprint "antmicro-footprints:C_0402_1005Metric"
		(layer "B.Cu")
		(at 212.19 131.06 180)
		(descr "Capacitor SMD 0402")
		(tags "capacitor SMD 0402")
		(property "Reference" "C70"
			(at -1.14 -1.27 0)
			(layer "B.SilkS")
			(effects
				(font
					(size 0.7 0.7)
					(thickness 0.15)
				)
				(justify left bottom mirror)
			)
		)
		(property "Value" "C_100n_0402"
			(at -1.022927 -2.155213 0)
			(layer "B.Fab")
			(hide yes)
			(effects
				(font
					(size 0.7 0.7)
					(thickness 0.15)
				)
				(justify left bottom mirror)
			)
		)
		(property "Datasheet" "https://www.murata.com/products/productdetail?partno=GRM155R61H104KE14%23"
			(at 0 0 180)
			(layer "F.Fab")
			(hide yes)
			(effects
				(font
					(size 1.27 1.27)
					(thickness 0.15)
				)
			)
		)
		(property "Description" "SMD Multilayer Ceramic Capacitor, 0.1 µF, 50 V, 0402 [1005 Metric], ± 10%, X5R, GRM Series"
			(at 0 0 180)
			(layer "F.Fab")
			(hide yes)
			(effects
				(font
					(size 1.27 1.27)
					(thickness 0.15)
				)
			)
		)
		(property "Author" "Antmicro"
			(at 424.38 262.12 0)
			(layer "B.Fab")
			(hide yes)
			(effects
				(font
					(size 1 1)
					(thickness 0.15)
				)
				(justify mirror)
			)
		)
		(property "Dielectric" "X5R"
			(at 424.38 262.12 0)
			(layer "B.Fab")
			(hide yes)
			(effects
				(font
					(size 1 1)
					(thickness 0.15)
				)
				(justify mirror)
			)
		)
		(property "License" "Apache-2.0"
			(at 424.38 262.12 0)
			(layer "B.Fab")
			(hide yes)
			(effects
				(font
					(size 1 1)
					(thickness 0.15)
				)
				(justify mirror)
			)
		)
		(property "MPN" "GRM155R61H104KE14D"
			(at 424.38 262.12 0)
			(layer "B.Fab")
			(hide yes)
			(effects
				(font
					(size 1 1)
					(thickness 0.15)
				)
				(justify mirror)
			)
		)
		(property "Manufacturer" "Murata"
			(at 424.38 262.12 0)
			(layer "B.Fab")
			(hide yes)
			(effects
				(font
					(size 1 1)
					(thickness 0.15)
				)
				(justify mirror)
			)
		)
		(property "Public" ""
			(at 424.38 262.12 0)
			(layer "B.Fab")
			(hide yes)
			(effects
				(font
					(size 1 1)
					(thickness 0.15)
				)
				(justify mirror)
			)
		)
		(property "Val" "100n"
			(at 424.38 262.12 0)
			(layer "B.Fab")
			(hide yes)
			(effects
				(font
					(size 1 1)
					(thickness 0.15)
				)
				(justify mirror)
			)
		)
		(property "Voltage" "50V"
			(at 424.38 262.12 0)
			(layer "B.Fab")
			(hide yes)
			(effects
				(font
					(size 1 1)
					(thickness 0.15)
				)
				(justify mirror)
			)
		)
		(sheetname "/Memory/")
		(sheetfile "memory.kicad_sch")
		(attr smd)
		(fp_rect
			(start -0.925 0.47)
			(end 0.925 -0.47)
			(stroke
				(width 0.05)
				(type default)
			)
			(fill no)
			(layer "B.CrtYd")
		)
		(fp_line
			(start 0.504 0.25)
			(end 0.504 -0.248)
			(stroke
				(width 0.15)
				(type solid)
			)
			(layer "B.Fab")
		)
		(fp_line
			(start 0.504 -0.248)
			(end -0.494 -0.248)
			(stroke
				(width 0.15)
				(type solid)
			)
			(layer "B.Fab")
		)
		(fp_line
			(start -0.494 0.25)
			(end 0.504 0.25)
			(stroke
				(width 0.15)
				(type solid)
			)
			(layer "B.Fab")
		)
		(fp_line
			(start -0.494 -0.248)
			(end -0.494 0.25)
			(stroke
				(width 0.15)
				(type solid)
			)
			(layer "B.Fab")
		)
		(fp_text user "Author: Antmicro"
			(at -0.939 -3.399 0)
			(layer "B.Fab")
			(effects
				(font
					(size 0.7 0.7)
					(thickness 0.15)
				)
				(justify left bottom mirror)
			)
		)
		(fp_text user "${REFERENCE}"
			(at -0.939 -4.599 0)
			(layer "B.Fab")
			(effects
				(font
					(size 0.7 0.7)
					(thickness 0.15)
				)
				(justify left bottom mirror)
			)
		)
		(fp_text user "License: Apache-2.0"
			(at -0.939 -5.799 0)
			(layer "B.Fab")
			(effects
				(font
					(size 0.7 0.7)
					(thickness 0.15)
				)
				(justify left bottom mirror)
			)
		)
		(pad "1" smd roundrect
			(at -0.48 0 180)
			(size 0.59 0.64)
			(layers "B.Cu" "B.Mask" "B.Paste")
			(roundrect_rratio 0.25)
			(net 417 "GND")
			(pintype "passive")
		)
		(pad "2" smd roundrect
			(at 0.48 0 180)
			(size 0.59 0.64)
			(layers "B.Cu" "B.Mask" "B.Paste")
			(roundrect_rratio 0.25)
			(net 52 "/Memory/eMMC_VDDI")
			(pintype "passive")
		)
	)
	(footprint "antmicro-footprints:R_0402_1005Metric"
		(layer "B.Cu")
		(at 185.75 120.85 90)
		(descr "Resistor SMD 0402")
		(tags "resistor SMD 0402")
		(property "Reference" "R43"
			(at 1.05 -1.5 270)
			(layer "B.SilkS")
			(effects
				(font
					(size 0.7 0.7)
					(thickness 0.15)
				)
				(justify left bottom mirror)
			)
		)
		(property "Value" "R_10k_0402"
			(at -1.011843 -1.772047 270)
			(layer "B.Fab")
			(hide yes)
			(effects
				(font
					(size 0.7 0.7)
					(thickness 0.15)
				)
				(justify left bottom mirror)
			)
		)
		(property "Datasheet" "https://www.bourns.com/docs/product-datasheets/cr.pdf"
			(at 0 0 90)
			(layer "F.Fab")
			(hide yes)
			(effects
				(font
					(size 1.27 1.27)
					(thickness 0.15)
				)
			)
		)
		(property "Description" "SMD Chip Resistor, 10 kohm, ± 1%, 62.5 mW, 0402 [1005 Metric], Thick Film, General Purpose"
			(at 0 0 90)
			(layer "F.Fab")
			(hide yes)
			(effects
				(font
					(size 1.27 1.27)
					(thickness 0.15)
				)
			)
		)
		(property "Author" "Antmicro"
			(at 306.6 -64.9 0)
			(layer "B.Fab")
			(hide yes)
			(effects
				(font
					(size 1 1)
					(thickness 0.15)
				)
				(justify mirror)
			)
		)
		(property "License" "Apache-2.0"
			(at 306.6 -64.9 0)
			(layer "B.Fab")
			(hide yes)
			(effects
				(font
					(size 1 1)
					(thickness 0.15)
				)
				(justify mirror)
			)
		)
		(property "MPN" "CR0402-FX-1002GLF"
			(at 306.6 -64.9 0)
			(layer "B.Fab")
			(hide yes)
			(effects
				(font
					(size 1 1)
					(thickness 0.15)
				)
				(justify mirror)
			)
		)
		(property "Manufacturer" "Bourns"
			(at 306.6 -64.9 0)
			(layer "B.Fab")
			(hide yes)
			(effects
				(font
					(size 1 1)
					(thickness 0.15)
				)
				(justify mirror)
			)
		)
		(property "Public" ""
			(at 306.6 -64.9 0)
			(layer "B.Fab")
			(hide yes)
			(effects
				(font
					(size 1 1)
					(thickness 0.15)
				)
				(justify mirror)
			)
		)
		(property "Tolerance" "1%"
			(at 306.6 -64.9 0)
			(layer "B.Fab")
			(hide yes)
			(effects
				(font
					(size 1 1)
					(thickness 0.15)
				)
				(justify mirror)
			)
		)
		(property "Val" "10k"
			(at 306.6 -64.9 0)
			(layer "B.Fab")
			(hide yes)
			(effects
				(font
					(size 1 1)
					(thickness 0.15)
				)
				(justify mirror)
			)
		)
		(sheetname "/FPGA Config/")
		(sheetfile "fpga-config.kicad_sch")
		(attr smd)
		(fp_rect
			(start -0.925 0.47)
			(end 0.925 -0.47)
			(stroke
				(width 0.05)
				(type default)
			)
			(fill no)
			(layer "B.CrtYd")
		)
		(fp_rect
			(start -0.5 0.25)
			(end 0.5 -0.25)
			(stroke
				(width 0.15)
				(type solid)
			)
			(fill no)
			(layer "B.Fab")
		)
		(fp_text user "License: Apache-2.0"
			(at -0.95 -5.169 270)
			(layer "B.Fab")
			(effects
				(font
					(size 0.7 0.7)
					(thickness 0.15)
				)
				(justify left bottom mirror)
			)
		)
		(fp_text user "${REFERENCE}"
			(at -0.95 -3.168 270)
			(layer "B.Fab")
			(effects
				(font
					(size 0.7 0.7)
					(thickness 0.15)
				)
				(justify left bottom mirror)
			)
		)
		(fp_text user "Author: Antmicro"
			(at -0.95 -4.169 270)
			(layer "B.Fab")
			(effects
				(font
					(size 0.7 0.7)
					(thickness 0.15)
				)
				(justify left bottom mirror)
			)
		)
		(pad "1" smd roundrect
			(at -0.48 0 90)
			(size 0.59 0.64)
			(layers "B.Cu" "B.Mask" "B.Paste")
			(roundrect_rratio 0.25)
			(net 417 "GND")
			(pintype "passive")
		)
		(pad "2" smd roundrect
			(at 0.48 0 90)
			(size 0.59 0.64)
			(layers "B.Cu" "B.Mask" "B.Paste")
			(roundrect_rratio 0.25)
			(net 124 "JTAG_TCK")
			(pintype "passive")
		)
	)
	(footprint "antmicro-footprints:C_0402_1005Metric"
		(layer "B.Cu")
		(at 199.89 134.73 90)
		(descr "Capacitor SMD 0402")
		(tags "capacitor SMD 0402")
		(property "Reference" "C63"
			(at 5.48 -9.615 90)
			(layer "B.SilkS")
			(effects
				(font
					(size 0.7 0.7)
					(thickness 0.15)
				)
				(justify right bottom mirror)
			)
		)
		(property "Value" "C_100n_0402"
			(at -1.022927 -2.155213 90)
			(layer "B.Fab")
			(hide yes)
			(effects
				(font
					(size 0.7 0.7)
					(thickness 0.15)
				)
				(justify right bottom mirror)
			)
		)
		(property "Datasheet" "https://www.murata.com/products/productdetail?partno=GRM155R61H104KE14%23"
			(at 0 0 90)
			(layer "F.Fab")
			(hide yes)
			(effects
				(font
					(size 1.27 1.27)
					(thickness 0.15)
				)
			)
		)
		(property "Description" "SMD Multilayer Ceramic Capacitor, 0.1 µF, 50 V, 0402 [1005 Metric], ± 10%, X5R, GRM Series"
			(at 0 0 90)
			(layer "F.Fab")
			(hide yes)
			(effects
				(font
					(size 1.27 1.27)
					(thickness 0.15)
				)
			)
		)
		(property "Author" "Antmicro"
			(at 334.62 -65.16 0)
			(layer "B.Fab")
			(hide yes)
			(effects
				(font
					(size 1 1)
					(thickness 0.15)
				)
				(justify mirror)
			)
		)
		(property "Dielectric" "X5R"
			(at 334.62 -65.16 0)
			(layer "B.Fab")
			(hide yes)
			(effects
				(font
					(size 1 1)
					(thickness 0.15)
				)
				(justify mirror)
			)
		)
		(property "License" "Apache-2.0"
			(at 334.62 -65.16 0)
			(layer "B.Fab")
			(hide yes)
			(effects
				(font
					(size 1 1)
					(thickness 0.15)
				)
				(justify mirror)
			)
		)
		(property "MPN" "GRM155R61H104KE14D"
			(at 334.62 -65.16 0)
			(layer "B.Fab")
			(hide yes)
			(effects
				(font
					(size 1 1)
					(thickness 0.15)
				)
				(justify mirror)
			)
		)
		(property "Manufacturer" "Murata"
			(at 334.62 -65.16 0)
			(layer "B.Fab")
			(hide yes)
			(effects
				(font
					(size 1 1)
					(thickness 0.15)
				)
				(justify mirror)
			)
		)
		(property "Public" ""
			(at 334.62 -65.16 0)
			(layer "B.Fab")
			(hide yes)
			(effects
				(font
					(size 1 1)
					(thickness 0.15)
				)
				(justify mirror)
			)
		)
		(property "Val" "100n"
			(at 334.62 -65.16 0)
			(layer "B.Fab")
			(hide yes)
			(effects
				(font
					(size 1 1)
					(thickness 0.15)
				)
				(justify mirror)
			)
		)
		(property "Voltage" "50V"
			(at 334.62 -65.16 0)
			(layer "B.Fab")
			(hide yes)
			(effects
				(font
					(size 1 1)
					(thickness 0.15)
				)
				(justify mirror)
			)
		)
		(sheetname "/FPGA Supply/")
		(sheetfile "fpga-supply.kicad_sch")
		(attr smd)
		(fp_rect
			(start -0.925 0.47)
			(end 0.925 -0.47)
			(stroke
				(width 0.05)
				(type default)
			)
			(fill no)
			(layer "B.CrtYd")
		)
		(fp_line
			(start 0.504 -0.248)
			(end -0.494 -0.248)
			(stroke
				(width 0.15)
				(type solid)
			)
			(layer "B.Fab")
		)
		(fp_line
			(start -0.494 -0.248)
			(end -0.494 0.25)
			(stroke
				(width 0.15)
				(type solid)
			)
			(layer "B.Fab")
		)
		(fp_line
			(start 0.504 0.25)
			(end 0.504 -0.248)
			(stroke
				(width 0.15)
				(type solid)
			)
			(layer "B.Fab")
		)
		(fp_line
			(start -0.494 0.25)
			(end 0.504 0.25)
			(stroke
				(width 0.15)
				(type solid)
			)
			(layer "B.Fab")
		)
		(fp_text user "${REFERENCE}"
			(at -0.939 -4.599 270)
			(layer "B.Fab")
			(effects
				(font
					(size 0.7 0.7)
					(thickness 0.15)
				)
				(justify left bottom mirror)
			)
		)
		(fp_text user "License: Apache-2.0"
			(at -0.939 -5.799 270)
			(layer "B.Fab")
			(effects
				(font
					(size 0.7 0.7)
					(thickness 0.15)
				)
				(justify left bottom mirror)
			)
		)
		(fp_text user "Author: Antmicro"
			(at -0.939 -3.399 270)
			(layer "B.Fab")
			(effects
				(font
					(size 0.7 0.7)
					(thickness 0.15)
				)
				(justify left bottom mirror)
			)
		)
		(pad "1" smd roundrect
			(at -0.48 0 90)
			(size 0.59 0.64)
			(layers "B.Cu" "B.Mask" "B.Paste")
			(roundrect_rratio 0.25)
			(net 417 "GND")
			(pintype "passive")
		)
		(pad "2" smd roundrect
			(at 0.48 0 90)
			(size 0.59 0.64)
			(layers "B.Cu" "B.Mask" "B.Paste")
			(roundrect_rratio 0.25)
			(net 49 "VDDAUX")
			(pintype "passive")
		)
	)
	(footprint "antmicro-footprints:R_0402_1005Metric"
		(layer "B.Cu")
		(at 219.911 116.704 180)
		(descr "Resistor SMD 0402")
		(tags "resistor SMD 0402")
		(property "Reference" "R67"
			(at -9.389 -4.546 0)
			(layer "B.SilkS")
			(effects
				(font
					(size 0.7 0.7)
					(thickness 0.15)
				)
				(justify left bottom mirror)
			)
		)
		(property "Value" "R_11k_0402"
			(at -1.011843 -1.772047 0)
			(layer "B.Fab")
			(hide yes)
			(effects
				(font
					(size 0.7 0.7)
					(thickness 0.15)
				)
				(justify left bottom mirror)
			)
		)
		(property "Datasheet" "https://www.bourns.com/docs/product-datasheets/cr.pdf"
			(at 0 0 180)
			(layer "F.Fab")
			(hide yes)
			(effects
				(font
					(size 1.27 1.27)
					(thickness 0.15)
				)
			)
		)
		(property "Description" "SMD Chip Resistor, 11 kohm, ± 1%, 62.5 mW, 0402 [1005 Metric], Thick Film, General Purpose"
			(at 0 0 180)
			(layer "F.Fab")
			(hide yes)
			(effects
				(font
					(size 1.27 1.27)
					(thickness 0.15)
				)
			)
		)
		(property "Author" "Antmicro"
			(at 439.822 233.408 0)
			(layer "B.Fab")
			(hide yes)
			(effects
				(font
					(size 1 1)
					(thickness 0.15)
				)
				(justify mirror)
			)
		)
		(property "License" "Apache-2.0"
			(at 439.822 233.408 0)
			(layer "B.Fab")
			(hide yes)
			(effects
				(font
					(size 1 1)
					(thickness 0.15)
				)
				(justify mirror)
			)
		)
		(property "MPN" "CR0402-FX-1102GLF"
			(at 439.822 233.408 0)
			(layer "B.Fab")
			(hide yes)
			(effects
				(font
					(size 1 1)
					(thickness 0.15)
				)
				(justify mirror)
			)
		)
		(property "Manufacturer" "Bourns"
			(at 439.822 233.408 0)
			(layer "B.Fab")
			(hide yes)
			(effects
				(font
					(size 1 1)
					(thickness 0.15)
				)
				(justify mirror)
			)
		)
		(property "Public" ""
			(at 439.822 233.408 0)
			(layer "B.Fab")
			(hide yes)
			(effects
				(font
					(size 1 1)
					(thickness 0.15)
				)
				(justify mirror)
			)
		)
		(property "Tolerance" "1%"
			(at 439.822 233.408 0)
			(layer "B.Fab")
			(hide yes)
			(effects
				(font
					(size 1 1)
					(thickness 0.15)
				)
				(justify mirror)
			)
		)
		(property "Val" "11k"
			(at 439.822 233.408 0)
			(layer "B.Fab")
			(hide yes)
			(effects
				(font
					(size 1 1)
					(thickness 0.15)
				)
				(justify mirror)
			)
		)
		(sheetname "/Ethernet/")
		(sheetfile "ethernet.kicad_sch")
		(attr smd)
		(fp_rect
			(start -0.925 0.47)
			(end 0.925 -0.47)
			(stroke
				(width 0.05)
				(type default)
			)
			(fill no)
			(layer "B.CrtYd")
		)
		(fp_rect
			(start -0.5 0.25)
			(end 0.5 -0.25)
			(stroke
				(width 0.15)
				(type solid)
			)
			(fill no)
			(layer "B.Fab")
		)
		(fp_text user "${REFERENCE}"
			(at -0.95 -3.168 0)
			(layer "B.Fab")
			(effects
				(font
					(size 0.7 0.7)
					(thickness 0.15)
				)
				(justify left bottom mirror)
			)
		)
		(fp_text user "Author: Antmicro"
			(at -0.95 -4.169 0)
			(layer "B.Fab")
			(effects
				(font
					(size 0.7 0.7)
					(thickness 0.15)
				)
				(justify left bottom mirror)
			)
		)
		(fp_text user "License: Apache-2.0"
			(at -0.95 -5.169 0)
			(layer "B.Fab")
			(effects
				(font
					(size 0.7 0.7)
					(thickness 0.15)
				)
				(justify left bottom mirror)
			)
		)
		(pad "1" smd roundrect
			(at -0.48 0 180)
			(size 0.59 0.64)
			(layers "B.Cu" "B.Mask" "B.Paste")
			(roundrect_rratio 0.25)
			(net 222 "Net-(U11-RBIAS)")
			(pintype "passive")
		)
		(pad "2" smd roundrect
			(at 0.48 0 180)
			(size 0.59 0.64)
			(layers "B.Cu" "B.Mask" "B.Paste")
			(roundrect_rratio 0.25)
			(net 417 "GND")
			(pintype "passive")
		)
	)
	(footprint "antmicro-footprints:R_0402_1005Metric"
		(layer "B.Cu")
		(at 218.361 123.254 90)
		(descr "Resistor SMD 0402")
		(tags "resistor SMD 0402")
		(property "Reference" "R141"
			(at -1.836 3.419 270)
			(layer "B.SilkS")
			(effects
				(font
					(size 0.7 0.7)
					(thickness 0.15)
				)
				(justify left bottom mirror)
			)
		)
		(property "Value" "R_2k2_0402"
			(at -1.011843 -1.772047 270)
			(layer "B.Fab")
			(hide yes)
			(effects
				(font
					(size 0.7 0.7)
					(thickness 0.15)
				)
				(justify left bottom mirror)
			)
		)
		(property "Datasheet" "https://www.bourns.com/docs/product-datasheets/cr.pdf"
			(at 0 0 90)
			(layer "F.Fab")
			(hide yes)
			(effects
				(font
					(size 1.27 1.27)
					(thickness 0.15)
				)
			)
		)
		(property "Description" "SMD Chip Resistor, 2.2 kohm, ± 1%, 62.5 mW, 0402 [1005 Metric], Thick Film, General Purpose"
			(at 0 0 90)
			(layer "F.Fab")
			(hide yes)
			(effects
				(font
					(size 1.27 1.27)
					(thickness 0.15)
				)
			)
		)
		(property "Author" "Antmicro"
			(at 341.615 -95.107 0)
			(layer "B.Fab")
			(hide yes)
			(effects
				(font
					(size 1 1)
					(thickness 0.15)
				)
				(justify mirror)
			)
		)
		(property "License" "Apache-2.0"
			(at 341.615 -95.107 0)
			(layer "B.Fab")
			(hide yes)
			(effects
				(font
					(size 1 1)
					(thickness 0.15)
				)
				(justify mirror)
			)
		)
		(property "MPN" "CR0402-FX-2201GLF"
			(at 341.615 -95.107 0)
			(layer "B.Fab")
			(hide yes)
			(effects
				(font
					(size 1 1)
					(thickness 0.15)
				)
				(justify mirror)
			)
		)
		(property "Manufacturer" "Bourns"
			(at 341.615 -95.107 0)
			(layer "B.Fab")
			(hide yes)
			(effects
				(font
					(size 1 1)
					(thickness 0.15)
				)
				(justify mirror)
			)
		)
		(property "Public" ""
			(at 341.615 -95.107 0)
			(layer "B.Fab")
			(hide yes)
			(effects
				(font
					(size 1 1)
					(thickness 0.15)
				)
				(justify mirror)
			)
		)
		(property "Tolerance" "1%"
			(at 341.615 -95.107 0)
			(layer "B.Fab")
			(hide yes)
			(effects
				(font
					(size 1 1)
					(thickness 0.15)
				)
				(justify mirror)
			)
		)
		(property "Val" "2k2"
			(at 341.615 -95.107 0)
			(layer "B.Fab")
			(hide yes)
			(effects
				(font
					(size 1 1)
					(thickness 0.15)
				)
				(justify mirror)
			)
		)
		(sheetname "/Ethernet/")
		(sheetfile "ethernet.kicad_sch")
		(attr smd)
		(fp_rect
			(start -0.925 0.47)
			(end 0.925 -0.47)
			(stroke
				(width 0.05)
				(type default)
			)
			(fill no)
			(layer "B.CrtYd")
		)
		(fp_rect
			(start -0.5 0.25)
			(end 0.5 -0.25)
			(stroke
				(width 0.15)
				(type solid)
			)
			(fill no)
			(layer "B.Fab")
		)
		(fp_text user "${REFERENCE}"
			(at -0.95 -3.168 270)
			(layer "B.Fab")
			(effects
				(font
					(size 0.7 0.7)
					(thickness 0.15)
				)
				(justify left bottom mirror)
			)
		)
		(fp_text user "License: Apache-2.0"
			(at -0.95 -5.169 270)
			(layer "B.Fab")
			(effects
				(font
					(size 0.7 0.7)
					(thickness 0.15)
				)
				(justify left bottom mirror)
			)
		)
		(fp_text user "Author: Antmicro"
			(at -0.95 -4.169 270)
			(layer "B.Fab")
			(effects
				(font
					(size 0.7 0.7)
					(thickness 0.15)
				)
				(justify left bottom mirror)
			)
		)
		(pad "1" smd roundrect
			(at -0.48 0 90)
			(size 0.59 0.64)
			(layers "B.Cu" "B.Mask" "B.Paste")
			(roundrect_rratio 0.25)
			(net 217 "ETH_PWDN_n")
			(pintype "passive")
		)
		(pad "2" smd roundrect
			(at 0.48 0 90)
			(size 0.59 0.64)
			(layers "B.Cu" "B.Mask" "B.Paste")
			(roundrect_rratio 0.25)
			(net 50 "+3V3")
			(pintype "passive")
		)
	)
	(footprint "antmicro-footprints:C_0402_1005Metric"
		(layer "B.Cu")
		(at 219.911 123.8)
		(descr "Capacitor SMD 0402")
		(tags "capacitor SMD 0402")
		(property "Reference" "C193"
			(at 6.539 3.76 0)
			(layer "B.SilkS")
			(effects
				(font
					(size 0.7 0.7)
					(thickness 0.15)
				)
				(justify right bottom mirror)
			)
		)
		(property "Value" "C_1u_0402"
			(at -1.022927 -2.155213 0)
			(layer "B.Fab")
			(hide yes)
			(effects
				(font
					(size 0.7 0.7)
					(thickness 0.15)
				)
				(justify right bottom mirror)
			)
		)
		(property "Datasheet" "https://product.tdk.com/en/search/capacitor/ceramic/mlcc/info?part_no=C1005X6S1A105K050BC"
			(at 0 0 0)
			(layer "F.Fab")
			(hide yes)
			(effects
				(font
					(size 1.27 1.27)
					(thickness 0.15)
				)
			)
		)
		(property "Description" "SMD Multilayer Ceramic Capacitor, 1 µF, 10 V, 0402 [1005 Metric], ± 10%, X6S, C"
			(at 0 0 0)
			(layer "F.Fab")
			(hide yes)
			(effects
				(font
					(size 1.27 1.27)
					(thickness 0.15)
				)
			)
		)
		(property "Author" "Antmicro"
			(at 0 0 0)
			(layer "B.Fab")
			(hide yes)
			(effects
				(font
					(size 1 1)
					(thickness 0.15)
				)
				(justify mirror)
			)
		)
		(property "Dielectric" ""
			(at 0 0 0)
			(layer "B.Fab")
			(hide yes)
			(effects
				(font
					(size 1 1)
					(thickness 0.15)
				)
				(justify mirror)
			)
		)
		(property "License" "Apache-2.0"
			(at 0 0 0)
			(layer "B.Fab")
			(hide yes)
			(effects
				(font
					(size 1 1)
					(thickness 0.15)
				)
				(justify mirror)
			)
		)
		(property "MPN" "C1005X6S1A105K050BC"
			(at 0 0 0)
			(layer "B.Fab")
			(hide yes)
			(effects
				(font
					(size 1 1)
					(thickness 0.15)
				)
				(justify mirror)
			)
		)
		(property "Manufacturer" "TDK"
			(at 0 0 0)
			(layer "B.Fab")
			(hide yes)
			(effects
				(font
					(size 1 1)
					(thickness 0.15)
				)
				(justify mirror)
			)
		)
		(property "Public" ""
			(at 0 0 0)
			(layer "B.Fab")
			(hide yes)
			(effects
				(font
					(size 1 1)
					(thickness 0.15)
				)
				(justify mirror)
			)
		)
		(property "Val" "1u"
			(at 0 0 0)
			(layer "B.Fab")
			(hide yes)
			(effects
				(font
					(size 1 1)
					(thickness 0.15)
				)
				(justify mirror)
			)
		)
		(property "Voltage" ""
			(at 0 0 0)
			(layer "B.Fab")
			(hide yes)
			(effects
				(font
					(size 1 1)
					(thickness 0.15)
				)
				(justify mirror)
			)
		)
		(sheetname "/Ethernet/")
		(sheetfile "ethernet.kicad_sch")
		(attr smd)
		(fp_rect
			(start -0.925 0.47)
			(end 0.925 -0.47)
			(stroke
				(width 0.05)
				(type default)
			)
			(fill no)
			(layer "B.CrtYd")
		)
		(fp_line
			(start -0.494 -0.248)
			(end -0.494 0.25)
			(stroke
				(width 0.15)
				(type solid)
			)
			(layer "B.Fab")
		)
		(fp_line
			(start -0.494 0.25)
			(end 0.504 0.25)
			(stroke
				(width 0.15)
				(type solid)
			)
			(layer "B.Fab")
		)
		(fp_line
			(start 0.504 -0.248)
			(end -0.494 -0.248)
			(stroke
				(width 0.15)
				(type solid)
			)
			(layer "B.Fab")
		)
		(fp_line
			(start 0.504 0.25)
			(end 0.504 -0.248)
			(stroke
				(width 0.15)
				(type solid)
			)
			(layer "B.Fab")
		)
		(fp_text user "${REFERENCE}"
			(at -0.939 -4.599 180)
			(layer "B.Fab")
			(effects
				(font
					(size 0.7 0.7)
					(thickness 0.15)
				)
				(justify left bottom mirror)
			)
		)
		(fp_text user "Author: Antmicro"
			(at -0.939 -3.399 180)
			(layer "B.Fab")
			(effects
				(font
					(size 0.7 0.7)
					(thickness 0.15)
				)
				(justify left bottom mirror)
			)
		)
		(fp_text user "License: Apache-2.0"
			(at -0.939 -5.799 180)
			(layer "B.Fab")
			(effects
				(font
					(size 0.7 0.7)
					(thickness 0.15)
				)
				(justify left bottom mirror)
			)
		)
		(pad "1" smd roundrect
			(at -0.48 0)
			(size 0.59 0.64)
			(layers "B.Cu" "B.Mask" "B.Paste")
			(roundrect_rratio 0.25)
			(net 417 "GND")
			(pintype "passive")
		)
		(pad "2" smd roundrect
			(at 0.48 0)
			(size 0.59 0.64)
			(layers "B.Cu" "B.Mask" "B.Paste")
			(roundrect_rratio 0.25)
			(net 418 "+2V5")
			(pintype "passive")
		)
	)
	(footprint "antmicro-footprints:C_0402_1005Metric"
		(layer "B.Cu")
		(at 194.72 137.64 90)
		(descr "Capacitor SMD 0402")
		(tags "capacitor SMD 0402")
		(property "Reference" "C41"
			(at -1.61 -0.52 90)
			(layer "B.SilkS")
			(effects
				(font
					(size 0.7 0.7)
					(thickness 0.15)
				)
				(justify right bottom mirror)
			)
		)
		(property "Value" "C_100n_0402"
			(at -1.022927 -2.155213 90)
			(layer "B.Fab")
			(hide yes)
			(effects
				(font
					(size 0.7 0.7)
					(thickness 0.15)
				)
				(justify right bottom mirror)
			)
		)
		(property "Datasheet" "https://www.murata.com/products/productdetail?partno=GRM155R61H104KE14%23"
			(at 0 0 90)
			(layer "F.Fab")
			(hide yes)
			(effects
				(font
					(size 1.27 1.27)
					(thickness 0.15)
				)
			)
		)
		(property "Description" "SMD Multilayer Ceramic Capacitor, 0.1 µF, 50 V, 0402 [1005 Metric], ± 10%, X5R, GRM Series"
			(at 0 0 90)
			(layer "F.Fab")
			(hide yes)
			(effects
				(font
					(size 1.27 1.27)
					(thickness 0.15)
				)
			)
		)
		(property "Author" "Antmicro"
			(at 332.36 -57.08 0)
			(layer "B.Fab")
			(hide yes)
			(effects
				(font
					(size 1 1)
					(thickness 0.15)
				)
				(justify mirror)
			)
		)
		(property "Dielectric" "X5R"
			(at 332.36 -57.08 0)
			(layer "B.Fab")
			(hide yes)
			(effects
				(font
					(size 1 1)
					(thickness 0.15)
				)
				(justify mirror)
			)
		)
		(property "License" "Apache-2.0"
			(at 332.36 -57.08 0)
			(layer "B.Fab")
			(hide yes)
			(effects
				(font
					(size 1 1)
					(thickness 0.15)
				)
				(justify mirror)
			)
		)
		(property "MPN" "GRM155R61H104KE14D"
			(at 332.36 -57.08 0)
			(layer "B.Fab")
			(hide yes)
			(effects
				(font
					(size 1 1)
					(thickness 0.15)
				)
				(justify mirror)
			)
		)
		(property "Manufacturer" "Murata"
			(at 332.36 -57.08 0)
			(layer "B.Fab")
			(hide yes)
			(effects
				(font
					(size 1 1)
					(thickness 0.15)
				)
				(justify mirror)
			)
		)
		(property "Public" ""
			(at 332.36 -57.08 0)
			(layer "B.Fab")
			(hide yes)
			(effects
				(font
					(size 1 1)
					(thickness 0.15)
				)
				(justify mirror)
			)
		)
		(property "Val" "100n"
			(at 332.36 -57.08 0)
			(layer "B.Fab")
			(hide yes)
			(effects
				(font
					(size 1 1)
					(thickness 0.15)
				)
				(justify mirror)
			)
		)
		(property "Voltage" "50V"
			(at 332.36 -57.08 0)
			(layer "B.Fab")
			(hide yes)
			(effects
				(font
					(size 1 1)
					(thickness 0.15)
				)
				(justify mirror)
			)
		)
		(sheetname "/FPGA Supply/")
		(sheetfile "fpga-supply.kicad_sch")
		(attr smd)
		(fp_rect
			(start -0.925 0.47)
			(end 0.925 -0.47)
			(stroke
				(width 0.05)
				(type default)
			)
			(fill no)
			(layer "B.CrtYd")
		)
		(fp_line
			(start 0.504 -0.248)
			(end -0.494 -0.248)
			(stroke
				(width 0.15)
				(type solid)
			)
			(layer "B.Fab")
		)
		(fp_line
			(start -0.494 -0.248)
			(end -0.494 0.25)
			(stroke
				(width 0.15)
				(type solid)
			)
			(layer "B.Fab")
		)
		(fp_line
			(start 0.504 0.25)
			(end 0.504 -0.248)
			(stroke
				(width 0.15)
				(type solid)
			)
			(layer "B.Fab")
		)
		(fp_line
			(start -0.494 0.25)
			(end 0.504 0.25)
			(stroke
				(width 0.15)
				(type solid)
			)
			(layer "B.Fab")
		)
		(fp_text user "Author: Antmicro"
			(at -0.939 -3.399 270)
			(layer "B.Fab")
			(effects
				(font
					(size 0.7 0.7)
					(thickness 0.15)
				)
				(justify left bottom mirror)
			)
		)
		(fp_text user "License: Apache-2.0"
			(at -0.939 -5.799 270)
			(layer "B.Fab")
			(effects
				(font
					(size 0.7 0.7)
					(thickness 0.15)
				)
				(justify left bottom mirror)
			)
		)
		(fp_text user "${REFERENCE}"
			(at -0.939 -4.599 270)
			(layer "B.Fab")
			(effects
				(font
					(size 0.7 0.7)
					(thickness 0.15)
				)
				(justify left bottom mirror)
			)
		)
		(pad "1" smd roundrect
			(at -0.48 0 90)
			(size 0.59 0.64)
			(layers "B.Cu" "B.Mask" "B.Paste")
			(roundrect_rratio 0.25)
			(net 417 "GND")
			(pintype "passive")
		)
		(pad "2" smd roundrect
			(at 0.48 0 90)
			(size 0.59 0.64)
			(layers "B.Cu" "B.Mask" "B.Paste")
			(roundrect_rratio 0.25)
			(net 418 "+2V5")
			(pintype "passive")
		)
	)
	(footprint "antmicro-footprints:C_0402_1005Metric"
		(layer "B.Cu")
		(at 184.85 135.325 90)
		(descr "Capacitor SMD 0402")
		(tags "capacitor SMD 0402")
		(property "Reference" "C159"
			(at -1.3 1.225 270)
			(layer "B.SilkS")
			(effects
				(font
					(size 0.7 0.7)
					(thickness 0.15)
				)
				(justify right bottom mirror)
			)
		)
		(property "Value" "C_1u_0402"
			(at -1.022927 -2.155213 90)
			(layer "B.Fab")
			(hide yes)
			(effects
				(font
					(size 0.7 0.7)
					(thickness 0.15)
				)
				(justify right bottom mirror)
			)
		)
		(property "Datasheet" "https://product.tdk.com/en/search/capacitor/ceramic/mlcc/info?part_no=C1005X6S1A105K050BC"
			(at 0 0 90)
			(layer "F.Fab")
			(hide yes)
			(effects
				(font
					(size 1.27 1.27)
					(thickness 0.15)
				)
			)
		)
		(property "Description" "SMD Multilayer Ceramic Capacitor, 1 µF, 10 V, 0402 [1005 Metric], ± 10%, X6S, C"
			(at 0 0 90)
			(layer "F.Fab")
			(hide yes)
			(effects
				(font
					(size 1.27 1.27)
					(thickness 0.15)
				)
			)
		)
		(property "Author" "Antmicro"
			(at 320.175 -49.525 0)
			(layer "B.Fab")
			(hide yes)
			(effects
				(font
					(size 1 1)
					(thickness 0.15)
				)
				(justify mirror)
			)
		)
		(property "Dielectric" "X5R"
			(at 320.175 -49.525 0)
			(layer "B.Fab")
			(hide yes)
			(effects
				(font
					(size 1 1)
					(thickness 0.15)
				)
				(justify mirror)
			)
		)
		(property "License" "Apache-2.0"
			(at 320.175 -49.525 0)
			(layer "B.Fab")
			(hide yes)
			(effects
				(font
					(size 1 1)
					(thickness 0.15)
				)
				(justify mirror)
			)
		)
		(property "MPN" "C1005X6S1A105K050BC"
			(at 320.175 -49.525 0)
			(layer "B.Fab")
			(hide yes)
			(effects
				(font
					(size 1 1)
					(thickness 0.15)
				)
				(justify mirror)
			)
		)
		(property "Manufacturer" "TDK"
			(at 320.175 -49.525 0)
			(layer "B.Fab")
			(hide yes)
			(effects
				(font
					(size 1 1)
					(thickness 0.15)
				)
				(justify mirror)
			)
		)
		(property "Public" ""
			(at 320.175 -49.525 0)
			(layer "B.Fab")
			(hide yes)
			(effects
				(font
					(size 1 1)
					(thickness 0.15)
				)
				(justify mirror)
			)
		)
		(property "Val" "1u"
			(at 320.175 -49.525 0)
			(layer "B.Fab")
			(hide yes)
			(effects
				(font
					(size 1 1)
					(thickness 0.15)
				)
				(justify mirror)
			)
		)
		(property "Voltage" "16V"
			(at 320.175 -49.525 0)
			(layer "B.Fab")
			(hide yes)
			(effects
				(font
					(size 1 1)
					(thickness 0.15)
				)
				(justify mirror)
			)
		)
		(sheetname "/LPDDR4/")
		(sheetfile "lpddr.kicad_sch")
		(attr smd)
		(fp_rect
			(start -0.925 0.47)
			(end 0.925 -0.47)
			(stroke
				(width 0.05)
				(type default)
			)
			(fill no)
			(layer "B.CrtYd")
		)
		(fp_line
			(start 0.504 -0.248)
			(end -0.494 -0.248)
			(stroke
				(width 0.15)
				(type solid)
			)
			(layer "B.Fab")
		)
		(fp_line
			(start -0.494 -0.248)
			(end -0.494 0.25)
			(stroke
				(width 0.15)
				(type solid)
			)
			(layer "B.Fab")
		)
		(fp_line
			(start 0.504 0.25)
			(end 0.504 -0.248)
			(stroke
				(width 0.15)
				(type solid)
			)
			(layer "B.Fab")
		)
		(fp_line
			(start -0.494 0.25)
			(end 0.504 0.25)
			(stroke
				(width 0.15)
				(type solid)
			)
			(layer "B.Fab")
		)
		(fp_text user "Author: Antmicro"
			(at -0.939 -3.399 270)
			(layer "B.Fab")
			(effects
				(font
					(size 0.7 0.7)
					(thickness 0.15)
				)
				(justify left bottom mirror)
			)
		)
		(fp_text user "${REFERENCE}"
			(at -0.939 -4.599 270)
			(layer "B.Fab")
			(effects
				(font
					(size 0.7 0.7)
					(thickness 0.15)
				)
				(justify left bottom mirror)
			)
		)
		(fp_text user "License: Apache-2.0"
			(at -0.939 -5.799 270)
			(layer "B.Fab")
			(effects
				(font
					(size 0.7 0.7)
					(thickness 0.15)
				)
				(justify left bottom mirror)
			)
		)
		(pad "1" smd roundrect
			(at -0.48 0 90)
			(size 0.59 0.64)
			(layers "B.Cu" "B.Mask" "B.Paste")
			(roundrect_rratio 0.25)
			(net 417 "GND")
			(pintype "passive")
		)
		(pad "2" smd roundrect
			(at 0.48 0 90)
			(size 0.59 0.64)
			(layers "B.Cu" "B.Mask" "B.Paste")
			(roundrect_rratio 0.25)
			(net 2 "+1V1")
			(pintype "passive")
		)
	)
	(footprint "antmicro-footprints:SOT-583"
		(layer "B.Cu")
		(at 222.175 136 -90)
		(property "Reference" "U10"
			(at -0.55 1.35 90)
			(layer "B.SilkS")
			(effects
				(font
					(size 0.7 0.7)
					(thickness 0.15)
				)
				(justify left bottom mirror)
			)
		)
		(property "Value" "TPS2117DRLR"
			(at 0 -2.3 90)
			(layer "B.Fab")
			(hide yes)
			(effects
				(font
					(size 0.7 0.7)
					(thickness 0.15)
				)
				(justify left bottom mirror)
			)
		)
		(property "Datasheet" "https://www.ti.com/lit/ds/symlink/tps2117.pdf"
			(at 0 0 270)
			(layer "F.Fab")
			(hide yes)
			(effects
				(font
					(size 1.27 1.27)
					(thickness 0.15)
				)
			)
		)
		(property "Description" "TPS2117 1.6-V to 5.5-V, 4-A Low IQ Power Mux With Manual and Priority Switchover"
			(at 0 0 270)
			(layer "F.Fab")
			(hide yes)
			(effects
				(font
					(size 1.27 1.27)
					(thickness 0.15)
				)
			)
		)
		(property "Author" "Antmicro"
			(at 86.175 358.175 0)
			(layer "B.Fab")
			(hide yes)
			(effects
				(font
					(size 1 1)
					(thickness 0.15)
				)
				(justify mirror)
			)
		)
		(property "License" "Apache-2.0"
			(at 86.175 358.175 0)
			(layer "B.Fab")
			(hide yes)
			(effects
				(font
					(size 1 1)
					(thickness 0.15)
				)
				(justify mirror)
			)
		)
		(property "MPN" "TPS2117DRLR"
			(at 86.175 358.175 0)
			(layer "B.Fab")
			(hide yes)
			(effects
				(font
					(size 1 1)
					(thickness 0.15)
				)
				(justify mirror)
			)
		)
		(property "Manufacturer" "Texas Instruments"
			(at 86.175 358.175 0)
			(layer "B.Fab")
			(hide yes)
			(effects
				(font
					(size 1 1)
					(thickness 0.15)
				)
				(justify mirror)
			)
		)
		(property ki_fp_filters "DRL0008A-MFG")
		(sheetname "/Memory/")
		(sheetfile "memory.kicad_sch")
		(attr smd)
		(fp_line
			(start -0.65 1.15)
			(end 0.65 1.15)
			(stroke
				(width 0.15)
				(type solid)
			)
			(layer "B.SilkS")
		)
		(fp_line
			(start -0.651 -1.15)
			(end 0.651 -1.15)
			(stroke
				(width 0.15)
				(type solid)
			)
			(layer "B.SilkS")
		)
		(fp_circle
			(center -0.9 1.1)
			(end -0.85 1.05)
			(stroke
				(width 0.15)
				(type solid)
			)
			(fill yes)
			(layer "B.SilkS")
		)
		(fp_rect
			(start -1.15 1.3)
			(end 1.15 -1.3)
			(stroke
				(width 0.05)
				(type solid)
			)
			(fill no)
			(layer "B.CrtYd")
		)
		(fp_line
			(start -0.651 1.1005)
			(end 0.651 1.1005)
			(stroke
				(width 0.15)
				(type solid)
			)
			(layer "B.Fab")
		)
		(fp_line
			(start -0.651 -1.1005)
			(end -0.651 1.1005)
			(stroke
				(width 0.15)
				(type solid)
			)
			(layer "B.Fab")
		)
		(fp_line
			(start -0.651 -1.1005)
			(end 0.651 -1.1005)
			(stroke
				(width 0.15)
				(type solid)
			)
			(layer "B.Fab")
		)
		(fp_line
			(start 0.651 -1.1005)
			(end 0.651 1.1005)
			(stroke
				(width 0.15)
				(type solid)
			)
			(layer "B.Fab")
		)
		(fp_text user "License: Apache-2.0"
			(at -0.06 -6.025 90)
			(layer "B.Fab")
			(effects
				(font
					(size 0.7 0.7)
					(thickness 0.15)
				)
				(justify left bottom mirror)
			)
		)
		(fp_text user "Author: Antmicro"
			(at -0.06 -5.025 90)
			(layer "B.Fab")
			(effects
				(font
					(size 0.7 0.7)
					(thickness 0.15)
				)
				(justify left bottom mirror)
			)
		)
		(fp_text user "${REFERENCE}"
			(at -0.06 -4.025 90)
			(layer "B.Fab")
			(effects
				(font
					(size 0.7 0.7)
					(thickness 0.15)
				)
				(justify left bottom mirror)
			)
		)
		(pad "1" smd roundrect
			(at -0.739 0.7495 270)
			(size 0.670001 0.299999)
			(layers "B.Cu" "B.Mask" "B.Paste")
			(roundrect_rratio 0.25)
			(net 417 "GND")
			(pinfunction "GND")
			(pintype "power_in")
		)
		(pad "2" smd roundrect
			(at -0.739 0.2505 270)
			(size 0.670001 0.299999)
			(layers "B.Cu" "B.Mask" "B.Paste")
			(roundrect_rratio 0.25)
			(net 518 "Net-(R56-Pad1)")
			(pinfunction "VOUT")
			(pintype "power_out")
		)
		(pad "3" smd roundrect
			(at -0.739 -0.2495 270)
			(size 0.670001 0.299999)
			(layers "B.Cu" "B.Mask" "B.Paste")
			(roundrect_rratio 0.25)
			(net 418 "+2V5")
			(pinfunction "VIN1")
			(pintype "power_in")
		)
		(pad "4" smd roundrect
			(at -0.739 -0.7495 270)
			(size 0.670001 0.299999)
			(layers "B.Cu" "B.Mask" "B.Paste")
			(roundrect_rratio 0.25)
			(net 246 "SD_VDD_OVERRIDE")
			(pinfunction "PR1")
			(pintype "input")
		)
		(pad "5" smd roundrect
			(at 0.74 -0.7495 270)
			(size 0.670001 0.299999)
			(layers "B.Cu" "B.Mask" "B.Paste")
			(roundrect_rratio 0.25)
			(net 50 "+3V3")
			(pinfunction "MODE")
			(pintype "input")
		)
		(pad "6" smd roundrect
			(at 0.74 -0.2495 270)
			(size 0.670001 0.299999)
			(layers "B.Cu" "B.Mask" "B.Paste")
			(roundrect_rratio 0.25)
			(net 50 "+3V3")
			(pinfunction "VIN2")
			(pintype "power_in")
		)
		(pad "7" smd roundrect
			(at 0.74 0.2505 270)
			(size 0.670001 0.299999)
			(layers "B.Cu" "B.Mask" "B.Paste")
			(roundrect_rratio 0.25)
			(net 518 "Net-(R56-Pad1)")
			(pinfunction "VOUT")
			(pintype "passive")
		)
		(pad "8" smd roundrect
			(at 0.74 0.7495 270)
			(size 0.670001 0.299999)
			(layers "B.Cu" "B.Mask" "B.Paste")
			(roundrect_rratio 0.25)
			(net 523 "unconnected-(U10-ST-Pad8)")
			(pinfunction "ST")
			(pintype "output+no_connect")
		)
	)
	(footprint "antmicro-footprints:C_0402_1005Metric"
		(layer "B.Cu")
		(at 222.43 152.76)
		(descr "Capacitor SMD 0402")
		(tags "capacitor SMD 0402")
		(property "Reference" "C3"
			(at 0.96 1.74 0)
			(layer "B.SilkS")
			(effects
				(font
					(size 0.7 0.7)
					(thickness 0.15)
				)
				(justify right bottom mirror)
			)
		)
		(property "Value" "C_100n_0402"
			(at -1.022927 -2.155213 0)
			(layer "B.Fab")
			(hide yes)
			(effects
				(font
					(size 0.7 0.7)
					(thickness 0.15)
				)
				(justify right bottom mirror)
			)
		)
		(property "Datasheet" "https://www.murata.com/products/productdetail?partno=GRM155R61H104KE14%23"
			(at 0 0 0)
			(layer "F.Fab")
			(hide yes)
			(effects
				(font
					(size 1.27 1.27)
					(thickness 0.15)
				)
			)
		)
		(property "Description" "SMD Multilayer Ceramic Capacitor, 0.1 µF, 50 V, 0402 [1005 Metric], ± 10%, X5R, GRM Series"
			(at 0 0 0)
			(layer "F.Fab")
			(hide yes)
			(effects
				(font
					(size 1.27 1.27)
					(thickness 0.15)
				)
			)
		)
		(property "Author" "Antmicro"
			(at 0 0 0)
			(layer "B.Fab")
			(hide yes)
			(effects
				(font
					(size 1 1)
					(thickness 0.15)
				)
				(justify mirror)
			)
		)
		(property "Dielectric" "X5R"
			(at 0 0 0)
			(layer "B.Fab")
			(hide yes)
			(effects
				(font
					(size 1 1)
					(thickness 0.15)
				)
				(justify mirror)
			)
		)
		(property "License" "Apache-2.0"
			(at 0 0 0)
			(layer "B.Fab")
			(hide yes)
			(effects
				(font
					(size 1 1)
					(thickness 0.15)
				)
				(justify mirror)
			)
		)
		(property "MPN" "GRM155R61H104KE14D"
			(at 0 0 0)
			(layer "B.Fab")
			(hide yes)
			(effects
				(font
					(size 1 1)
					(thickness 0.15)
				)
				(justify mirror)
			)
		)
		(property "Manufacturer" "Murata"
			(at 0 0 0)
			(layer "B.Fab")
			(hide yes)
			(effects
				(font
					(size 1 1)
					(thickness 0.15)
				)
				(justify mirror)
			)
		)
		(property "Public" ""
			(at 0 0 0)
			(layer "B.Fab")
			(hide yes)
			(effects
				(font
					(size 1 1)
					(thickness 0.15)
				)
				(justify mirror)
			)
		)
		(property "Val" "100n"
			(at 0 0 0)
			(layer "B.Fab")
			(hide yes)
			(effects
				(font
					(size 1 1)
					(thickness 0.15)
				)
				(justify mirror)
			)
		)
		(property "Voltage" "50V"
			(at 0 0 0)
			(layer "B.Fab")
			(hide yes)
			(effects
				(font
					(size 1 1)
					(thickness 0.15)
				)
				(justify mirror)
			)
		)
		(sheetname "/PCIe/")
		(sheetfile "pcie.kicad_sch")
		(attr smd)
		(fp_rect
			(start -0.925 0.47)
			(end 0.925 -0.47)
			(stroke
				(width 0.05)
				(type default)
			)
			(fill no)
			(layer "B.CrtYd")
		)
		(fp_line
			(start -0.494 -0.248)
			(end -0.494 0.25)
			(stroke
				(width 0.15)
				(type solid)
			)
			(layer "B.Fab")
		)
		(fp_line
			(start -0.494 0.25)
			(end 0.504 0.25)
			(stroke
				(width 0.15)
				(type solid)
			)
			(layer "B.Fab")
		)
		(fp_line
			(start 0.504 -0.248)
			(end -0.494 -0.248)
			(stroke
				(width 0.15)
				(type solid)
			)
			(layer "B.Fab")
		)
		(fp_line
			(start 0.504 0.25)
			(end 0.504 -0.248)
			(stroke
				(width 0.15)
				(type solid)
			)
			(layer "B.Fab")
		)
		(fp_text user "Author: Antmicro"
			(at -0.939 -3.399 180)
			(layer "B.Fab")
			(effects
				(font
					(size 0.7 0.7)
					(thickness 0.15)
				)
				(justify left bottom mirror)
			)
		)
		(fp_text user "${REFERENCE}"
			(at -0.939 -4.599 180)
			(layer "B.Fab")
			(effects
				(font
					(size 0.7 0.7)
					(thickness 0.15)
				)
				(justify left bottom mirror)
			)
		)
		(fp_text user "License: Apache-2.0"
			(at -0.939 -5.799 180)
			(layer "B.Fab")
			(effects
				(font
					(size 0.7 0.7)
					(thickness 0.15)
				)
				(justify left bottom mirror)
			)
		)
		(pad "1" smd roundrect
			(at -0.48 0)
			(size 0.59 0.64)
			(layers "B.Cu" "B.Mask" "B.Paste")
			(roundrect_rratio 0.25)
			(net 417 "GND")
			(pintype "passive")
		)
		(pad "2" smd roundrect
			(at 0.48 0)
			(size 0.59 0.64)
			(layers "B.Cu" "B.Mask" "B.Paste")
			(roundrect_rratio 0.25)
			(net 418 "+2V5")
			(pintype "passive")
		)
	)
	(footprint "antmicro-footprints:C_0402_1005Metric"
		(layer "B.Cu")
		(at 204.5 135.01 90)
		(descr "Capacitor SMD 0402")
		(tags "capacitor SMD 0402")
		(property "Reference" "C57"
			(at 1.01 0.5 90)
			(layer "B.SilkS")
			(effects
				(font
					(size 0.7 0.7)
					(thickness 0.15)
				)
				(justify right bottom mirror)
			)
		)
		(property "Value" "C_4n7_0402"
			(at -1.022927 -2.155213 90)
			(layer "B.Fab")
			(hide yes)
			(effects
				(font
					(size 0.7 0.7)
					(thickness 0.15)
				)
				(justify right bottom mirror)
			)
		)
		(property "Datasheet" "https://product.tdk.com/en/search/capacitor/ceramic/mlcc/info?part_no=CGA2B3X7S2A472K050BB"
			(at 0 0 90)
			(layer "F.Fab")
			(hide yes)
			(effects
				(font
					(size 1.27 1.27)
					(thickness 0.15)
				)
			)
		)
		(property "Description" "SMD Multilayer Ceramic Capacitor, 4700 pF, 100 V, 0402 [1005 Metric], ± 10%, X7S, CGA"
			(at 0 0 90)
			(layer "F.Fab")
			(hide yes)
			(effects
				(font
					(size 1.27 1.27)
					(thickness 0.15)
				)
			)
		)
		(property "Author" "Antmicro"
			(at 339.51 -69.49 0)
			(layer "B.Fab")
			(hide yes)
			(effects
				(font
					(size 1 1)
					(thickness 0.15)
				)
				(justify mirror)
			)
		)
		(property "Dielectric" "X7R"
			(at 339.51 -69.49 0)
			(layer "B.Fab")
			(hide yes)
			(effects
				(font
					(size 1 1)
					(thickness 0.15)
				)
				(justify mirror)
			)
		)
		(property "License" "Apache-2.0"
			(at 339.51 -69.49 0)
			(layer "B.Fab")
			(hide yes)
			(effects
				(font
					(size 1 1)
					(thickness 0.15)
				)
				(justify mirror)
			)
		)
		(property "MPN" "CGA2B3X7S2A472K050BB"
			(at 339.51 -69.49 0)
			(layer "B.Fab")
			(hide yes)
			(effects
				(font
					(size 1 1)
					(thickness 0.15)
				)
				(justify mirror)
			)
		)
		(property "Manufacturer" "TDK"
			(at 339.51 -69.49 0)
			(layer "B.Fab")
			(hide yes)
			(effects
				(font
					(size 1 1)
					(thickness 0.15)
				)
				(justify mirror)
			)
		)
		(property "Public" ""
			(at 339.51 -69.49 0)
			(layer "B.Fab")
			(hide yes)
			(effects
				(font
					(size 1 1)
					(thickness 0.15)
				)
				(justify mirror)
			)
		)
		(property "Val" "4n7"
			(at 339.51 -69.49 0)
			(layer "B.Fab")
			(hide yes)
			(effects
				(font
					(size 1 1)
					(thickness 0.15)
				)
				(justify mirror)
			)
		)
		(property "Voltage" "25V"
			(at 339.51 -69.49 0)
			(layer "B.Fab")
			(hide yes)
			(effects
				(font
					(size 1 1)
					(thickness 0.15)
				)
				(justify mirror)
			)
		)
		(sheetname "/FPGA Supply/")
		(sheetfile "fpga-supply.kicad_sch")
		(attr smd)
		(fp_rect
			(start -0.925 0.47)
			(end 0.925 -0.47)
			(stroke
				(width 0.05)
				(type default)
			)
			(fill no)
			(layer "B.CrtYd")
		)
		(fp_line
			(start 0.504 -0.248)
			(end -0.494 -0.248)
			(stroke
				(width 0.15)
				(type solid)
			)
			(layer "B.Fab")
		)
		(fp_line
			(start -0.494 -0.248)
			(end -0.494 0.25)
			(stroke
				(width 0.15)
				(type solid)
			)
			(layer "B.Fab")
		)
		(fp_line
			(start 0.504 0.25)
			(end 0.504 -0.248)
			(stroke
				(width 0.15)
				(type solid)
			)
			(layer "B.Fab")
		)
		(fp_line
			(start -0.494 0.25)
			(end 0.504 0.25)
			(stroke
				(width 0.15)
				(type solid)
			)
			(layer "B.Fab")
		)
		(fp_text user "Author: Antmicro"
			(at -0.939 -3.399 270)
			(layer "B.Fab")
			(effects
				(font
					(size 0.7 0.7)
					(thickness 0.15)
				)
				(justify left bottom mirror)
			)
		)
		(fp_text user "License: Apache-2.0"
			(at -0.939 -5.799 270)
			(layer "B.Fab")
			(effects
				(font
					(size 0.7 0.7)
					(thickness 0.15)
				)
				(justify left bottom mirror)
			)
		)
		(fp_text user "${REFERENCE}"
			(at -0.939 -4.599 270)
			(layer "B.Fab")
			(effects
				(font
					(size 0.7 0.7)
					(thickness 0.15)
				)
				(justify left bottom mirror)
			)
		)
		(pad "1" smd roundrect
			(at -0.48 0 90)
			(size 0.59 0.64)
			(layers "B.Cu" "B.Mask" "B.Paste")
			(roundrect_rratio 0.25)
			(net 417 "GND")
			(pintype "passive")
		)
		(pad "2" smd roundrect
			(at 0.48 0 90)
			(size 0.59 0.64)
			(layers "B.Cu" "B.Mask" "B.Paste")
			(roundrect_rratio 0.25)
			(net 649 "VDD")
			(pintype "passive")
		)
	)
	(footprint "antmicro-footprints:Fiducial_1mm_Mask2mm"
		(layer "B.Cu")
		(at 175.76 120.87 180)
		(descr "Circular Fiducial, 1mm bare copper, 3mm soldermask opening")
		(tags "fiducial")
		(property "Reference" "FD6"
			(at 0 1.4 0)
			(layer "B.SilkS")
			(hide yes)
			(effects
				(font
					(size 0.7 0.7)
					(thickness 0.15)
				)
				(justify left bottom mirror)
			)
		)
		(property "Value" "Fiducial_1mm_Mask2mm"
			(at 0 -2.2 0)
			(layer "B.Fab")
			(hide yes)
			(effects
				(font
					(size 0.7 0.7)
					(thickness 0.15)
				)
				(justify left bottom mirror)
			)
		)
		(property "Description" "Fiducial mask "
			(at 0 0 180)
			(layer "F.Fab")
			(hide yes)
			(effects
				(font
					(size 1.27 1.27)
					(thickness 0.15)
				)
			)
		)
		(property "Author" "Antmicro"
			(at 351.52 241.74 0)
			(layer "B.Fab")
			(hide yes)
			(effects
				(font
					(size 1 1)
					(thickness 0.15)
				)
				(justify mirror)
			)
		)
		(property "License" "Apache-2.0"
			(at 351.52 241.74 0)
			(layer "B.Fab")
			(hide yes)
			(effects
				(font
					(size 1 1)
					(thickness 0.15)
				)
				(justify mirror)
			)
		)
		(property "exclude_from_bom" ""
			(at 351.52 241.74 0)
			(layer "B.Fab")
			(hide yes)
			(effects
				(font
					(size 1 1)
					(thickness 0.15)
				)
				(justify mirror)
			)
		)
		(sheetfile "polarfire-som.kicad_sch")
		(attr board_only exclude_from_pos_files exclude_from_bom)
		(fp_circle
			(center 0 0)
			(end 1.24 0)
			(stroke
				(width 0.05)
				(type solid)
			)
			(fill no)
			(layer "B.CrtYd")
		)
		(fp_circle
			(center 0 0)
			(end 0.999 0)
			(stroke
				(width 0.15)
				(type solid)
			)
			(fill no)
			(layer "B.Fab")
		)
		(fp_text user "License: Apache-2.0"
			(at -1.25 -7.003 0)
			(layer "B.Fab")
			(effects
				(font
					(size 0.7 0.7)
					(thickness 0.15)
				)
				(justify left bottom mirror)
			)
		)
		(fp_text user "${REFERENCE}"
			(at -1.25 -4.603 0)
			(layer "B.Fab")
			(effects
				(font
					(size 0.7 0.7)
					(thickness 0.15)
				)
				(justify left bottom mirror)
			)
		)
		(fp_text user "Author: Antmicro"
			(at -1.25 -5.803 0)
			(layer "B.Fab")
			(effects
				(font
					(size 0.7 0.7)
					(thickness 0.15)
				)
				(justify left bottom mirror)
			)
		)
		(pad "" smd circle
			(at 0 0 180)
			(size 1 1)
			(layers "B.Cu" "B.Mask")
			(solder_mask_margin 0.5)
			(clearance 0.5)
		)
	)
	(footprint "antmicro-footprints:D_0402_1005Metric"
		(layer "B.Cu")
		(at 211.05 150.413 180)
		(property "Reference" "D4"
			(at -0.575 -1.312 0)
			(layer "B.SilkS")
			(effects
				(font
					(size 0.7 0.7)
					(thickness 0.15)
				)
				(justify left bottom mirror)
			)
		)
		(property "Value" "AXGD10402KR"
			(at -2.54 -2.54 0)
			(layer "B.Fab")
			(hide yes)
			(effects
				(font
					(size 0.7 0.7)
					(thickness 0.15)
				)
				(justify left bottom mirror)
			)
		)
		(property "Datasheet" "https://www.littelfuse.com/media?resourcetype=datasheets&itemid=020b2bf2-064c-4ff1-a898-b4ec805b2fea&filename=littelfuse-xtremeguard-axgd-datasheet"
			(at 0 0 180)
			(layer "F.Fab")
			(hide yes)
			(effects
				(font
					(size 1.27 1.27)
					(thickness 0.15)
				)
			)
		)
		(property "Description" "Bidirectional TVS, 30 kV,  0402, 24 V, 0.04 pF"
			(at 0 0 180)
			(layer "F.Fab")
			(hide yes)
			(effects
				(font
					(size 1.27 1.27)
					(thickness 0.15)
				)
			)
		)
		(property "Author" "Antmicro"
			(at 422.1 300.826 0)
			(layer "B.Fab")
			(hide yes)
			(effects
				(font
					(size 1 1)
					(thickness 0.15)
				)
				(justify mirror)
			)
		)
		(property "License" "Apache-2.0"
			(at 422.1 300.826 0)
			(layer "B.Fab")
			(hide yes)
			(effects
				(font
					(size 1 1)
					(thickness 0.15)
				)
				(justify mirror)
			)
		)
		(property "MPN" "AXGD10402KR"
			(at 422.1 300.826 0)
			(layer "B.Fab")
			(hide yes)
			(effects
				(font
					(size 1 1)
					(thickness 0.15)
				)
				(justify mirror)
			)
		)
		(property "Manufacturer" "Littelfuse"
			(at 422.1 300.826 0)
			(layer "B.Fab")
			(hide yes)
			(effects
				(font
					(size 1 1)
					(thickness 0.15)
				)
				(justify mirror)
			)
		)
		(property "Public" ""
			(at 422.1 300.826 0)
			(layer "B.Fab")
			(hide yes)
			(effects
				(font
					(size 1 1)
					(thickness 0.15)
				)
				(justify mirror)
			)
		)
		(sheetname "/USB/")
		(sheetfile "usb.kicad_sch")
		(attr smd)
		(fp_line
			(start 0.1 0.255)
			(end -0.1 0.255)
			(stroke
				(width 0.15)
				(type solid)
			)
			(layer "B.SilkS")
		)
		(fp_line
			(start -0.1 -0.255)
			(end 0.1 -0.255)
			(stroke
				(width 0.15)
				(type solid)
			)
			(layer "B.SilkS")
		)
		(fp_line
			(start -0.875 0.25)
			(end -0.875 -0.25)
			(stroke
				(width 0.15)
				(type solid)
			)
			(layer "B.SilkS")
		)
		(fp_rect
			(start -0.925 0.47)
			(end 0.925 -0.47)
			(stroke
				(width 0.05)
				(type default)
			)
			(fill no)
			(layer "B.CrtYd")
		)
		(fp_line
			(start 0.51 0.255)
			(end 0.51 -0.255)
			(stroke
				(width 0.15)
				(type solid)
			)
			(layer "B.Fab")
		)
		(fp_line
			(start 0.51 -0.255)
			(end -0.51 -0.255)
			(stroke
				(width 0.15)
				(type solid)
			)
			(layer "B.Fab")
		)
		(fp_line
			(start -0.2 0.25)
			(end -0.5 -0.05)
			(stroke
				(width 0.15)
				(type solid)
			)
			(layer "B.Fab")
		)
		(fp_line
			(start -0.51 0.255)
			(end 0.51 0.255)
			(stroke
				(width 0.15)
				(type solid)
			)
			(layer "B.Fab")
		)
		(fp_line
			(start -0.51 -0.255)
			(end -0.51 0.255)
			(stroke
				(width 0.15)
				(type solid)
			)
			(layer "B.Fab")
		)
		(fp_text user "${REFERENCE}"
			(at -2.54 -4.54 0)
			(layer "B.Fab")
			(effects
				(font
					(size 0.7 0.7)
					(thickness 0.15)
				)
				(justify left bottom mirror)
			)
		)
		(fp_text user "Author: Antmicro"
			(at -2.54 -6.94 0)
			(layer "B.Fab")
			(effects
				(font
					(size 0.7 0.7)
					(thickness 0.15)
				)
				(justify left bottom mirror)
			)
		)
		(fp_text user "License: Apache-2.0"
			(at -2.54 -5.74 0)
			(layer "B.Fab")
			(effects
				(font
					(size 0.7 0.7)
					(thickness 0.15)
				)
				(justify left bottom mirror)
			)
		)
		(pad "1" smd roundrect
			(at -0.48 0 180)
			(size 0.59 0.64)
			(layers "B.Cu" "B.Mask" "B.Paste")
			(roundrect_rratio 0.25)
			(net 417 "GND")
			(pinfunction "C")
			(pintype "passive")
		)
		(pad "2" smd roundrect
			(at 0.48 0 180)
			(size 0.59 0.64)
			(layers "B.Cu" "B.Mask" "B.Paste")
			(roundrect_rratio 0.25)
			(net 62 "USB_OTG_ID")
			(pinfunction "A")
			(pintype "passive")
		)
	)
	(footprint "antmicro-footprints:C_0402_1005Metric"
		(layer "B.Cu")
		(at 177.2 128.3 -90)
		(descr "Capacitor SMD 0402")
		(tags "capacitor SMD 0402")
		(property "Reference" "C126"
			(at 1.24 -3.205 180)
			(layer "B.SilkS")
			(effects
				(font
					(size 0.7 0.7)
					(thickness 0.15)
				)
				(justify left bottom mirror)
			)
		)
		(property "Value" "C_1u_0402"
			(at -1.022927 -2.155213 90)
			(layer "B.Fab")
			(hide yes)
			(effects
				(font
					(size 0.7 0.7)
					(thickness 0.15)
				)
				(justify left bottom mirror)
			)
		)
		(property "Datasheet" "https://product.tdk.com/en/search/capacitor/ceramic/mlcc/info?part_no=C1005X6S1A105K050BC"
			(at 0 0 270)
			(layer "F.Fab")
			(hide yes)
			(effects
				(font
					(size 1.27 1.27)
					(thickness 0.15)
				)
			)
		)
		(property "Description" "SMD Multilayer Ceramic Capacitor, 1 µF, 10 V, 0402 [1005 Metric], ± 10%, X6S, C"
			(at 0 0 270)
			(layer "F.Fab")
			(hide yes)
			(effects
				(font
					(size 1.27 1.27)
					(thickness 0.15)
				)
			)
		)
		(property "Author" "Antmicro"
			(at 48.9 305.5 0)
			(layer "B.Fab")
			(hide yes)
			(effects
				(font
					(size 1 1)
					(thickness 0.15)
				)
				(justify mirror)
			)
		)
		(property "Dielectric" "X5R"
			(at 48.9 305.5 0)
			(layer "B.Fab")
			(hide yes)
			(effects
				(font
					(size 1 1)
					(thickness 0.15)
				)
				(justify mirror)
			)
		)
		(property "License" "Apache-2.0"
			(at 48.9 305.5 0)
			(layer "B.Fab")
			(hide yes)
			(effects
				(font
					(size 1 1)
					(thickness 0.15)
				)
				(justify mirror)
			)
		)
		(property "MPN" "C1005X6S1A105K050BC"
			(at 48.9 305.5 0)
			(layer "B.Fab")
			(hide yes)
			(effects
				(font
					(size 1 1)
					(thickness 0.15)
				)
				(justify mirror)
			)
		)
		(property "Manufacturer" "TDK"
			(at 48.9 305.5 0)
			(layer "B.Fab")
			(hide yes)
			(effects
				(font
					(size 1 1)
					(thickness 0.15)
				)
				(justify mirror)
			)
		)
		(property "Public" ""
			(at 48.9 305.5 0)
			(layer "B.Fab")
			(hide yes)
			(effects
				(font
					(size 1 1)
					(thickness 0.15)
				)
				(justify mirror)
			)
		)
		(property "Val" "1u"
			(at 48.9 305.5 0)
			(layer "B.Fab")
			(hide yes)
			(effects
				(font
					(size 1 1)
					(thickness 0.15)
				)
				(justify mirror)
			)
		)
		(property "Voltage" "16V"
			(at 48.9 305.5 0)
			(layer "B.Fab")
			(hide yes)
			(effects
				(font
					(size 1 1)
					(thickness 0.15)
				)
				(justify mirror)
			)
		)
		(sheetname "/LPDDR4/")
		(sheetfile "lpddr.kicad_sch")
		(attr smd)
		(fp_rect
			(start -0.925 0.47)
			(end 0.925 -0.47)
			(stroke
				(width 0.05)
				(type default)
			)
			(fill no)
			(layer "B.CrtYd")
		)
		(fp_line
			(start -0.494 0.25)
			(end 0.504 0.25)
			(stroke
				(width 0.15)
				(type solid)
			)
			(layer "B.Fab")
		)
		(fp_line
			(start 0.504 0.25)
			(end 0.504 -0.248)
			(stroke
				(width 0.15)
				(type solid)
			)
			(layer "B.Fab")
		)
		(fp_line
			(start -0.494 -0.248)
			(end -0.494 0.25)
			(stroke
				(width 0.15)
				(type solid)
			)
			(layer "B.Fab")
		)
		(fp_line
			(start 0.504 -0.248)
			(end -0.494 -0.248)
			(stroke
				(width 0.15)
				(type solid)
			)
			(layer "B.Fab")
		)
		(fp_text user "License: Apache-2.0"
			(at -0.939 -5.799 90)
			(layer "B.Fab")
			(effects
				(font
					(size 0.7 0.7)
					(thickness 0.15)
				)
				(justify left bottom mirror)
			)
		)
		(fp_text user "Author: Antmicro"
			(at -0.939 -3.399 90)
			(layer "B.Fab")
			(effects
				(font
					(size 0.7 0.7)
					(thickness 0.15)
				)
				(justify left bottom mirror)
			)
		)
		(fp_text user "${REFERENCE}"
			(at -0.939 -4.599 90)
			(layer "B.Fab")
			(effects
				(font
					(size 0.7 0.7)
					(thickness 0.15)
				)
				(justify left bottom mirror)
			)
		)
		(pad "1" smd roundrect
			(at -0.48 0 270)
			(size 0.59 0.64)
			(layers "B.Cu" "B.Mask" "B.Paste")
			(roundrect_rratio 0.25)
			(net 417 "GND")
			(pintype "passive")
		)
		(pad "2" smd roundrect
			(at 0.48 0 270)
			(size 0.59 0.64)
			(layers "B.Cu" "B.Mask" "B.Paste")
			(roundrect_rratio 0.25)
			(net 2 "+1V1")
			(pintype "passive")
		)
	)
	(footprint "antmicro-footprints:C_0402_1005Metric"
		(layer "B.Cu")
		(at 219.725 144.895 -90)
		(descr "Capacitor SMD 0402")
		(tags "capacitor SMD 0402")
		(property "Reference" "C287"
			(at -9.92 -7.23 90)
			(layer "B.SilkS")
			(effects
				(font
					(size 0.7 0.7)
					(thickness 0.15)
				)
				(justify left bottom mirror)
			)
		)
		(property "Value" "C_10u_0402"
			(at -1.022927 -2.155213 90)
			(layer "B.Fab")
			(hide yes)
			(effects
				(font
					(size 0.7 0.7)
					(thickness 0.15)
				)
				(justify left bottom mirror)
			)
		)
		(property "Datasheet" "https://www.yageo.com/en/Chart/Download/pdf/CC0402MRX5R5BB106"
			(at 0 0 270)
			(layer "F.Fab")
			(hide yes)
			(effects
				(font
					(size 1.27 1.27)
					(thickness 0.15)
				)
			)
		)
		(property "Description" "SMD Multilayer Ceramic Capacitor, 10 µF, 6.3 V, 0402 [1005 Metric], ± 20%, X5R, CC Series"
			(at 0 0 270)
			(layer "F.Fab")
			(hide yes)
			(effects
				(font
					(size 1.27 1.27)
					(thickness 0.15)
				)
			)
		)
		(property "Author" "Antmicro"
			(at 74.83 364.62 0)
			(layer "B.Fab")
			(hide yes)
			(effects
				(font
					(size 1 1)
					(thickness 0.15)
				)
				(justify mirror)
			)
		)
		(property "Dielectric" ""
			(at 74.83 364.62 0)
			(layer "B.Fab")
			(hide yes)
			(effects
				(font
					(size 1 1)
					(thickness 0.15)
				)
				(justify mirror)
			)
		)
		(property "License" "Apache-2.0"
			(at 74.83 364.62 0)
			(layer "B.Fab")
			(hide yes)
			(effects
				(font
					(size 1 1)
					(thickness 0.15)
				)
				(justify mirror)
			)
		)
		(property "MPN" "CC0402MRX5R5BB106"
			(at 74.83 364.62 0)
			(layer "B.Fab")
			(hide yes)
			(effects
				(font
					(size 1 1)
					(thickness 0.15)
				)
				(justify mirror)
			)
		)
		(property "Manufacturer" "YAGEO"
			(at 74.83 364.62 0)
			(layer "B.Fab")
			(hide yes)
			(effects
				(font
					(size 1 1)
					(thickness 0.15)
				)
				(justify mirror)
			)
		)
		(property "Public" ""
			(at 74.83 364.62 0)
			(layer "B.Fab")
			(hide yes)
			(effects
				(font
					(size 1 1)
					(thickness 0.15)
				)
				(justify mirror)
			)
		)
		(property "Val" "10u"
			(at 74.83 364.62 0)
			(layer "B.Fab")
			(hide yes)
			(effects
				(font
					(size 1 1)
					(thickness 0.15)
				)
				(justify mirror)
			)
		)
		(property "Voltage" ""
			(at 74.83 364.62 0)
			(layer "B.Fab")
			(hide yes)
			(effects
				(font
					(size 1 1)
					(thickness 0.15)
				)
				(justify mirror)
			)
		)
		(sheetname "/WiFi_Bluetooth/")
		(sheetfile "wifi_bt.kicad_sch")
		(attr smd)
		(fp_rect
			(start -0.925 0.47)
			(end 0.925 -0.47)
			(stroke
				(width 0.05)
				(type default)
			)
			(fill no)
			(layer "B.CrtYd")
		)
		(fp_line
			(start -0.494 0.25)
			(end 0.504 0.25)
			(stroke
				(width 0.15)
				(type solid)
			)
			(layer "B.Fab")
		)
		(fp_line
			(start 0.504 0.25)
			(end 0.504 -0.248)
			(stroke
				(width 0.15)
				(type solid)
			)
			(layer "B.Fab")
		)
		(fp_line
			(start -0.494 -0.248)
			(end -0.494 0.25)
			(stroke
				(width 0.15)
				(type solid)
			)
			(layer "B.Fab")
		)
		(fp_line
			(start 0.504 -0.248)
			(end -0.494 -0.248)
			(stroke
				(width 0.15)
				(type solid)
			)
			(layer "B.Fab")
		)
		(fp_text user "${REFERENCE}"
			(at -0.939 -4.599 90)
			(layer "B.Fab")
			(effects
				(font
					(size 0.7 0.7)
					(thickness 0.15)
				)
				(justify left bottom mirror)
			)
		)
		(fp_text user "Author: Antmicro"
			(at -0.939 -3.399 90)
			(layer "B.Fab")
			(effects
				(font
					(size 0.7 0.7)
					(thickness 0.15)
				)
				(justify left bottom mirror)
			)
		)
		(fp_text user "License: Apache-2.0"
			(at -0.939 -5.799 90)
			(layer "B.Fab")
			(effects
				(font
					(size 0.7 0.7)
					(thickness 0.15)
				)
				(justify left bottom mirror)
			)
		)
		(pad "1" smd roundrect
			(at -0.48 0 270)
			(size 0.59 0.64)
			(layers "B.Cu" "B.Mask" "B.Paste")
			(roundrect_rratio 0.25)
			(net 417 "GND")
			(pintype "passive")
		)
		(pad "2" smd roundrect
			(at 0.48 0 270)
			(size 0.59 0.64)
			(layers "B.Cu" "B.Mask" "B.Paste")
			(roundrect_rratio 0.25)
			(net 50 "+3V3")
			(pintype "passive")
		)
	)
	(footprint "antmicro-footprints:SOT-523"
		(layer "B.Cu")
		(at 183.6 154.2)
		(property "Reference" "Q6"
			(at -4.35 1.05 90)
			(layer "B.SilkS")
			(effects
				(font
					(size 0.7 0.7)
					(thickness 0.15)
				)
				(justify right bottom mirror)
			)
		)
		(property "Value" "DMG1012T-7"
			(at 0.1 -1.824 0)
			(layer "B.Fab")
			(hide yes)
			(effects
				(font
					(size 0.7 0.7)
					(thickness 0.15)
				)
				(justify right bottom mirror)
			)
		)
		(property "Datasheet" "https://www.diodes.com/assets/Datasheets/ds31783.pdf"
			(at 0 0 0)
			(layer "F.Fab")
			(hide yes)
			(effects
				(font
					(size 1.27 1.27)
					(thickness 0.15)
				)
			)
		)
		(property "Description" "Power MOSFET, N Channel, 20 V, 630 mA, 0.3 ohm, SOT-523, Surface Mount"
			(at 0 0 0)
			(layer "F.Fab")
			(hide yes)
			(effects
				(font
					(size 1.27 1.27)
					(thickness 0.15)
				)
			)
		)
		(property "Author" "Antmicro"
			(at 0 0 0)
			(layer "B.Fab")
			(hide yes)
			(effects
				(font
					(size 1 1)
					(thickness 0.15)
				)
				(justify mirror)
			)
		)
		(property "License" "Apache-2.0"
			(at 0 0 0)
			(layer "B.Fab")
			(hide yes)
			(effects
				(font
					(size 1 1)
					(thickness 0.15)
				)
				(justify mirror)
			)
		)
		(property "MPN" "DMG1012T-7"
			(at 0 0 0)
			(layer "B.Fab")
			(hide yes)
			(effects
				(font
					(size 1 1)
					(thickness 0.15)
				)
				(justify mirror)
			)
		)
		(property "Manufacturer" "Diodes Incorporated"
			(at 0 0 0)
			(layer "B.Fab")
			(hide yes)
			(effects
				(font
					(size 1 1)
					(thickness 0.15)
				)
				(justify mirror)
			)
		)
		(property "Public" ""
			(at 0 0 0)
			(layer "B.Fab")
			(hide yes)
			(effects
				(font
					(size 1 1)
					(thickness 0.15)
				)
				(justify mirror)
			)
		)
		(sheetname "/Supply/")
		(sheetfile "supply.kicad_sch")
		(attr smd)
		(fp_line
			(start -0.927 0.051)
			(end -0.927 0.351)
			(stroke
				(width 0.15)
				(type solid)
			)
			(layer "B.SilkS")
		)
		(fp_line
			(start -0.927 0.351)
			(end -0.725 0.551)
			(stroke
				(width 0.15)
				(type solid)
			)
			(layer "B.SilkS")
		)
		(fp_line
			(start -0.725 0.551)
			(end -0.277 0.551)
			(stroke
				(width 0.15)
				(type solid)
			)
			(layer "B.SilkS")
		)
		(fp_line
			(start -0.277 0.551)
			(end -0.277 0.75)
			(stroke
				(width 0.15)
				(type solid)
			)
			(layer "B.SilkS")
		)
		(fp_circle
			(center -0.9652 -0.9652)
			(end -0.9152 -0.9652)
			(stroke
				(width 0.15)
				(type solid)
			)
			(fill yes)
			(layer "B.SilkS")
		)
		(fp_line
			(start -1.12 -1.15)
			(end 1.1 -1.15)
			(stroke
				(width 0.05)
				(type solid)
			)
			(layer "B.CrtYd")
		)
		(fp_line
			(start -1.12 1.16)
			(end -1.12 -1.15)
			(stroke
				(width 0.05)
				(type solid)
			)
			(layer "B.CrtYd")
		)
		(fp_line
			(start -1.12 1.16)
			(end 1.1 1.16)
			(stroke
				(width 0.05)
				(type solid)
			)
			(layer "B.CrtYd")
		)
		(fp_line
			(start 1.1 1.16)
			(end 1.1 -1.15)
			(stroke
				(width 0.05)
				(type solid)
			)
			(layer "B.CrtYd")
		)
		(fp_line
			(start -0.802 0.276)
			(end -0.802 -0.424)
			(stroke
				(width 0.15)
				(type solid)
			)
			(layer "B.Fab")
		)
		(fp_line
			(start -0.652 0.425)
			(end -0.802 0.276)
			(stroke
				(width 0.15)
				(type solid)
			)
			(layer "B.Fab")
		)
		(fp_line
			(start 0.8 -0.424)
			(end -0.802 -0.424)
			(stroke
				(width 0.15)
				(type solid)
			)
			(layer "B.Fab")
		)
		(fp_line
			(start 0.8 0.425)
			(end -0.652 0.425)
			(stroke
				(width 0.15)
				(type solid)
			)
			(layer "B.Fab")
		)
		(fp_line
			(start 0.8 0.425)
			(end 0.8 -0.424)
			(stroke
				(width 0.15)
				(type solid)
			)
			(layer "B.Fab")
		)
		(fp_circle
			(center -0.9652 -0.9652)
			(end -0.9144 -0.9652)
			(stroke
				(width 0.15)
				(type solid)
			)
			(fill no)
			(layer "B.Fab")
		)
		(fp_text user "License: Apache-2.0"
			(at -1.12 -5.024 180)
			(layer "B.Fab")
			(effects
				(font
					(size 0.7 0.7)
					(thickness 0.15)
				)
				(justify left bottom mirror)
			)
		)
		(fp_text user "Author: Antmicro"
			(at -1.12 -6.224 180)
			(layer "B.Fab")
			(effects
				(font
					(size 0.7 0.7)
					(thickness 0.15)
				)
				(justify left bottom mirror)
			)
		)
		(fp_text user "${REFERENCE}"
			(at -1.12 -3.824 180)
			(layer "B.Fab")
			(effects
				(font
					(size 0.7 0.7)
					(thickness 0.15)
				)
				(justify left bottom mirror)
			)
		)
		(pad "1" smd rect
			(at -0.5 -0.65)
			(size 0.4 0.51)
			(layers "B.Cu" "B.Mask" "B.Paste")
			(net 656 "/Supply/PG")
			(pinfunction "G")
			(pintype "input")
		)
		(pad "2" smd rect
			(at 0.498 -0.65)
			(size 0.4 0.51)
			(layers "B.Cu" "B.Mask" "B.Paste")
			(net 417 "GND")
			(pinfunction "S")
			(pintype "passive")
		)
		(pad "3" smd rect
			(at 0 0.652)
			(size 0.4 0.51)
			(layers "B.Cu" "B.Mask" "B.Paste")
			(net 230 "~{PG}")
			(pinfunction "D")
			(pintype "passive")
		)
	)
	(footprint "antmicro-footprints:R_0402_1005Metric"
		(layer "B.Cu")
		(at 181.3 152.05 90)
		(descr "Resistor SMD 0402")
		(tags "resistor SMD 0402")
		(property "Reference" "R64"
			(at 2.95 0.3 270)
			(layer "B.SilkS")
			(effects
				(font
					(size 0.7 0.7)
					(thickness 0.15)
				)
				(justify left bottom mirror)
			)
		)
		(property "Value" "R_93k1_0402"
			(at -1.011843 -1.772047 270)
			(layer "B.Fab")
			(hide yes)
			(effects
				(font
					(size 0.7 0.7)
					(thickness 0.15)
				)
				(justify left bottom mirror)
			)
		)
		(property "Datasheet" "https://www.bourns.com/docs/product-datasheets/cr.pdf"
			(at 0 0 90)
			(layer "F.Fab")
			(hide yes)
			(effects
				(font
					(size 1.27 1.27)
					(thickness 0.15)
				)
			)
		)
		(property "Description" "SMD Chip Resistor"
			(at 0 0 90)
			(layer "F.Fab")
			(hide yes)
			(effects
				(font
					(size 1.27 1.27)
					(thickness 0.15)
				)
			)
		)
		(property "Author" "Antmicro"
			(at 333.35 -29.25 0)
			(layer "B.Fab")
			(hide yes)
			(effects
				(font
					(size 1 1)
					(thickness 0.15)
				)
				(justify mirror)
			)
		)
		(property "License" "Apache-2.0"
			(at 333.35 -29.25 0)
			(layer "B.Fab")
			(hide yes)
			(effects
				(font
					(size 1 1)
					(thickness 0.15)
				)
				(justify mirror)
			)
		)
		(property "MPN" "CR0402-FX-9312GLF"
			(at 333.35 -29.25 0)
			(layer "B.Fab")
			(hide yes)
			(effects
				(font
					(size 1 1)
					(thickness 0.15)
				)
				(justify mirror)
			)
		)
		(property "Manufacturer" "Bourns"
			(at 333.35 -29.25 0)
			(layer "B.Fab")
			(hide yes)
			(effects
				(font
					(size 1 1)
					(thickness 0.15)
				)
				(justify mirror)
			)
		)
		(property "Public" ""
			(at 333.35 -29.25 0)
			(layer "B.Fab")
			(hide yes)
			(effects
				(font
					(size 1 1)
					(thickness 0.15)
				)
				(justify mirror)
			)
		)
		(property "Tolerance" "1%"
			(at 333.35 -29.25 0)
			(layer "B.Fab")
			(hide yes)
			(effects
				(font
					(size 1 1)
					(thickness 0.15)
				)
				(justify mirror)
			)
		)
		(property "Val" "93k1"
			(at 333.35 -29.25 0)
			(layer "B.Fab")
			(hide yes)
			(effects
				(font
					(size 1 1)
					(thickness 0.15)
				)
				(justify mirror)
			)
		)
		(sheetname "/Supply/")
		(sheetfile "supply.kicad_sch")
		(attr smd)
		(fp_rect
			(start -0.925 0.47)
			(end 0.925 -0.47)
			(stroke
				(width 0.05)
				(type default)
			)
			(fill no)
			(layer "B.CrtYd")
		)
		(fp_rect
			(start -0.5 0.25)
			(end 0.5 -0.25)
			(stroke
				(width 0.15)
				(type solid)
			)
			(fill no)
			(layer "B.Fab")
		)
		(fp_text user "Author: Antmicro"
			(at -0.95 -4.169 270)
			(layer "B.Fab")
			(effects
				(font
					(size 0.7 0.7)
					(thickness 0.15)
				)
				(justify left bottom mirror)
			)
		)
		(fp_text user "License: Apache-2.0"
			(at -0.95 -5.169 270)
			(layer "B.Fab")
			(effects
				(font
					(size 0.7 0.7)
					(thickness 0.15)
				)
				(justify left bottom mirror)
			)
		)
		(fp_text user "${REFERENCE}"
			(at -0.95 -3.168 270)
			(layer "B.Fab")
			(effects
				(font
					(size 0.7 0.7)
					(thickness 0.15)
				)
				(justify left bottom mirror)
			)
		)
		(pad "1" smd roundrect
			(at -0.48 0 90)
			(size 0.59 0.64)
			(layers "B.Cu" "B.Mask" "B.Paste")
			(roundrect_rratio 0.25)
			(net 14 "Net-(C111-Pad1)")
			(pintype "passive")
		)
		(pad "2" smd roundrect
			(at 0.48 0 90)
			(size 0.59 0.64)
			(layers "B.Cu" "B.Mask" "B.Paste")
			(roundrect_rratio 0.25)
			(net 522 "/Supply/1V05_REG")
			(pintype "passive")
		)
	)
	(footprint "antmicro-footprints:C_0402_1005Metric"
		(layer "B.Cu")
		(at 208.12 143.58 180)
		(descr "Capacitor SMD 0402")
		(tags "capacitor SMD 0402")
		(property "Reference" "C201"
			(at 5.62 18.42 0)
			(layer "B.SilkS")
			(effects
				(font
					(size 0.7 0.7)
					(thickness 0.15)
				)
				(justify left bottom mirror)
			)
		)
		(property "Value" "C_10u_10V_0402"
			(at -1.022927 -2.155213 0)
			(layer "B.Fab")
			(hide yes)
			(effects
				(font
					(size 0.7 0.7)
					(thickness 0.15)
				)
				(justify left bottom mirror)
			)
		)
		(property "Datasheet" "https://www.murata.com/products/productdetail?partno=GRM155R61A106ME11%23"
			(at 0 0 180)
			(layer "F.Fab")
			(hide yes)
			(effects
				(font
					(size 1.27 1.27)
					(thickness 0.15)
				)
			)
		)
		(property "Description" "Multilayer Ceramic Capacitors MLCC - SMD/SMT 10 uF 10 VDC 20% 0402 X5R"
			(at 0 0 180)
			(layer "F.Fab")
			(hide yes)
			(effects
				(font
					(size 1.27 1.27)
					(thickness 0.15)
				)
			)
		)
		(property "Author" "Antmicro"
			(at 416.24 287.16 0)
			(layer "B.Fab")
			(hide yes)
			(effects
				(font
					(size 1 1)
					(thickness 0.15)
				)
				(justify mirror)
			)
		)
		(property "Dielectric" "X5R"
			(at 416.24 287.16 0)
			(layer "B.Fab")
			(hide yes)
			(effects
				(font
					(size 1 1)
					(thickness 0.15)
				)
				(justify mirror)
			)
		)
		(property "License" "Apache-2.0"
			(at 416.24 287.16 0)
			(layer "B.Fab")
			(hide yes)
			(effects
				(font
					(size 1 1)
					(thickness 0.15)
				)
				(justify mirror)
			)
		)
		(property "MPN" "GRM155R61A106ME11D"
			(at 416.24 287.16 0)
			(layer "B.Fab")
			(hide yes)
			(effects
				(font
					(size 1 1)
					(thickness 0.15)
				)
				(justify mirror)
			)
		)
		(property "Manufacturer" "Murata"
			(at 416.24 287.16 0)
			(layer "B.Fab")
			(hide yes)
			(effects
				(font
					(size 1 1)
					(thickness 0.15)
				)
				(justify mirror)
			)
		)
		(property "Public" ""
			(at 416.24 287.16 0)
			(layer "B.Fab")
			(hide yes)
			(effects
				(font
					(size 1 1)
					(thickness 0.15)
				)
				(justify mirror)
			)
		)
		(property "Val" "10u"
			(at 416.24 287.16 0)
			(layer "B.Fab")
			(hide yes)
			(effects
				(font
					(size 1 1)
					(thickness 0.15)
				)
				(justify mirror)
			)
		)
		(property "Voltage" "10V"
			(at 416.24 287.16 0)
			(layer "B.Fab")
			(hide yes)
			(effects
				(font
					(size 1 1)
					(thickness 0.15)
				)
				(justify mirror)
			)
		)
		(sheetname "/MIPI CrossLink/")
		(sheetfile "crosslink.kicad_sch")
		(attr smd)
		(fp_rect
			(start -0.925 0.47)
			(end 0.925 -0.47)
			(stroke
				(width 0.05)
				(type default)
			)
			(fill no)
			(layer "B.CrtYd")
		)
		(fp_line
			(start 0.504 0.25)
			(end 0.504 -0.248)
			(stroke
				(width 0.15)
				(type solid)
			)
			(layer "B.Fab")
		)
		(fp_line
			(start 0.504 -0.248)
			(end -0.494 -0.248)
			(stroke
				(width 0.15)
				(type solid)
			)
			(layer "B.Fab")
		)
		(fp_line
			(start -0.494 0.25)
			(end 0.504 0.25)
			(stroke
				(width 0.15)
				(type solid)
			)
			(layer "B.Fab")
		)
		(fp_line
			(start -0.494 -0.248)
			(end -0.494 0.25)
			(stroke
				(width 0.15)
				(type solid)
			)
			(layer "B.Fab")
		)
		(fp_text user "${REFERENCE}"
			(at -0.939 -4.599 0)
			(layer "B.Fab")
			(effects
				(font
					(size 0.7 0.7)
					(thickness 0.15)
				)
				(justify left bottom mirror)
			)
		)
		(fp_text user "Author: Antmicro"
			(at -0.939 -3.399 0)
			(layer "B.Fab")
			(effects
				(font
					(size 0.7 0.7)
					(thickness 0.15)
				)
				(justify left bottom mirror)
			)
		)
		(fp_text user "License: Apache-2.0"
			(at -0.939 -5.799 0)
			(layer "B.Fab")
			(effects
				(font
					(size 0.7 0.7)
					(thickness 0.15)
				)
				(justify left bottom mirror)
			)
		)
		(pad "1" smd roundrect
			(at -0.48 0 180)
			(size 0.59 0.64)
			(layers "B.Cu" "B.Mask" "B.Paste")
			(roundrect_rratio 0.25)
			(net 417 "GND")
			(pintype "passive")
		)
		(pad "2" smd roundrect
			(at 0.48 0 180)
			(size 0.59 0.64)
			(layers "B.Cu" "B.Mask" "B.Paste")
			(roundrect_rratio 0.25)
			(net 191 "/MIPI CrossLink/CL_VCCIO2")
			(pintype "passive")
		)
	)
	(footprint "antmicro-footprints:C_0402_1005Metric"
		(layer "B.Cu")
		(at 203.21 125.7)
		(descr "Capacitor SMD 0402")
		(tags "capacitor SMD 0402")
		(property "Reference" "C23"
			(at 0.91 0.895 0)
			(layer "B.SilkS")
			(effects
				(font
					(size 0.7 0.7)
					(thickness 0.15)
				)
				(justify right bottom mirror)
			)
		)
		(property "Value" "C_10u_0402"
			(at -1.022927 -2.155213 0)
			(layer "B.Fab")
			(hide yes)
			(effects
				(font
					(size 0.7 0.7)
					(thickness 0.15)
				)
				(justify right bottom mirror)
			)
		)
		(property "Datasheet" "https://www.yageo.com/en/Chart/Download/pdf/CC0402MRX5R5BB106"
			(at 0 0 0)
			(layer "F.Fab")
			(hide yes)
			(effects
				(font
					(size 1.27 1.27)
					(thickness 0.15)
				)
			)
		)
		(property "Description" "SMD Multilayer Ceramic Capacitor, 10 µF, 6.3 V, 0402 [1005 Metric], ± 20%, X5R, CC Series"
			(at 0 0 0)
			(layer "F.Fab")
			(hide yes)
			(effects
				(font
					(size 1.27 1.27)
					(thickness 0.15)
				)
			)
		)
		(property "Author" "Antmicro"
			(at 0 0 0)
			(layer "B.Fab")
			(hide yes)
			(effects
				(font
					(size 1 1)
					(thickness 0.15)
				)
				(justify mirror)
			)
		)
		(property "Dielectric" ""
			(at 0 0 0)
			(layer "B.Fab")
			(hide yes)
			(effects
				(font
					(size 1 1)
					(thickness 0.15)
				)
				(justify mirror)
			)
		)
		(property "License" "Apache-2.0"
			(at 0 0 0)
			(layer "B.Fab")
			(hide yes)
			(effects
				(font
					(size 1 1)
					(thickness 0.15)
				)
				(justify mirror)
			)
		)
		(property "MPN" "CC0402MRX5R5BB106"
			(at 0 0 0)
			(layer "B.Fab")
			(hide yes)
			(effects
				(font
					(size 1 1)
					(thickness 0.15)
				)
				(justify mirror)
			)
		)
		(property "Manufacturer" "YAGEO"
			(at 0 0 0)
			(layer "B.Fab")
			(hide yes)
			(effects
				(font
					(size 1 1)
					(thickness 0.15)
				)
				(justify mirror)
			)
		)
		(property "Public" ""
			(at 0 0 0)
			(layer "B.Fab")
			(hide yes)
			(effects
				(font
					(size 1 1)
					(thickness 0.15)
				)
				(justify mirror)
			)
		)
		(property "Val" "10u"
			(at 0 0 0)
			(layer "B.Fab")
			(hide yes)
			(effects
				(font
					(size 1 1)
					(thickness 0.15)
				)
				(justify mirror)
			)
		)
		(property "Voltage" ""
			(at 0 0 0)
			(layer "B.Fab")
			(hide yes)
			(effects
				(font
					(size 1 1)
					(thickness 0.15)
				)
				(justify mirror)
			)
		)
		(sheetname "/FPGA Supply/")
		(sheetfile "fpga-supply.kicad_sch")
		(attr smd)
		(fp_rect
			(start -0.925 0.47)
			(end 0.925 -0.47)
			(stroke
				(width 0.05)
				(type default)
			)
			(fill no)
			(layer "B.CrtYd")
		)
		(fp_line
			(start -0.494 -0.248)
			(end -0.494 0.25)
			(stroke
				(width 0.15)
				(type solid)
			)
			(layer "B.Fab")
		)
		(fp_line
			(start -0.494 0.25)
			(end 0.504 0.25)
			(stroke
				(width 0.15)
				(type solid)
			)
			(layer "B.Fab")
		)
		(fp_line
			(start 0.504 -0.248)
			(end -0.494 -0.248)
			(stroke
				(width 0.15)
				(type solid)
			)
			(layer "B.Fab")
		)
		(fp_line
			(start 0.504 0.25)
			(end 0.504 -0.248)
			(stroke
				(width 0.15)
				(type solid)
			)
			(layer "B.Fab")
		)
		(fp_text user "License: Apache-2.0"
			(at -0.939 -5.799 180)
			(layer "B.Fab")
			(effects
				(font
					(size 0.7 0.7)
					(thickness 0.15)
				)
				(justify left bottom mirror)
			)
		)
		(fp_text user "Author: Antmicro"
			(at -0.939 -3.399 180)
			(layer "B.Fab")
			(effects
				(font
					(size 0.7 0.7)
					(thickness 0.15)
				)
				(justify left bottom mirror)
			)
		)
		(fp_text user "${REFERENCE}"
			(at -0.939 -4.599 180)
			(layer "B.Fab")
			(effects
				(font
					(size 0.7 0.7)
					(thickness 0.15)
				)
				(justify left bottom mirror)
			)
		)
		(pad "1" smd roundrect
			(at -0.48 0)
			(size 0.59 0.64)
			(layers "B.Cu" "B.Mask" "B.Paste")
			(roundrect_rratio 0.25)
			(net 417 "GND")
			(pintype "passive")
		)
		(pad "2" smd roundrect
			(at 0.48 0)
			(size 0.59 0.64)
			(layers "B.Cu" "B.Mask" "B.Paste")
			(roundrect_rratio 0.25)
			(net 649 "VDD")
			(pintype "passive")
		)
	)
	(footprint "antmicro-footprints:R_0402_1005Metric"
		(layer "B.Cu")
		(at 220.7175 144.895 90)
		(descr "Resistor SMD 0402")
		(tags "resistor SMD 0402")
		(property "Reference" "R147"
			(at 9.93 7.3275 270)
			(layer "B.SilkS")
			(effects
				(font
					(size 0.7 0.7)
					(thickness 0.15)
				)
				(justify left bottom mirror)
			)
		)
		(property "Value" "R_10k_0402"
			(at -1.011843 -1.772047 270)
			(layer "B.Fab")
			(hide yes)
			(effects
				(font
					(size 0.7 0.7)
					(thickness 0.15)
				)
				(justify left bottom mirror)
			)
		)
		(property "Datasheet" "https://www.bourns.com/docs/product-datasheets/cr.pdf"
			(at 0 0 90)
			(layer "F.Fab")
			(hide yes)
			(effects
				(font
					(size 1.27 1.27)
					(thickness 0.15)
				)
			)
		)
		(property "Description" "SMD Chip Resistor, 10 kohm, ± 1%, 62.5 mW, 0402 [1005 Metric], Thick Film, General Purpose"
			(at 0 0 90)
			(layer "F.Fab")
			(hide yes)
			(effects
				(font
					(size 1.27 1.27)
					(thickness 0.15)
				)
			)
		)
		(property "Author" "Antmicro"
			(at 365.6125 -75.8225 0)
			(layer "B.Fab")
			(hide yes)
			(effects
				(font
					(size 1 1)
					(thickness 0.15)
				)
				(justify mirror)
			)
		)
		(property "License" "Apache-2.0"
			(at 365.6125 -75.8225 0)
			(layer "B.Fab")
			(hide yes)
			(effects
				(font
					(size 1 1)
					(thickness 0.15)
				)
				(justify mirror)
			)
		)
		(property "MPN" "CR0402-FX-1002GLF"
			(at 365.6125 -75.8225 0)
			(layer "B.Fab")
			(hide yes)
			(effects
				(font
					(size 1 1)
					(thickness 0.15)
				)
				(justify mirror)
			)
		)
		(property "Manufacturer" "Bourns"
			(at 365.6125 -75.8225 0)
			(layer "B.Fab")
			(hide yes)
			(effects
				(font
					(size 1 1)
					(thickness 0.15)
				)
				(justify mirror)
			)
		)
		(property "Public" ""
			(at 365.6125 -75.8225 0)
			(layer "B.Fab")
			(hide yes)
			(effects
				(font
					(size 1 1)
					(thickness 0.15)
				)
				(justify mirror)
			)
		)
		(property "Tolerance" "1%"
			(at 365.6125 -75.8225 0)
			(layer "B.Fab")
			(hide yes)
			(effects
				(font
					(size 1 1)
					(thickness 0.15)
				)
				(justify mirror)
			)
		)
		(property "Val" "10k"
			(at 365.6125 -75.8225 0)
			(layer "B.Fab")
			(hide yes)
			(effects
				(font
					(size 1 1)
					(thickness 0.15)
				)
				(justify mirror)
			)
		)
		(sheetname "/WiFi_Bluetooth/")
		(sheetfile "wifi_bt.kicad_sch")
		(attr smd)
		(fp_rect
			(start -0.925 0.47)
			(end 0.925 -0.47)
			(stroke
				(width 0.05)
				(type default)
			)
			(fill no)
			(layer "B.CrtYd")
		)
		(fp_rect
			(start -0.5 0.25)
			(end 0.5 -0.25)
			(stroke
				(width 0.15)
				(type solid)
			)
			(fill no)
			(layer "B.Fab")
		)
		(fp_text user "License: Apache-2.0"
			(at -0.95 -5.169 270)
			(layer "B.Fab")
			(effects
				(font
					(size 0.7 0.7)
					(thickness 0.15)
				)
				(justify left bottom mirror)
			)
		)
		(fp_text user "${REFERENCE}"
			(at -0.95 -3.168 270)
			(layer "B.Fab")
			(effects
				(font
					(size 0.7 0.7)
					(thickness 0.15)
				)
				(justify left bottom mirror)
			)
		)
		(fp_text user "Author: Antmicro"
			(at -0.95 -4.169 270)
			(layer "B.Fab")
			(effects
				(font
					(size 0.7 0.7)
					(thickness 0.15)
				)
				(justify left bottom mirror)
			)
		)
		(pad "1" smd roundrect
			(at -0.48 0 90)
			(size 0.59 0.64)
			(layers "B.Cu" "B.Mask" "B.Paste")
			(roundrect_rratio 0.25)
			(net 172 "BT_REG_ON")
			(pintype "passive")
		)
		(pad "2" smd roundrect
			(at 0.48 0 90)
			(size 0.59 0.64)
			(layers "B.Cu" "B.Mask" "B.Paste")
			(roundrect_rratio 0.25)
			(net 50 "+3V3")
			(pintype "passive")
		)
	)
	(footprint "antmicro-footprints:C_0402_1005Metric"
		(layer "B.Cu")
		(at 196.08 138.614 90)
		(descr "Capacitor SMD 0402")
		(tags "capacitor SMD 0402")
		(property "Reference" "C16"
			(at 4.939 -9.705 90)
			(layer "B.SilkS")
			(effects
				(font
					(size 0.7 0.7)
					(thickness 0.15)
				)
				(justify right bottom mirror)
			)
		)
		(property "Value" "C_100n_0402"
			(at -1.022927 -2.155213 90)
			(layer "B.Fab")
			(hide yes)
			(effects
				(font
					(size 0.7 0.7)
					(thickness 0.15)
				)
				(justify right bottom mirror)
			)
		)
		(property "Datasheet" "https://www.murata.com/products/productdetail?partno=GRM155R61H104KE14%23"
			(at 0 0 90)
			(layer "F.Fab")
			(hide yes)
			(effects
				(font
					(size 1.27 1.27)
					(thickness 0.15)
				)
			)
		)
		(property "Description" "SMD Multilayer Ceramic Capacitor, 0.1 µF, 50 V, 0402 [1005 Metric], ± 10%, X5R, GRM Series"
			(at 0 0 90)
			(layer "F.Fab")
			(hide yes)
			(effects
				(font
					(size 1.27 1.27)
					(thickness 0.15)
				)
			)
		)
		(property "Author" "Antmicro"
			(at 334.694 -57.466 0)
			(layer "B.Fab")
			(hide yes)
			(effects
				(font
					(size 1 1)
					(thickness 0.15)
				)
				(justify mirror)
			)
		)
		(property "Dielectric" "X5R"
			(at 334.694 -57.466 0)
			(layer "B.Fab")
			(hide yes)
			(effects
				(font
					(size 1 1)
					(thickness 0.15)
				)
				(justify mirror)
			)
		)
		(property "License" "Apache-2.0"
			(at 334.694 -57.466 0)
			(layer "B.Fab")
			(hide yes)
			(effects
				(font
					(size 1 1)
					(thickness 0.15)
				)
				(justify mirror)
			)
		)
		(property "MPN" "GRM155R61H104KE14D"
			(at 334.694 -57.466 0)
			(layer "B.Fab")
			(hide yes)
			(effects
				(font
					(size 1 1)
					(thickness 0.15)
				)
				(justify mirror)
			)
		)
		(property "Manufacturer" "Murata"
			(at 334.694 -57.466 0)
			(layer "B.Fab")
			(hide yes)
			(effects
				(font
					(size 1 1)
					(thickness 0.15)
				)
				(justify mirror)
			)
		)
		(property "Public" ""
			(at 334.694 -57.466 0)
			(layer "B.Fab")
			(hide yes)
			(effects
				(font
					(size 1 1)
					(thickness 0.15)
				)
				(justify mirror)
			)
		)
		(property "Val" "100n"
			(at 334.694 -57.466 0)
			(layer "B.Fab")
			(hide yes)
			(effects
				(font
					(size 1 1)
					(thickness 0.15)
				)
				(justify mirror)
			)
		)
		(property "Voltage" "50V"
			(at 334.694 -57.466 0)
			(layer "B.Fab")
			(hide yes)
			(effects
				(font
					(size 1 1)
					(thickness 0.15)
				)
				(justify mirror)
			)
		)
		(sheetname "/FPGA Supply/")
		(sheetfile "fpga-supply.kicad_sch")
		(attr smd)
		(fp_rect
			(start -0.925 0.47)
			(end 0.925 -0.47)
			(stroke
				(width 0.05)
				(type default)
			)
			(fill no)
			(layer "B.CrtYd")
		)
		(fp_line
			(start 0.504 -0.248)
			(end -0.494 -0.248)
			(stroke
				(width 0.15)
				(type solid)
			)
			(layer "B.Fab")
		)
		(fp_line
			(start -0.494 -0.248)
			(end -0.494 0.25)
			(stroke
				(width 0.15)
				(type solid)
			)
			(layer "B.Fab")
		)
		(fp_line
			(start 0.504 0.25)
			(end 0.504 -0.248)
			(stroke
				(width 0.15)
				(type solid)
			)
			(layer "B.Fab")
		)
		(fp_line
			(start -0.494 0.25)
			(end 0.504 0.25)
			(stroke
				(width 0.15)
				(type solid)
			)
			(layer "B.Fab")
		)
		(fp_text user "License: Apache-2.0"
			(at -0.939 -5.799 270)
			(layer "B.Fab")
			(effects
				(font
					(size 0.7 0.7)
					(thickness 0.15)
				)
				(justify left bottom mirror)
			)
		)
		(fp_text user "${REFERENCE}"
			(at -0.939 -4.599 270)
			(layer "B.Fab")
			(effects
				(font
					(size 0.7 0.7)
					(thickness 0.15)
				)
				(justify left bottom mirror)
			)
		)
		(fp_text user "Author: Antmicro"
			(at -0.939 -3.399 270)
			(layer "B.Fab")
			(effects
				(font
					(size 0.7 0.7)
					(thickness 0.15)
				)
				(justify left bottom mirror)
			)
		)
		(pad "1" smd roundrect
			(at -0.48 0 90)
			(size 0.59 0.64)
			(layers "B.Cu" "B.Mask" "B.Paste")
			(roundrect_rratio 0.25)
			(net 417 "GND")
			(pintype "passive")
		)
		(pad "2" smd roundrect
			(at 0.48 0 90)
			(size 0.59 0.64)
			(layers "B.Cu" "B.Mask" "B.Paste")
			(roundrect_rratio 0.25)
			(net 418 "+2V5")
			(pintype "passive")
		)
	)
	(footprint "antmicro-footprints:C_0402_1005Metric"
		(layer "B.Cu")
		(at 219.911 120.7394)
		(descr "Capacitor SMD 0402")
		(tags "capacitor SMD 0402")
		(property "Reference" "C224"
			(at 6.539 4.1106 0)
			(layer "B.SilkS")
			(effects
				(font
					(size 0.7 0.7)
					(thickness 0.15)
				)
				(justify right bottom mirror)
			)
		)
		(property "Value" "C_100n_0402"
			(at -1.022927 -2.155213 0)
			(layer "B.Fab")
			(hide yes)
			(effects
				(font
					(size 0.7 0.7)
					(thickness 0.15)
				)
				(justify right bottom mirror)
			)
		)
		(property "Datasheet" "https://www.murata.com/products/productdetail?partno=GRM155R61H104KE14%23"
			(at 0 0 0)
			(layer "F.Fab")
			(hide yes)
			(effects
				(font
					(size 1.27 1.27)
					(thickness 0.15)
				)
			)
		)
		(property "Description" "SMD Multilayer Ceramic Capacitor, 0.1 µF, 50 V, 0402 [1005 Metric], ± 10%, X5R, GRM Series"
			(at 0 0 0)
			(layer "F.Fab")
			(hide yes)
			(effects
				(font
					(size 1.27 1.27)
					(thickness 0.15)
				)
			)
		)
		(property "Author" "Antmicro"
			(at 0 0 0)
			(layer "B.Fab")
			(hide yes)
			(effects
				(font
					(size 1 1)
					(thickness 0.15)
				)
				(justify mirror)
			)
		)
		(property "Dielectric" "X5R"
			(at 0 0 0)
			(layer "B.Fab")
			(hide yes)
			(effects
				(font
					(size 1 1)
					(thickness 0.15)
				)
				(justify mirror)
			)
		)
		(property "License" "Apache-2.0"
			(at 0 0 0)
			(layer "B.Fab")
			(hide yes)
			(effects
				(font
					(size 1 1)
					(thickness 0.15)
				)
				(justify mirror)
			)
		)
		(property "MPN" "GRM155R61H104KE14D"
			(at 0 0 0)
			(layer "B.Fab")
			(hide yes)
			(effects
				(font
					(size 1 1)
					(thickness 0.15)
				)
				(justify mirror)
			)
		)
		(property "Manufacturer" "Murata"
			(at 0 0 0)
			(layer "B.Fab")
			(hide yes)
			(effects
				(font
					(size 1 1)
					(thickness 0.15)
				)
				(justify mirror)
			)
		)
		(property "Public" ""
			(at 0 0 0)
			(layer "B.Fab")
			(hide yes)
			(effects
				(font
					(size 1 1)
					(thickness 0.15)
				)
				(justify mirror)
			)
		)
		(property "Val" "100n"
			(at 0 0 0)
			(layer "B.Fab")
			(hide yes)
			(effects
				(font
					(size 1 1)
					(thickness 0.15)
				)
				(justify mirror)
			)
		)
		(property "Voltage" "50V"
			(at 0 0 0)
			(layer "B.Fab")
			(hide yes)
			(effects
				(font
					(size 1 1)
					(thickness 0.15)
				)
				(justify mirror)
			)
		)
		(sheetname "/Ethernet/")
		(sheetfile "ethernet.kicad_sch")
		(attr smd)
		(fp_rect
			(start -0.925 0.47)
			(end 0.925 -0.47)
			(stroke
				(width 0.05)
				(type default)
			)
			(fill no)
			(layer "B.CrtYd")
		)
		(fp_line
			(start -0.494 -0.248)
			(end -0.494 0.25)
			(stroke
				(width 0.15)
				(type solid)
			)
			(layer "B.Fab")
		)
		(fp_line
			(start -0.494 0.25)
			(end 0.504 0.25)
			(stroke
				(width 0.15)
				(type solid)
			)
			(layer "B.Fab")
		)
		(fp_line
			(start 0.504 -0.248)
			(end -0.494 -0.248)
			(stroke
				(width 0.15)
				(type solid)
			)
			(layer "B.Fab")
		)
		(fp_line
			(start 0.504 0.25)
			(end 0.504 -0.248)
			(stroke
				(width 0.15)
				(type solid)
			)
			(layer "B.Fab")
		)
		(fp_text user "Author: Antmicro"
			(at -0.939 -3.399 180)
			(layer "B.Fab")
			(effects
				(font
					(size 0.7 0.7)
					(thickness 0.15)
				)
				(justify left bottom mirror)
			)
		)
		(fp_text user "License: Apache-2.0"
			(at -0.939 -5.799 180)
			(layer "B.Fab")
			(effects
				(font
					(size 0.7 0.7)
					(thickness 0.15)
				)
				(justify left bottom mirror)
			)
		)
		(fp_text user "${REFERENCE}"
			(at -0.939 -4.599 180)
			(layer "B.Fab")
			(effects
				(font
					(size 0.7 0.7)
					(thickness 0.15)
				)
				(justify left bottom mirror)
			)
		)
		(pad "1" smd roundrect
			(at -0.48 0)
			(size 0.59 0.64)
			(layers "B.Cu" "B.Mask" "B.Paste")
			(roundrect_rratio 0.25)
			(net 417 "GND")
			(pintype "passive")
		)
		(pad "2" smd roundrect
			(at 0.48 0)
			(size 0.59 0.64)
			(layers "B.Cu" "B.Mask" "B.Paste")
			(roundrect_rratio 0.25)
			(net 47 "+1V05")
			(pintype "passive")
		)
	)
	(footprint "antmicro-footprints:C_0402_1005Metric"
		(layer "B.Cu")
		(at 185 140.9675 90)
		(descr "Capacitor SMD 0402")
		(tags "capacitor SMD 0402")
		(property "Reference" "C107"
			(at -1.7825 0.4 0)
			(layer "B.SilkS")
			(effects
				(font
					(size 0.7 0.7)
					(thickness 0.15)
				)
				(justify right bottom mirror)
			)
		)
		(property "Value" "C_22u_0402"
			(at -1.022927 -2.155213 90)
			(layer "B.Fab")
			(hide yes)
			(effects
				(font
					(size 0.7 0.7)
					(thickness 0.15)
				)
				(justify right bottom mirror)
			)
		)
		(property "Datasheet" "https://www.murata.com/products/productdetail?partno=GRM158R60J226ME01%23"
			(at 0 0 90)
			(layer "F.Fab")
			(hide yes)
			(effects
				(font
					(size 1.27 1.27)
					(thickness 0.15)
				)
			)
		)
		(property "Description" "SMD Multilayer Ceramic Capacitor, 22 uF, 4 V, 0402 [1005 Metric], X6S"
			(at 0 0 90)
			(layer "F.Fab")
			(hide yes)
			(effects
				(font
					(size 1.27 1.27)
					(thickness 0.15)
				)
			)
		)
		(property "Author" "Antmicro"
			(at 325.9675 -44.0325 0)
			(layer "B.Fab")
			(hide yes)
			(effects
				(font
					(size 1 1)
					(thickness 0.15)
				)
				(justify mirror)
			)
		)
		(property "Dielectric" ""
			(at 325.9675 -44.0325 0)
			(layer "B.Fab")
			(hide yes)
			(effects
				(font
					(size 1 1)
					(thickness 0.15)
				)
				(justify mirror)
			)
		)
		(property "License" "Apache-2.0"
			(at 325.9675 -44.0325 0)
			(layer "B.Fab")
			(hide yes)
			(effects
				(font
					(size 1 1)
					(thickness 0.15)
				)
				(justify mirror)
			)
		)
		(property "MPN" "GRM158R60J226ME01D"
			(at 325.9675 -44.0325 0)
			(layer "B.Fab")
			(hide yes)
			(effects
				(font
					(size 1 1)
					(thickness 0.15)
				)
				(justify mirror)
			)
		)
		(property "Manufacturer" "Murata"
			(at 325.9675 -44.0325 0)
			(layer "B.Fab")
			(hide yes)
			(effects
				(font
					(size 1 1)
					(thickness 0.15)
				)
				(justify mirror)
			)
		)
		(property "Public" ""
			(at 325.9675 -44.0325 0)
			(layer "B.Fab")
			(hide yes)
			(effects
				(font
					(size 1 1)
					(thickness 0.15)
				)
				(justify mirror)
			)
		)
		(property "Val" "22u"
			(at 325.9675 -44.0325 0)
			(layer "B.Fab")
			(hide yes)
			(effects
				(font
					(size 1 1)
					(thickness 0.15)
				)
				(justify mirror)
			)
		)
		(property "Voltage" ""
			(at 325.9675 -44.0325 0)
			(layer "B.Fab")
			(hide yes)
			(effects
				(font
					(size 1 1)
					(thickness 0.15)
				)
				(justify mirror)
			)
		)
		(sheetname "/Supply/")
		(sheetfile "supply.kicad_sch")
		(attr smd)
		(fp_rect
			(start -0.925 0.47)
			(end 0.925 -0.47)
			(stroke
				(width 0.05)
				(type default)
			)
			(fill no)
			(layer "B.CrtYd")
		)
		(fp_line
			(start 0.504 -0.248)
			(end -0.494 -0.248)
			(stroke
				(width 0.15)
				(type solid)
			)
			(layer "B.Fab")
		)
		(fp_line
			(start -0.494 -0.248)
			(end -0.494 0.25)
			(stroke
				(width 0.15)
				(type solid)
			)
			(layer "B.Fab")
		)
		(fp_line
			(start 0.504 0.25)
			(end 0.504 -0.248)
			(stroke
				(width 0.15)
				(type solid)
			)
			(layer "B.Fab")
		)
		(fp_line
			(start -0.494 0.25)
			(end 0.504 0.25)
			(stroke
				(width 0.15)
				(type solid)
			)
			(layer "B.Fab")
		)
		(fp_text user "${REFERENCE}"
			(at -0.939 -4.599 270)
			(layer "B.Fab")
			(effects
				(font
					(size 0.7 0.7)
					(thickness 0.15)
				)
				(justify left bottom mirror)
			)
		)
		(fp_text user "Author: Antmicro"
			(at -0.939 -3.399 270)
			(layer "B.Fab")
			(effects
				(font
					(size 0.7 0.7)
					(thickness 0.15)
				)
				(justify left bottom mirror)
			)
		)
		(fp_text user "License: Apache-2.0"
			(at -0.939 -5.799 270)
			(layer "B.Fab")
			(effects
				(font
					(size 0.7 0.7)
					(thickness 0.15)
				)
				(justify left bottom mirror)
			)
		)
		(pad "1" smd roundrect
			(at -0.48 0 90)
			(size 0.59 0.64)
			(layers "B.Cu" "B.Mask" "B.Paste")
			(roundrect_rratio 0.25)
			(net 417 "GND")
			(pintype "passive")
		)
		(pad "2" smd roundrect
			(at 0.48 0 90)
			(size 0.59 0.64)
			(layers "B.Cu" "B.Mask" "B.Paste")
			(roundrect_rratio 0.25)
			(net 272 "/Supply/SENSE3_P")
			(pintype "passive")
		)
	)
	(footprint "antmicro-footprints:R_0402_1005Metric"
		(layer "B.Cu")
		(at 185.325 154.43 90)
		(descr "Resistor SMD 0402")
		(tags "resistor SMD 0402")
		(property "Reference" "R61"
			(at 1.225 -4.975 270)
			(layer "B.SilkS")
			(effects
				(font
					(size 0.7 0.7)
					(thickness 0.15)
				)
				(justify left bottom mirror)
			)
		)
		(property "Value" "R_1M_0402"
			(at -1.011843 -1.772047 270)
			(layer "B.Fab")
			(hide yes)
			(effects
				(font
					(size 0.7 0.7)
					(thickness 0.15)
				)
				(justify left bottom mirror)
			)
		)
		(property "Datasheet" "https://www.bourns.com/docs/product-datasheets/cr.pdf"
			(at 0 0 90)
			(layer "F.Fab")
			(hide yes)
			(effects
				(font
					(size 1.27 1.27)
					(thickness 0.15)
				)
			)
		)
		(property "Description" "SMD Chip Resistor, 1 Mohm, ± 1%, 62.5 mW, 0402 [1005 Metric], Thick Film, General Purpose"
			(at 0 0 90)
			(layer "F.Fab")
			(hide yes)
			(effects
				(font
					(size 1.27 1.27)
					(thickness 0.15)
				)
			)
		)
		(property "Author" "Antmicro"
			(at 339.755 -30.895 0)
			(layer "B.Fab")
			(hide yes)
			(effects
				(font
					(size 1 1)
					(thickness 0.15)
				)
				(justify mirror)
			)
		)
		(property "License" "Apache-2.0"
			(at 339.755 -30.895 0)
			(layer "B.Fab")
			(hide yes)
			(effects
				(font
					(size 1 1)
					(thickness 0.15)
				)
				(justify mirror)
			)
		)
		(property "MPN" "CR0402-FX-1004GLF"
			(at 339.755 -30.895 0)
			(layer "B.Fab")
			(hide yes)
			(effects
				(font
					(size 1 1)
					(thickness 0.15)
				)
				(justify mirror)
			)
		)
		(property "Manufacturer" "Bourns"
			(at 339.755 -30.895 0)
			(layer "B.Fab")
			(hide yes)
			(effects
				(font
					(size 1 1)
					(thickness 0.15)
				)
				(justify mirror)
			)
		)
		(property "Public" ""
			(at 339.755 -30.895 0)
			(layer "B.Fab")
			(hide yes)
			(effects
				(font
					(size 1 1)
					(thickness 0.15)
				)
				(justify mirror)
			)
		)
		(property "Tolerance" "1%"
			(at 339.755 -30.895 0)
			(layer "B.Fab")
			(hide yes)
			(effects
				(font
					(size 1 1)
					(thickness 0.15)
				)
				(justify mirror)
			)
		)
		(property "Val" "1M"
			(at 339.755 -30.895 0)
			(layer "B.Fab")
			(hide yes)
			(effects
				(font
					(size 1 1)
					(thickness 0.15)
				)
				(justify mirror)
			)
		)
		(sheetname "/Bottom Connector/")
		(sheetfile "bottom-connector.kicad_sch")
		(attr smd)
		(fp_rect
			(start -0.925 0.47)
			(end 0.925 -0.47)
			(stroke
				(width 0.05)
				(type default)
			)
			(fill no)
			(layer "B.CrtYd")
		)
		(fp_rect
			(start -0.5 0.25)
			(end 0.5 -0.25)
			(stroke
				(width 0.15)
				(type solid)
			)
			(fill no)
			(layer "B.Fab")
		)
		(fp_text user "License: Apache-2.0"
			(at -0.95 -5.169 270)
			(layer "B.Fab")
			(effects
				(font
					(size 0.7 0.7)
					(thickness 0.15)
				)
				(justify left bottom mirror)
			)
		)
		(fp_text user "Author: Antmicro"
			(at -0.95 -4.169 270)
			(layer "B.Fab")
			(effects
				(font
					(size 0.7 0.7)
					(thickness 0.15)
				)
				(justify left bottom mirror)
			)
		)
		(fp_text user "${REFERENCE}"
			(at -0.95 -3.168 270)
			(layer "B.Fab")
			(effects
				(font
					(size 0.7 0.7)
					(thickness 0.15)
				)
				(justify left bottom mirror)
			)
		)
		(pad "1" smd roundrect
			(at -0.48 0 90)
			(size 0.59 0.64)
			(layers "B.Cu" "B.Mask" "B.Paste")
			(roundrect_rratio 0.25)
			(net 417 "GND")
			(pintype "passive")
		)
		(pad "2" smd roundrect
			(at 0.48 0 90)
			(size 0.59 0.64)
			(layers "B.Cu" "B.Mask" "B.Paste")
			(roundrect_rratio 0.25)
			(net 411 "Net-(Q3-BIAS)")
			(pintype "passive")
		)
	)
	(footprint "antmicro-footprints:R_0402_1005Metric"
		(layer "B.Cu")
		(at 210.1925 130.35)
		(descr "Resistor SMD 0402")
		(tags "resistor SMD 0402")
		(property "Reference" "R36"
			(at -0.8425 0.628 180)
			(layer "B.SilkS")
			(effects
				(font
					(size 0.7 0.7)
					(thickness 0.15)
				)
				(justify left bottom mirror)
			)
		)
		(property "Value" "R_49k9_0402"
			(at -1.011843 -1.772047 180)
			(layer "B.Fab")
			(hide yes)
			(effects
				(font
					(size 0.7 0.7)
					(thickness 0.15)
				)
				(justify left bottom mirror)
			)
		)
		(property "Datasheet" "https://www.bourns.com/docs/product-datasheets/cr.pdf"
			(at 0 0 0)
			(layer "F.Fab")
			(hide yes)
			(effects
				(font
					(size 1.27 1.27)
					(thickness 0.15)
				)
			)
		)
		(property "Description" "SMD Chip Resistor, 49.9 kohm, ± 1%, 63 mW, 0402 [1005 Metric], Thick Film, General Purpose"
			(at 0 0 0)
			(layer "F.Fab")
			(hide yes)
			(effects
				(font
					(size 1.27 1.27)
					(thickness 0.15)
				)
			)
		)
		(property "Author" "Antmicro"
			(at 0 0 0)
			(layer "B.Fab")
			(hide yes)
			(effects
				(font
					(size 1 1)
					(thickness 0.15)
				)
				(justify mirror)
			)
		)
		(property "License" "Apache-2.0"
			(at 0 0 0)
			(layer "B.Fab")
			(hide yes)
			(effects
				(font
					(size 1 1)
					(thickness 0.15)
				)
				(justify mirror)
			)
		)
		(property "MPN" "CR0402-FX-4992GLF"
			(at 0 0 0)
			(layer "B.Fab")
			(hide yes)
			(effects
				(font
					(size 1 1)
					(thickness 0.15)
				)
				(justify mirror)
			)
		)
		(property "Manufacturer" "Bourns"
			(at 0 0 0)
			(layer "B.Fab")
			(hide yes)
			(effects
				(font
					(size 1 1)
					(thickness 0.15)
				)
				(justify mirror)
			)
		)
		(property "Public" ""
			(at 0 0 0)
			(layer "B.Fab")
			(hide yes)
			(effects
				(font
					(size 1 1)
					(thickness 0.15)
				)
				(justify mirror)
			)
		)
		(property "Tolerance" "1%"
			(at 0 0 0)
			(layer "B.Fab")
			(hide yes)
			(effects
				(font
					(size 1 1)
					(thickness 0.15)
				)
				(justify mirror)
			)
		)
		(property "Val" "49k9"
			(at 0 0 0)
			(layer "B.Fab")
			(hide yes)
			(effects
				(font
					(size 1 1)
					(thickness 0.15)
				)
				(justify mirror)
			)
		)
		(sheetname "/Memory/")
		(sheetfile "memory.kicad_sch")
		(attr smd)
		(fp_rect
			(start -0.925 0.47)
			(end 0.925 -0.47)
			(stroke
				(width 0.05)
				(type default)
			)
			(fill no)
			(layer "B.CrtYd")
		)
		(fp_rect
			(start -0.5 0.25)
			(end 0.5 -0.25)
			(stroke
				(width 0.15)
				(type solid)
			)
			(fill no)
			(layer "B.Fab")
		)
		(fp_text user "License: Apache-2.0"
			(at -0.95 -5.169 180)
			(layer "B.Fab")
			(effects
				(font
					(size 0.7 0.7)
					(thickness 0.15)
				)
				(justify left bottom mirror)
			)
		)
		(fp_text user "Author: Antmicro"
			(at -0.95 -4.169 180)
			(layer "B.Fab")
			(effects
				(font
					(size 0.7 0.7)
					(thickness 0.15)
				)
				(justify left bottom mirror)
			)
		)
		(fp_text user "${REFERENCE}"
			(at -0.95 -3.168 180)
			(layer "B.Fab")
			(effects
				(font
					(size 0.7 0.7)
					(thickness 0.15)
				)
				(justify left bottom mirror)
			)
		)
		(pad "1" smd roundrect
			(at -0.48 0)
			(size 0.59 0.64)
			(layers "B.Cu" "B.Mask" "B.Paste")
			(roundrect_rratio 0.25)
			(net 248 "/FPGA MSSIO/EMMC.DAT2")
			(pintype "passive")
		)
		(pad "2" smd roundrect
			(at 0.48 0)
			(size 0.59 0.64)
			(layers "B.Cu" "B.Mask" "B.Paste")
			(roundrect_rratio 0.25)
			(net 137 "SD_VDD")
			(pintype "passive")
		)
	)
	(footprint "antmicro-footprints:C_0402_1005Metric"
		(layer "B.Cu")
		(at 216.615 144.05)
		(descr "Capacitor SMD 0402")
		(tags "capacitor SMD 0402")
		(property "Reference" "C179"
			(at -1.795 1.22 180)
			(layer "B.SilkS")
			(effects
				(font
					(size 0.7 0.7)
					(thickness 0.15)
				)
				(justify right bottom mirror)
			)
		)
		(property "Value" "C_1u_0402"
			(at -1.022927 -2.155213 0)
			(layer "B.Fab")
			(hide yes)
			(effects
				(font
					(size 0.7 0.7)
					(thickness 0.15)
				)
				(justify right bottom mirror)
			)
		)
		(property "Datasheet" "https://product.tdk.com/en/search/capacitor/ceramic/mlcc/info?part_no=C1005X6S1A105K050BC"
			(at 0 0 0)
			(layer "F.Fab")
			(hide yes)
			(effects
				(font
					(size 1.27 1.27)
					(thickness 0.15)
				)
			)
		)
		(property "Description" "SMD Multilayer Ceramic Capacitor, 1 µF, 10 V, 0402 [1005 Metric], ± 10%, X6S, C"
			(at 0 0 0)
			(layer "F.Fab")
			(hide yes)
			(effects
				(font
					(size 1.27 1.27)
					(thickness 0.15)
				)
			)
		)
		(property "Author" "Antmicro"
			(at 0 0 0)
			(layer "B.Fab")
			(hide yes)
			(effects
				(font
					(size 1 1)
					(thickness 0.15)
				)
				(justify mirror)
			)
		)
		(property "Dielectric" ""
			(at 0 0 0)
			(layer "B.Fab")
			(hide yes)
			(effects
				(font
					(size 1 1)
					(thickness 0.15)
				)
				(justify mirror)
			)
		)
		(property "License" "Apache-2.0"
			(at 0 0 0)
			(layer "B.Fab")
			(hide yes)
			(effects
				(font
					(size 1 1)
					(thickness 0.15)
				)
				(justify mirror)
			)
		)
		(property "MPN" "C1005X6S1A105K050BC"
			(at 0 0 0)
			(layer "B.Fab")
			(hide yes)
			(effects
				(font
					(size 1 1)
					(thickness 0.15)
				)
				(justify mirror)
			)
		)
		(property "Manufacturer" "TDK"
			(at 0 0 0)
			(layer "B.Fab")
			(hide yes)
			(effects
				(font
					(size 1 1)
					(thickness 0.15)
				)
				(justify mirror)
			)
		)
		(property "Public" ""
			(at 0 0 0)
			(layer "B.Fab")
			(hide yes)
			(effects
				(font
					(size 1 1)
					(thickness 0.15)
				)
				(justify mirror)
			)
		)
		(property "Val" "1u"
			(at 0 0 0)
			(layer "B.Fab")
			(hide yes)
			(effects
				(font
					(size 1 1)
					(thickness 0.15)
				)
				(justify mirror)
			)
		)
		(property "Voltage" ""
			(at 0 0 0)
			(layer "B.Fab")
			(hide yes)
			(effects
				(font
					(size 1 1)
					(thickness 0.15)
				)
				(justify mirror)
			)
		)
		(sheetname "/USB/")
		(sheetfile "usb.kicad_sch")
		(attr smd)
		(fp_rect
			(start -0.925 0.47)
			(end 0.925 -0.47)
			(stroke
				(width 0.05)
				(type default)
			)
			(fill no)
			(layer "B.CrtYd")
		)
		(fp_line
			(start -0.494 -0.248)
			(end -0.494 0.25)
			(stroke
				(width 0.15)
				(type solid)
			)
			(layer "B.Fab")
		)
		(fp_line
			(start -0.494 0.25)
			(end 0.504 0.25)
			(stroke
				(width 0.15)
				(type solid)
			)
			(layer "B.Fab")
		)
		(fp_line
			(start 0.504 -0.248)
			(end -0.494 -0.248)
			(stroke
				(width 0.15)
				(type solid)
			)
			(layer "B.Fab")
		)
		(fp_line
			(start 0.504 0.25)
			(end 0.504 -0.248)
			(stroke
				(width 0.15)
				(type solid)
			)
			(layer "B.Fab")
		)
		(fp_text user "Author: Antmicro"
			(at -0.939 -3.399 180)
			(layer "B.Fab")
			(effects
				(font
					(size 0.7 0.7)
					(thickness 0.15)
				)
				(justify left bottom mirror)
			)
		)
		(fp_text user "License: Apache-2.0"
			(at -0.939 -5.799 180)
			(layer "B.Fab")
			(effects
				(font
					(size 0.7 0.7)
					(thickness 0.15)
				)
				(justify left bottom mirror)
			)
		)
		(fp_text user "${REFERENCE}"
			(at -0.939 -4.599 180)
			(layer "B.Fab")
			(effects
				(font
					(size 0.7 0.7)
					(thickness 0.15)
				)
				(justify left bottom mirror)
			)
		)
		(pad "1" smd roundrect
			(at -0.48 0)
			(size 0.59 0.64)
			(layers "B.Cu" "B.Mask" "B.Paste")
			(roundrect_rratio 0.25)
			(net 417 "GND")
			(pintype "passive")
		)
		(pad "2" smd roundrect
			(at 0.48 0)
			(size 0.59 0.64)
			(layers "B.Cu" "B.Mask" "B.Paste")
			(roundrect_rratio 0.25)
			(net 153 "/USB/VDD33")
			(pintype "passive")
		)
	)
	(footprint "antmicro-footprints:C_0402_1005Metric"
		(layer "B.Cu")
		(at 212.415 141.15 -90)
		(descr "Capacitor SMD 0402")
		(tags "capacitor SMD 0402")
		(property "Reference" "C180"
			(at -3.6 -0.435 90)
			(layer "B.SilkS")
			(effects
				(font
					(size 0.7 0.7)
					(thickness 0.15)
				)
				(justify left bottom mirror)
			)
		)
		(property "Value" "C_1u_0402"
			(at -1.022927 -2.155213 90)
			(layer "B.Fab")
			(hide yes)
			(effects
				(font
					(size 0.7 0.7)
					(thickness 0.15)
				)
				(justify left bottom mirror)
			)
		)
		(property "Datasheet" "https://product.tdk.com/en/search/capacitor/ceramic/mlcc/info?part_no=C1005X6S1A105K050BC"
			(at 0 0 270)
			(layer "F.Fab")
			(hide yes)
			(effects
				(font
					(size 1.27 1.27)
					(thickness 0.15)
				)
			)
		)
		(property "Description" "SMD Multilayer Ceramic Capacitor, 1 µF, 10 V, 0402 [1005 Metric], ± 10%, X6S, C"
			(at 0 0 270)
			(layer "F.Fab")
			(hide yes)
			(effects
				(font
					(size 1.27 1.27)
					(thickness 0.15)
				)
			)
		)
		(property "Author" "Antmicro"
			(at 71.265 353.565 0)
			(layer "B.Fab")
			(hide yes)
			(effects
				(font
					(size 1 1)
					(thickness 0.15)
				)
				(justify mirror)
			)
		)
		(property "Dielectric" ""
			(at 71.265 353.565 0)
			(layer "B.Fab")
			(hide yes)
			(effects
				(font
					(size 1 1)
					(thickness 0.15)
				)
				(justify mirror)
			)
		)
		(property "License" "Apache-2.0"
			(at 71.265 353.565 0)
			(layer "B.Fab")
			(hide yes)
			(effects
				(font
					(size 1 1)
					(thickness 0.15)
				)
				(justify mirror)
			)
		)
		(property "MPN" "C1005X6S1A105K050BC"
			(at 71.265 353.565 0)
			(layer "B.Fab")
			(hide yes)
			(effects
				(font
					(size 1 1)
					(thickness 0.15)
				)
				(justify mirror)
			)
		)
		(property "Manufacturer" "TDK"
			(at 71.265 353.565 0)
			(layer "B.Fab")
			(hide yes)
			(effects
				(font
					(size 1 1)
					(thickness 0.15)
				)
				(justify mirror)
			)
		)
		(property "Public" ""
			(at 71.265 353.565 0)
			(layer "B.Fab")
			(hide yes)
			(effects
				(font
					(size 1 1)
					(thickness 0.15)
				)
				(justify mirror)
			)
		)
		(property "Val" "1u"
			(at 71.265 353.565 0)
			(layer "B.Fab")
			(hide yes)
			(effects
				(font
					(size 1 1)
					(thickness 0.15)
				)
				(justify mirror)
			)
		)
		(property "Voltage" ""
			(at 71.265 353.565 0)
			(layer "B.Fab")
			(hide yes)
			(effects
				(font
					(size 1 1)
					(thickness 0.15)
				)
				(justify mirror)
			)
		)
		(sheetname "/USB/")
		(sheetfile "usb.kicad_sch")
		(attr smd)
		(fp_rect
			(start -0.925 0.47)
			(end 0.925 -0.47)
			(stroke
				(width 0.05)
				(type default)
			)
			(fill no)
			(layer "B.CrtYd")
		)
		(fp_line
			(start -0.494 0.25)
			(end 0.504 0.25)
			(stroke
				(width 0.15)
				(type solid)
			)
			(layer "B.Fab")
		)
		(fp_line
			(start 0.504 0.25)
			(end 0.504 -0.248)
			(stroke
				(width 0.15)
				(type solid)
			)
			(layer "B.Fab")
		)
		(fp_line
			(start -0.494 -0.248)
			(end -0.494 0.25)
			(stroke
				(width 0.15)
				(type solid)
			)
			(layer "B.Fab")
		)
		(fp_line
			(start 0.504 -0.248)
			(end -0.494 -0.248)
			(stroke
				(width 0.15)
				(type solid)
			)
			(layer "B.Fab")
		)
		(fp_text user "License: Apache-2.0"
			(at -0.939 -5.799 90)
			(layer "B.Fab")
			(effects
				(font
					(size 0.7 0.7)
					(thickness 0.15)
				)
				(justify left bottom mirror)
			)
		)
		(fp_text user "${REFERENCE}"
			(at -0.939 -4.599 90)
			(layer "B.Fab")
			(effects
				(font
					(size 0.7 0.7)
					(thickness 0.15)
				)
				(justify left bottom mirror)
			)
		)
		(fp_text user "Author: Antmicro"
			(at -0.939 -3.399 90)
			(layer "B.Fab")
			(effects
				(font
					(size 0.7 0.7)
					(thickness 0.15)
				)
				(justify left bottom mirror)
			)
		)
		(pad "1" smd roundrect
			(at -0.48 0 270)
			(size 0.59 0.64)
			(layers "B.Cu" "B.Mask" "B.Paste")
			(roundrect_rratio 0.25)
			(net 417 "GND")
			(pintype "passive")
		)
		(pad "2" smd roundrect
			(at 0.48 0 270)
			(size 0.59 0.64)
			(layers "B.Cu" "B.Mask" "B.Paste")
			(roundrect_rratio 0.25)
			(net 48 "+1V8")
			(pintype "passive")
		)
	)
	(footprint "antmicro-footprints:C_0402_1005Metric"
		(layer "B.Cu")
		(at 179.1 140.9675)
		(descr "Capacitor SMD 0402")
		(tags "capacitor SMD 0402")
		(property "Reference" "C85"
			(at 9.05 9.8575 180)
			(layer "B.SilkS")
			(effects
				(font
					(size 0.7 0.7)
					(thickness 0.15)
				)
				(justify right bottom mirror)
			)
		)
		(property "Value" "C_22u_0402"
			(at -1.022927 -2.155213 0)
			(layer "B.Fab")
			(hide yes)
			(effects
				(font
					(size 0.7 0.7)
					(thickness 0.15)
				)
				(justify right bottom mirror)
			)
		)
		(property "Datasheet" "https://www.murata.com/products/productdetail?partno=GRM158R60J226ME01%23"
			(at 0 0 0)
			(layer "F.Fab")
			(hide yes)
			(effects
				(font
					(size 1.27 1.27)
					(thickness 0.15)
				)
			)
		)
		(property "Description" "SMD Multilayer Ceramic Capacitor, 22 uF, 4 V, 0402 [1005 Metric], X6S"
			(at 0 0 0)
			(layer "F.Fab")
			(hide yes)
			(effects
				(font
					(size 1.27 1.27)
					(thickness 0.15)
				)
			)
		)
		(property "Author" "Antmicro"
			(at 0 0 0)
			(layer "B.Fab")
			(hide yes)
			(effects
				(font
					(size 1 1)
					(thickness 0.15)
				)
				(justify mirror)
			)
		)
		(property "Dielectric" ""
			(at 0 0 0)
			(layer "B.Fab")
			(hide yes)
			(effects
				(font
					(size 1 1)
					(thickness 0.15)
				)
				(justify mirror)
			)
		)
		(property "License" "Apache-2.0"
			(at 0 0 0)
			(layer "B.Fab")
			(hide yes)
			(effects
				(font
					(size 1 1)
					(thickness 0.15)
				)
				(justify mirror)
			)
		)
		(property "MPN" "GRM158R60J226ME01D"
			(at 0 0 0)
			(layer "B.Fab")
			(hide yes)
			(effects
				(font
					(size 1 1)
					(thickness 0.15)
				)
				(justify mirror)
			)
		)
		(property "Manufacturer" "Murata"
			(at 0 0 0)
			(layer "B.Fab")
			(hide yes)
			(effects
				(font
					(size 1 1)
					(thickness 0.15)
				)
				(justify mirror)
			)
		)
		(property "Public" ""
			(at 0 0 0)
			(layer "B.Fab")
			(hide yes)
			(effects
				(font
					(size 1 1)
					(thickness 0.15)
				)
				(justify mirror)
			)
		)
		(property "Val" "22u"
			(at 0 0 0)
			(layer "B.Fab")
			(hide yes)
			(effects
				(font
					(size 1 1)
					(thickness 0.15)
				)
				(justify mirror)
			)
		)
		(property "Voltage" ""
			(at 0 0 0)
			(layer "B.Fab")
			(hide yes)
			(effects
				(font
					(size 1 1)
					(thickness 0.15)
				)
				(justify mirror)
			)
		)
		(sheetname "/Supply/")
		(sheetfile "supply.kicad_sch")
		(attr smd)
		(fp_rect
			(start -0.925 0.47)
			(end 0.925 -0.47)
			(stroke
				(width 0.05)
				(type default)
			)
			(fill no)
			(layer "B.CrtYd")
		)
		(fp_line
			(start -0.494 -0.248)
			(end -0.494 0.25)
			(stroke
				(width 0.15)
				(type solid)
			)
			(layer "B.Fab")
		)
		(fp_line
			(start -0.494 0.25)
			(end 0.504 0.25)
			(stroke
				(width 0.15)
				(type solid)
			)
			(layer "B.Fab")
		)
		(fp_line
			(start 0.504 -0.248)
			(end -0.494 -0.248)
			(stroke
				(width 0.15)
				(type solid)
			)
			(layer "B.Fab")
		)
		(fp_line
			(start 0.504 0.25)
			(end 0.504 -0.248)
			(stroke
				(width 0.15)
				(type solid)
			)
			(layer "B.Fab")
		)
		(fp_text user "Author: Antmicro"
			(at -0.939 -3.399 180)
			(layer "B.Fab")
			(effects
				(font
					(size 0.7 0.7)
					(thickness 0.15)
				)
				(justify left bottom mirror)
			)
		)
		(fp_text user "${REFERENCE}"
			(at -0.939 -4.599 180)
			(layer "B.Fab")
			(effects
				(font
					(size 0.7 0.7)
					(thickness 0.15)
				)
				(justify left bottom mirror)
			)
		)
		(fp_text user "License: Apache-2.0"
			(at -0.939 -5.799 180)
			(layer "B.Fab")
			(effects
				(font
					(size 0.7 0.7)
					(thickness 0.15)
				)
				(justify left bottom mirror)
			)
		)
		(pad "1" smd roundrect
			(at -0.48 0)
			(size 0.59 0.64)
			(layers "B.Cu" "B.Mask" "B.Paste")
			(roundrect_rratio 0.25)
			(net 417 "GND")
			(pintype "passive")
		)
		(pad "2" smd roundrect
			(at 0.48 0)
			(size 0.59 0.64)
			(layers "B.Cu" "B.Mask" "B.Paste")
			(roundrect_rratio 0.25)
			(net 90 "+5V")
			(pintype "passive")
		)
	)
	(footprint "antmicro-footprints:C_0402_1005Metric"
		(layer "B.Cu")
		(at 214.982486 143.297401 90)
		(descr "Capacitor SMD 0402")
		(tags "capacitor SMD 0402")
		(property "Reference" "C184"
			(at 2.857401 0.117514 90)
			(layer "B.SilkS")
			(effects
				(font
					(size 0.7 0.7)
					(thickness 0.15)
				)
				(justify right bottom mirror)
			)
		)
		(property "Value" "C_100n_0402"
			(at -1.022927 -2.155213 90)
			(layer "B.Fab")
			(hide yes)
			(effects
				(font
					(size 0.7 0.7)
					(thickness 0.15)
				)
				(justify right bottom mirror)
			)
		)
		(property "Datasheet" "https://www.murata.com/products/productdetail?partno=GRM155R61H104KE14%23"
			(at 0 0 90)
			(layer "F.Fab")
			(hide yes)
			(effects
				(font
					(size 1.27 1.27)
					(thickness 0.15)
				)
			)
		)
		(property "Description" "SMD Multilayer Ceramic Capacitor, 0.1 µF, 50 V, 0402 [1005 Metric], ± 10%, X5R, GRM Series"
			(at 0 0 90)
			(layer "F.Fab")
			(hide yes)
			(effects
				(font
					(size 1.27 1.27)
					(thickness 0.15)
				)
			)
		)
		(property "Author" "Antmicro"
			(at 358.279887 -71.685085 0)
			(layer "B.Fab")
			(hide yes)
			(effects
				(font
					(size 1 1)
					(thickness 0.15)
				)
				(justify mirror)
			)
		)
		(property "Dielectric" "X5R"
			(at 358.279887 -71.685085 0)
			(layer "B.Fab")
			(hide yes)
			(effects
				(font
					(size 1 1)
					(thickness 0.15)
				)
				(justify mirror)
			)
		)
		(property "License" "Apache-2.0"
			(at 358.279887 -71.685085 0)
			(layer "B.Fab")
			(hide yes)
			(effects
				(font
					(size 1 1)
					(thickness 0.15)
				)
				(justify mirror)
			)
		)
		(property "MPN" "GRM155R61H104KE14D"
			(at 358.279887 -71.685085 0)
			(layer "B.Fab")
			(hide yes)
			(effects
				(font
					(size 1 1)
					(thickness 0.15)
				)
				(justify mirror)
			)
		)
		(property "Manufacturer" "Murata"
			(at 358.279887 -71.685085 0)
			(layer "B.Fab")
			(hide yes)
			(effects
				(font
					(size 1 1)
					(thickness 0.15)
				)
				(justify mirror)
			)
		)
		(property "Public" ""
			(at 358.279887 -71.685085 0)
			(layer "B.Fab")
			(hide yes)
			(effects
				(font
					(size 1 1)
					(thickness 0.15)
				)
				(justify mirror)
			)
		)
		(property "Val" "100n"
			(at 358.279887 -71.685085 0)
			(layer "B.Fab")
			(hide yes)
			(effects
				(font
					(size 1 1)
					(thickness 0.15)
				)
				(justify mirror)
			)
		)
		(property "Voltage" "50V"
			(at 358.279887 -71.685085 0)
			(layer "B.Fab")
			(hide yes)
			(effects
				(font
					(size 1 1)
					(thickness 0.15)
				)
				(justify mirror)
			)
		)
		(sheetname "/USB/")
		(sheetfile "usb.kicad_sch")
		(attr smd)
		(fp_rect
			(start -0.925 0.47)
			(end 0.925 -0.47)
			(stroke
				(width 0.05)
				(type default)
			)
			(fill no)
			(layer "B.CrtYd")
		)
		(fp_line
			(start 0.504 -0.248)
			(end -0.494 -0.248)
			(stroke
				(width 0.15)
				(type solid)
			)
			(layer "B.Fab")
		)
		(fp_line
			(start -0.494 -0.248)
			(end -0.494 0.25)
			(stroke
				(width 0.15)
				(type solid)
			)
			(layer "B.Fab")
		)
		(fp_line
			(start 0.504 0.25)
			(end 0.504 -0.248)
			(stroke
				(width 0.15)
				(type solid)
			)
			(layer "B.Fab")
		)
		(fp_line
			(start -0.494 0.25)
			(end 0.504 0.25)
			(stroke
				(width 0.15)
				(type solid)
			)
			(layer "B.Fab")
		)
		(fp_text user "Author: Antmicro"
			(at -0.939 -3.399 270)
			(layer "B.Fab")
			(effects
				(font
					(size 0.7 0.7)
					(thickness 0.15)
				)
				(justify left bottom mirror)
			)
		)
		(fp_text user "${REFERENCE}"
			(at -0.939 -4.599 270)
			(layer "B.Fab")
			(effects
				(font
					(size 0.7 0.7)
					(thickness 0.15)
				)
				(justify left bottom mirror)
			)
		)
		(fp_text user "License: Apache-2.0"
			(at -0.939 -5.799 270)
			(layer "B.Fab")
			(effects
				(font
					(size 0.7 0.7)
					(thickness 0.15)
				)
				(justify left bottom mirror)
			)
		)
		(pad "1" smd roundrect
			(at -0.48 0 90)
			(size 0.59 0.64)
			(layers "B.Cu" "B.Mask" "B.Paste")
			(roundrect_rratio 0.25)
			(net 417 "GND")
			(pintype "passive")
		)
		(pad "2" smd roundrect
			(at 0.48 0 90)
			(size 0.59 0.64)
			(layers "B.Cu" "B.Mask" "B.Paste")
			(roundrect_rratio 0.25)
			(net 152 "/USB/VDDIO")
			(pintype "passive")
		)
	)
	(footprint "antmicro-footprints:R_0402_1005Metric"
		(layer "B.Cu")
		(at 224.38 131.6)
		(descr "Resistor SMD 0402")
		(tags "resistor SMD 0402")
		(property "Reference" "R81"
			(at 1.07 1.3 180)
			(layer "B.SilkS")
			(effects
				(font
					(size 0.7 0.7)
					(thickness 0.15)
				)
				(justify left bottom mirror)
			)
		)
		(property "Value" "R_100k_0402"
			(at -1.011843 -1.772047 180)
			(layer "B.Fab")
			(hide yes)
			(effects
				(font
					(size 0.7 0.7)
					(thickness 0.15)
				)
				(justify left bottom mirror)
			)
		)
		(property "Datasheet" "https://www.bourns.com/docs/product-datasheets/cr.pdf"
			(at 0 0 0)
			(layer "F.Fab")
			(hide yes)
			(effects
				(font
					(size 1.27 1.27)
					(thickness 0.15)
				)
			)
		)
		(property "Description" "SMD Chip Resistor, 100 kohm, ± 1%, 62.5 mW, 0402 [1005 Metric], Thick Film, General Purpose"
			(at 0 0 0)
			(layer "F.Fab")
			(hide yes)
			(effects
				(font
					(size 1.27 1.27)
					(thickness 0.15)
				)
			)
		)
		(property "Author" "Antmicro"
			(at 0 0 0)
			(layer "B.Fab")
			(hide yes)
			(effects
				(font
					(size 1 1)
					(thickness 0.15)
				)
				(justify mirror)
			)
		)
		(property "License" "Apache-2.0"
			(at 0 0 0)
			(layer "B.Fab")
			(hide yes)
			(effects
				(font
					(size 1 1)
					(thickness 0.15)
				)
				(justify mirror)
			)
		)
		(property "MPN" "CR0402-FX-1003GLF"
			(at 0 0 0)
			(layer "B.Fab")
			(hide yes)
			(effects
				(font
					(size 1 1)
					(thickness 0.15)
				)
				(justify mirror)
			)
		)
		(property "Manufacturer" "Bourns"
			(at 0 0 0)
			(layer "B.Fab")
			(hide yes)
			(effects
				(font
					(size 1 1)
					(thickness 0.15)
				)
				(justify mirror)
			)
		)
		(property "Public" ""
			(at 0 0 0)
			(layer "B.Fab")
			(hide yes)
			(effects
				(font
					(size 1 1)
					(thickness 0.15)
				)
				(justify mirror)
			)
		)
		(property "Tolerance" "1%"
			(at 0 0 0)
			(layer "B.Fab")
			(hide yes)
			(effects
				(font
					(size 1 1)
					(thickness 0.15)
				)
				(justify mirror)
			)
		)
		(property "Val" "100k"
			(at 0 0 0)
			(layer "B.Fab")
			(hide yes)
			(effects
				(font
					(size 1 1)
					(thickness 0.15)
				)
				(justify mirror)
			)
		)
		(sheetname "/FPGA GPIO/")
		(sheetfile "fpga-gpio.kicad_sch")
		(attr smd)
		(fp_rect
			(start -0.925 0.47)
			(end 0.925 -0.47)
			(stroke
				(width 0.05)
				(type default)
			)
			(fill no)
			(layer "B.CrtYd")
		)
		(fp_rect
			(start -0.5 0.25)
			(end 0.5 -0.25)
			(stroke
				(width 0.15)
				(type solid)
			)
			(fill no)
			(layer "B.Fab")
		)
		(fp_text user "Author: Antmicro"
			(at -0.95 -4.169 180)
			(layer "B.Fab")
			(effects
				(font
					(size 0.7 0.7)
					(thickness 0.15)
				)
				(justify left bottom mirror)
			)
		)
		(fp_text user "${REFERENCE}"
			(at -0.95 -3.168 180)
			(layer "B.Fab")
			(effects
				(font
					(size 0.7 0.7)
					(thickness 0.15)
				)
				(justify left bottom mirror)
			)
		)
		(fp_text user "License: Apache-2.0"
			(at -0.95 -5.169 180)
			(layer "B.Fab")
			(effects
				(font
					(size 0.7 0.7)
					(thickness 0.15)
				)
				(justify left bottom mirror)
			)
		)
		(pad "1" smd roundrect
			(at -0.48 0)
			(size 0.59 0.64)
			(layers "B.Cu" "B.Mask" "B.Paste")
			(roundrect_rratio 0.25)
			(net 417 "GND")
			(pintype "passive")
		)
		(pad "2" smd roundrect
			(at 0.48 0)
			(size 0.59 0.64)
			(layers "B.Cu" "B.Mask" "B.Paste")
			(roundrect_rratio 0.25)
			(net 341 "/FPGA GPIO/USER_LED_G")
			(pintype "passive")
		)
	)
	(footprint "antmicro-footprints:TP_SMD_0.75mm"
		(layer "B.Cu")
		(at 216.35 121.75 180)
		(property "Reference" "TP23"
			(at -3.04 -0.26 0)
			(layer "B.SilkS")
			(hide yes)
			(effects
				(font
					(size 0.7 0.7)
					(thickness 0.15)
				)
				(justify left bottom mirror)
			)
		)
		(property "Value" "TP_0.75mm_SMD"
			(at 0 -1.2 0)
			(layer "B.Fab")
			(hide yes)
			(effects
				(font
					(size 0.7 0.7)
					(thickness 0.15)
				)
				(justify left bottom mirror)
			)
		)
		(property "Description" "SMT test point"
			(at 0 0 0)
			(layer "B.Fab")
			(hide yes)
			(effects
				(font
					(size 1.27 1.27)
					(thickness 0.15)
				)
				(justify mirror)
			)
		)
		(property "MPN" ""
			(at 0 0 0)
			(unlocked yes)
			(layer "B.Fab")
			(hide yes)
			(effects
				(font
					(size 1 1)
					(thickness 0.15)
				)
				(justify mirror)
			)
		)
		(property "Manufacturer" ""
			(at 0 0 0)
			(unlocked yes)
			(layer "B.Fab")
			(hide yes)
			(effects
				(font
					(size 1 1)
					(thickness 0.15)
				)
				(justify mirror)
			)
		)
		(property "Author" "Antmicro"
			(at 0 0 0)
			(unlocked yes)
			(layer "B.Fab")
			(hide yes)
			(effects
				(font
					(size 1 1)
					(thickness 0.15)
				)
				(justify mirror)
			)
		)
		(property "License" "Apache-2.0"
			(at 0 0 0)
			(unlocked yes)
			(layer "B.Fab")
			(hide yes)
			(effects
				(font
					(size 1 1)
					(thickness 0.15)
				)
				(justify mirror)
			)
		)
		(property "Public" "False"
			(at 0 0 0)
			(unlocked yes)
			(layer "B.Fab")
			(hide yes)
			(effects
				(font
					(size 1 1)
					(thickness 0.15)
				)
				(justify mirror)
			)
		)
		(sheetname "/Supply/")
		(sheetfile "supply.kicad_sch")
		(attr exclude_from_pos_files exclude_from_bom)
		(fp_circle
			(center 0 0)
			(end 0.475 0)
			(stroke
				(width 0.05)
				(type default)
			)
			(fill no)
			(layer "B.CrtYd")
		)
		(fp_text user "License: Apache-2.0"
			(at -0.4 -5.101 0)
			(layer "B.Fab")
			(effects
				(font
					(size 0.7 0.7)
					(thickness 0.15)
				)
				(justify left bottom mirror)
			)
		)
		(fp_text user "${REFERENCE}"
			(at -0.4 -2.7 0)
			(layer "B.Fab")
			(effects
				(font
					(size 0.7 0.7)
					(thickness 0.15)
				)
				(justify left bottom mirror)
			)
		)
		(fp_text user "Author: Antmicro"
			(at -0.4 -3.901 0)
			(layer "B.Fab")
			(effects
				(font
					(size 0.7 0.7)
					(thickness 0.15)
				)
				(justify left bottom mirror)
			)
		)
		(pad "1" smd circle
			(at 0 0 180)
			(size 0.75 0.75)
			(layers "B.Cu" "B.Mask")
			(net 417 "GND")
			(pinfunction "1")
			(pintype "passive")
		)
	)
	(footprint "antmicro-footprints:SOT-523"
		(layer "B.Cu")
		(at 226.68 129.9 180)
		(property "Reference" "Q8"
			(at 2.505 0.325 180)
			(layer "B.SilkS")
			(effects
				(font
					(size 0.7 0.7)
					(thickness 0.15)
				)
				(justify left bottom mirror)
			)
		)
		(property "Value" "DMG1012T-7"
			(at 0.1 -1.824 0)
			(layer "B.Fab")
			(hide yes)
			(effects
				(font
					(size 0.7 0.7)
					(thickness 0.15)
				)
				(justify left bottom mirror)
			)
		)
		(property "Datasheet" "https://www.diodes.com/assets/Datasheets/ds31783.pdf"
			(at 0 0 180)
			(layer "F.Fab")
			(hide yes)
			(effects
				(font
					(size 1.27 1.27)
					(thickness 0.15)
				)
			)
		)
		(property "Description" "Power MOSFET, N Channel, 20 V, 630 mA, 0.3 ohm, SOT-523, Surface Mount"
			(at 0 0 180)
			(layer "F.Fab")
			(hide yes)
			(effects
				(font
					(size 1.27 1.27)
					(thickness 0.15)
				)
			)
		)
		(property "Author" "Antmicro"
			(at 453.36 259.8 0)
			(layer "B.Fab")
			(hide yes)
			(effects
				(font
					(size 1 1)
					(thickness 0.15)
				)
				(justify mirror)
			)
		)
		(property "License" "Apache-2.0"
			(at 453.36 259.8 0)
			(layer "B.Fab")
			(hide yes)
			(effects
				(font
					(size 1 1)
					(thickness 0.15)
				)
				(justify mirror)
			)
		)
		(property "MPN" "DMG1012T-7"
			(at 453.36 259.8 0)
			(layer "B.Fab")
			(hide yes)
			(effects
				(font
					(size 1 1)
					(thickness 0.15)
				)
				(justify mirror)
			)
		)
		(property "Manufacturer" "Diodes Incorporated"
			(at 453.36 259.8 0)
			(layer "B.Fab")
			(hide yes)
			(effects
				(font
					(size 1 1)
					(thickness 0.15)
				)
				(justify mirror)
			)
		)
		(property "Public" ""
			(at 453.36 259.8 0)
			(layer "B.Fab")
			(hide yes)
			(effects
				(font
					(size 1 1)
					(thickness 0.15)
				)
				(justify mirror)
			)
		)
		(sheetname "/FPGA GPIO/")
		(sheetfile "fpga-gpio.kicad_sch")
		(attr smd)
		(fp_line
			(start -0.277 0.551)
			(end -0.277 0.75)
			(stroke
				(width 0.15)
				(type solid)
			)
			(layer "B.SilkS")
		)
		(fp_line
			(start -0.725 0.551)
			(end -0.277 0.551)
			(stroke
				(width 0.15)
				(type solid)
			)
			(layer "B.SilkS")
		)
		(fp_line
			(start -0.927 0.351)
			(end -0.725 0.551)
			(stroke
				(width 0.15)
				(type solid)
			)
			(layer "B.SilkS")
		)
		(fp_line
			(start -0.927 0.051)
			(end -0.927 0.351)
			(stroke
				(width 0.15)
				(type solid)
			)
			(layer "B.SilkS")
		)
		(fp_circle
			(center -0.9652 -0.9652)
			(end -0.9152 -0.9652)
			(stroke
				(width 0.15)
				(type solid)
			)
			(fill yes)
			(layer "B.SilkS")
		)
		(fp_line
			(start 1.1 1.16)
			(end 1.1 -1.15)
			(stroke
				(width 0.05)
				(type solid)
			)
			(layer "B.CrtYd")
		)
		(fp_line
			(start -1.12 1.16)
			(end 1.1 1.16)
			(stroke
				(width 0.05)
				(type solid)
			)
			(layer "B.CrtYd")
		)
		(fp_line
			(start -1.12 1.16)
			(end -1.12 -1.15)
			(stroke
				(width 0.05)
				(type solid)
			)
			(layer "B.CrtYd")
		)
		(fp_line
			(start -1.12 -1.15)
			(end 1.1 -1.15)
			(stroke
				(width 0.05)
				(type solid)
			)
			(layer "B.CrtYd")
		)
		(fp_line
			(start 0.8 0.425)
			(end 0.8 -0.424)
			(stroke
				(width 0.15)
				(type solid)
			)
			(layer "B.Fab")
		)
		(fp_line
			(start 0.8 0.425)
			(end -0.652 0.425)
			(stroke
				(width 0.15)
				(type solid)
			)
			(layer "B.Fab")
		)
		(fp_line
			(start 0.8 -0.424)
			(end -0.802 -0.424)
			(stroke
				(width 0.15)
				(type solid)
			)
			(layer "B.Fab")
		)
		(fp_line
			(start -0.652 0.425)
			(end -0.802 0.276)
			(stroke
				(width 0.15)
				(type solid)
			)
			(layer "B.Fab")
		)
		(fp_line
			(start -0.802 0.276)
			(end -0.802 -0.424)
			(stroke
				(width 0.15)
				(type solid)
			)
			(layer "B.Fab")
		)
		(fp_circle
			(center -0.9652 -0.9652)
			(end -0.9144 -0.9652)
			(stroke
				(width 0.15)
				(type solid)
			)
			(fill no)
			(layer "B.Fab")
		)
		(fp_text user "License: Apache-2.0"
			(at -1.12 -5.024 0)
			(layer "B.Fab")
			(effects
				(font
					(size 0.7 0.7)
					(thickness 0.15)
				)
				(justify left bottom mirror)
			)
		)
		(fp_text user "Author: Antmicro"
			(at -1.12 -6.224 0)
			(layer "B.Fab")
			(effects
				(font
					(size 0.7 0.7)
					(thickness 0.15)
				)
				(justify left bottom mirror)
			)
		)
		(fp_text user "${REFERENCE}"
			(at -1.12 -3.824 0)
			(layer "B.Fab")
			(effects
				(font
					(size 0.7 0.7)
					(thickness 0.15)
				)
				(justify left bottom mirror)
			)
		)
		(pad "1" smd rect
			(at -0.5 -0.65 180)
			(size 0.4 0.51)
			(layers "B.Cu" "B.Mask" "B.Paste")
			(net 342 "/FPGA GPIO/USER_LED_R")
			(pinfunction "G")
			(pintype "input")
		)
		(pad "2" smd rect
			(at 0.498 -0.65 180)
			(size 0.4 0.51)
			(layers "B.Cu" "B.Mask" "B.Paste")
			(net 417 "GND")
			(pinfunction "S")
			(pintype "passive")
		)
		(pad "3" smd rect
			(at 0 0.652 180)
			(size 0.4 0.51)
			(layers "B.Cu" "B.Mask" "B.Paste")
			(net 542 "Net-(Q8-D)")
			(pinfunction "D")
			(pintype "passive")
		)
	)
	(footprint "antmicro-footprints:C_0402_1005Metric"
		(layer "B.Cu")
		(at 201.15 140.564 90)
		(descr "Capacitor SMD 0402")
		(tags "capacitor SMD 0402")
		(property "Reference" "C27"
			(at 0.424 2.72 270)
			(layer "B.SilkS")
			(effects
				(font
					(size 0.7 0.7)
					(thickness 0.15)
				)
				(justify left bottom mirror)
			)
		)
		(property "Value" "C_4n7_0402"
			(at -1.022927 -2.155213 270)
			(layer "B.Fab")
			(hide yes)
			(effects
				(font
					(size 0.7 0.7)
					(thickness 0.15)
				)
				(justify left bottom mirror)
			)
		)
		(property "Datasheet" "https://product.tdk.com/en/search/capacitor/ceramic/mlcc/info?part_no=CGA2B3X7S2A472K050BB"
			(at 0 0 90)
			(layer "F.Fab")
			(hide yes)
			(effects
				(font
					(size 1.27 1.27)
					(thickness 0.15)
				)
			)
		)
		(property "Description" "SMD Multilayer Ceramic Capacitor, 4700 pF, 100 V, 0402 [1005 Metric], ± 10%, X7S, CGA"
			(at 0 0 90)
			(layer "F.Fab")
			(hide yes)
			(effects
				(font
					(size 1.27 1.27)
					(thickness 0.15)
				)
			)
		)
		(property "Author" "Antmicro"
			(at 341.714 -60.586 0)
			(layer "B.Fab")
			(hide yes)
			(effects
				(font
					(size 1 1)
					(thickness 0.15)
				)
				(justify mirror)
			)
		)
		(property "Dielectric" "X7R"
			(at 341.714 -60.586 0)
			(layer "B.Fab")
			(hide yes)
			(effects
				(font
					(size 1 1)
					(thickness 0.15)
				)
				(justify mirror)
			)
		)
		(property "License" "Apache-2.0"
			(at 341.714 -60.586 0)
			(layer "B.Fab")
			(hide yes)
			(effects
				(font
					(size 1 1)
					(thickness 0.15)
				)
				(justify mirror)
			)
		)
		(property "MPN" "CGA2B3X7S2A472K050BB"
			(at 341.714 -60.586 0)
			(layer "B.Fab")
			(hide yes)
			(effects
				(font
					(size 1 1)
					(thickness 0.15)
				)
				(justify mirror)
			)
		)
		(property "Manufacturer" "TDK"
			(at 341.714 -60.586 0)
			(layer "B.Fab")
			(hide yes)
			(effects
				(font
					(size 1 1)
					(thickness 0.15)
				)
				(justify mirror)
			)
		)
		(property "Public" ""
			(at 341.714 -60.586 0)
			(layer "B.Fab")
			(hide yes)
			(effects
				(font
					(size 1 1)
					(thickness 0.15)
				)
				(justify mirror)
			)
		)
		(property "Val" "4n7"
			(at 341.714 -60.586 0)
			(layer "B.Fab")
			(hide yes)
			(effects
				(font
					(size 1 1)
					(thickness 0.15)
				)
				(justify mirror)
			)
		)
		(property "Voltage" "25V"
			(at 341.714 -60.586 0)
			(layer "B.Fab")
			(hide yes)
			(effects
				(font
					(size 1 1)
					(thickness 0.15)
				)
				(justify mirror)
			)
		)
		(sheetname "/FPGA Supply/")
		(sheetfile "fpga-supply.kicad_sch")
		(attr smd)
		(fp_rect
			(start -0.925 0.47)
			(end 0.925 -0.47)
			(stroke
				(width 0.05)
				(type default)
			)
			(fill no)
			(layer "B.CrtYd")
		)
		(fp_line
			(start 0.504 -0.248)
			(end -0.494 -0.248)
			(stroke
				(width 0.15)
				(type solid)
			)
			(layer "B.Fab")
		)
		(fp_line
			(start -0.494 -0.248)
			(end -0.494 0.25)
			(stroke
				(width 0.15)
				(type solid)
			)
			(layer "B.Fab")
		)
		(fp_line
			(start 0.504 0.25)
			(end 0.504 -0.248)
			(stroke
				(width 0.15)
				(type solid)
			)
			(layer "B.Fab")
		)
		(fp_line
			(start -0.494 0.25)
			(end 0.504 0.25)
			(stroke
				(width 0.15)
				(type solid)
			)
			(layer "B.Fab")
		)
		(fp_text user "Author: Antmicro"
			(at -0.939 -3.399 270)
			(layer "B.Fab")
			(effects
				(font
					(size 0.7 0.7)
					(thickness 0.15)
				)
				(justify left bottom mirror)
			)
		)
		(fp_text user "License: Apache-2.0"
			(at -0.939 -5.799 270)
			(layer "B.Fab")
			(effects
				(font
					(size 0.7 0.7)
					(thickness 0.15)
				)
				(justify left bottom mirror)
			)
		)
		(fp_text user "${REFERENCE}"
			(at -0.939 -4.599 270)
			(layer "B.Fab")
			(effects
				(font
					(size 0.7 0.7)
					(thickness 0.15)
				)
				(justify left bottom mirror)
			)
		)
		(pad "1" smd roundrect
			(at -0.48 0 90)
			(size 0.59 0.64)
			(layers "B.Cu" "B.Mask" "B.Paste")
			(roundrect_rratio 0.25)
			(net 417 "GND")
			(pintype "passive")
		)
		(pad "2" smd roundrect
			(at 0.48 0 90)
			(size 0.59 0.64)
			(layers "B.Cu" "B.Mask" "B.Paste")
			(roundrect_rratio 0.25)
			(net 47 "+1V05")
			(pintype "passive")
		)
	)
	(footprint "antmicro-footprints:C_0402_1005Metric"
		(layer "B.Cu")
		(at 206.146 148.65 180)
		(descr "Capacitor SMD 0402")
		(tags "capacitor SMD 0402")
		(property "Reference" "C281"
			(at -1.044 8.94 0)
			(layer "B.SilkS")
			(effects
				(font
					(size 0.7 0.7)
					(thickness 0.15)
				)
				(justify left bottom mirror)
			)
		)
		(property "Value" "C_100n_0402"
			(at -1.022927 -2.155213 0)
			(layer "B.Fab")
			(hide yes)
			(effects
				(font
					(size 0.7 0.7)
					(thickness 0.15)
				)
				(justify left bottom mirror)
			)
		)
		(property "Datasheet" "https://www.murata.com/products/productdetail?partno=GRM155R61H104KE14%23"
			(at 0 0 180)
			(layer "F.Fab")
			(hide yes)
			(effects
				(font
					(size 1.27 1.27)
					(thickness 0.15)
				)
			)
		)
		(property "Description" "SMD Multilayer Ceramic Capacitor, 0.1 µF, 50 V, 0402 [1005 Metric], ± 10%, X5R, GRM Series"
			(at 0 0 180)
			(layer "F.Fab")
			(hide yes)
			(effects
				(font
					(size 1.27 1.27)
					(thickness 0.15)
				)
			)
		)
		(property "Author" "Antmicro"
			(at 412.292 297.3 0)
			(layer "B.Fab")
			(hide yes)
			(effects
				(font
					(size 1 1)
					(thickness 0.15)
				)
				(justify mirror)
			)
		)
		(property "Dielectric" "X5R"
			(at 412.292 297.3 0)
			(layer "B.Fab")
			(hide yes)
			(effects
				(font
					(size 1 1)
					(thickness 0.15)
				)
				(justify mirror)
			)
		)
		(property "License" "Apache-2.0"
			(at 412.292 297.3 0)
			(layer "B.Fab")
			(hide yes)
			(effects
				(font
					(size 1 1)
					(thickness 0.15)
				)
				(justify mirror)
			)
		)
		(property "MPN" "GRM155R61H104KE14D"
			(at 412.292 297.3 0)
			(layer "B.Fab")
			(hide yes)
			(effects
				(font
					(size 1 1)
					(thickness 0.15)
				)
				(justify mirror)
			)
		)
		(property "Manufacturer" "Murata"
			(at 412.292 297.3 0)
			(layer "B.Fab")
			(hide yes)
			(effects
				(font
					(size 1 1)
					(thickness 0.15)
				)
				(justify mirror)
			)
		)
		(property "Public" ""
			(at 412.292 297.3 0)
			(layer "B.Fab")
			(hide yes)
			(effects
				(font
					(size 1 1)
					(thickness 0.15)
				)
				(justify mirror)
			)
		)
		(property "Val" "100n"
			(at 412.292 297.3 0)
			(layer "B.Fab")
			(hide yes)
			(effects
				(font
					(size 1 1)
					(thickness 0.15)
				)
				(justify mirror)
			)
		)
		(property "Voltage" "50V"
			(at 412.292 297.3 0)
			(layer "B.Fab")
			(hide yes)
			(effects
				(font
					(size 1 1)
					(thickness 0.15)
				)
				(justify mirror)
			)
		)
		(sheetname "/MIPI CrossLink/")
		(sheetfile "crosslink.kicad_sch")
		(attr smd)
		(fp_rect
			(start -0.925 0.47)
			(end 0.925 -0.47)
			(stroke
				(width 0.05)
				(type default)
			)
			(fill no)
			(layer "B.CrtYd")
		)
		(fp_line
			(start 0.504 0.25)
			(end 0.504 -0.248)
			(stroke
				(width 0.15)
				(type solid)
			)
			(layer "B.Fab")
		)
		(fp_line
			(start 0.504 -0.248)
			(end -0.494 -0.248)
			(stroke
				(width 0.15)
				(type solid)
			)
			(layer "B.Fab")
		)
		(fp_line
			(start -0.494 0.25)
			(end 0.504 0.25)
			(stroke
				(width 0.15)
				(type solid)
			)
			(layer "B.Fab")
		)
		(fp_line
			(start -0.494 -0.248)
			(end -0.494 0.25)
			(stroke
				(width 0.15)
				(type solid)
			)
			(layer "B.Fab")
		)
		(fp_text user "${REFERENCE}"
			(at -0.939 -4.599 0)
			(layer "B.Fab")
			(effects
				(font
					(size 0.7 0.7)
					(thickness 0.15)
				)
				(justify left bottom mirror)
			)
		)
		(fp_text user "License: Apache-2.0"
			(at -0.939 -5.799 0)
			(layer "B.Fab")
			(effects
				(font
					(size 0.7 0.7)
					(thickness 0.15)
				)
				(justify left bottom mirror)
			)
		)
		(fp_text user "Author: Antmicro"
			(at -0.939 -3.399 0)
			(layer "B.Fab")
			(effects
				(font
					(size 0.7 0.7)
					(thickness 0.15)
				)
				(justify left bottom mirror)
			)
		)
		(pad "1" smd roundrect
			(at -0.48 0 180)
			(size 0.59 0.64)
			(layers "B.Cu" "B.Mask" "B.Paste")
			(roundrect_rratio 0.25)
			(net 417 "GND")
			(pintype "passive")
		)
		(pad "2" smd roundrect
			(at 0.48 0 180)
			(size 0.59 0.64)
			(layers "B.Cu" "B.Mask" "B.Paste")
			(roundrect_rratio 0.25)
			(net 211 "/MIPI CrossLink/CL_VCCPLL_DPHY1")
			(pintype "passive")
		)
	)
	(footprint "antmicro-footprints:C_0402_1005Metric"
		(layer "B.Cu")
		(at 214.865 146.55 90)
		(descr "Capacitor SMD 0402")
		(tags "capacitor SMD 0402")
		(property "Reference" "C217"
			(at -5.56 1.65 90)
			(layer "B.SilkS")
			(effects
				(font
					(size 0.7 0.7)
					(thickness 0.15)
				)
				(justify right bottom mirror)
			)
		)
		(property "Value" "C_100n_0402"
			(at -1.022927 -2.155213 90)
			(layer "B.Fab")
			(hide yes)
			(effects
				(font
					(size 0.7 0.7)
					(thickness 0.15)
				)
				(justify right bottom mirror)
			)
		)
		(property "Datasheet" "https://www.murata.com/products/productdetail?partno=GRM155R61H104KE14%23"
			(at 0 0 90)
			(layer "F.Fab")
			(hide yes)
			(effects
				(font
					(size 1.27 1.27)
					(thickness 0.15)
				)
			)
		)
		(property "Description" "SMD Multilayer Ceramic Capacitor, 0.1 µF, 50 V, 0402 [1005 Metric], ± 10%, X5R, GRM Series"
			(at 0 0 90)
			(layer "F.Fab")
			(hide yes)
			(effects
				(font
					(size 1.27 1.27)
					(thickness 0.15)
				)
			)
		)
		(property "Author" "Antmicro"
			(at 361.415 -68.315 0)
			(layer "B.Fab")
			(hide yes)
			(effects
				(font
					(size 1 1)
					(thickness 0.15)
				)
				(justify mirror)
			)
		)
		(property "Dielectric" "X5R"
			(at 361.415 -68.315 0)
			(layer "B.Fab")
			(hide yes)
			(effects
				(font
					(size 1 1)
					(thickness 0.15)
				)
				(justify mirror)
			)
		)
		(property "License" "Apache-2.0"
			(at 361.415 -68.315 0)
			(layer "B.Fab")
			(hide yes)
			(effects
				(font
					(size 1 1)
					(thickness 0.15)
				)
				(justify mirror)
			)
		)
		(property "MPN" "GRM155R61H104KE14D"
			(at 361.415 -68.315 0)
			(layer "B.Fab")
			(hide yes)
			(effects
				(font
					(size 1 1)
					(thickness 0.15)
				)
				(justify mirror)
			)
		)
		(property "Manufacturer" "Murata"
			(at 361.415 -68.315 0)
			(layer "B.Fab")
			(hide yes)
			(effects
				(font
					(size 1 1)
					(thickness 0.15)
				)
				(justify mirror)
			)
		)
		(property "Public" ""
			(at 361.415 -68.315 0)
			(layer "B.Fab")
			(hide yes)
			(effects
				(font
					(size 1 1)
					(thickness 0.15)
				)
				(justify mirror)
			)
		)
		(property "Val" "100n"
			(at 361.415 -68.315 0)
			(layer "B.Fab")
			(hide yes)
			(effects
				(font
					(size 1 1)
					(thickness 0.15)
				)
				(justify mirror)
			)
		)
		(property "Voltage" "50V"
			(at 361.415 -68.315 0)
			(layer "B.Fab")
			(hide yes)
			(effects
				(font
					(size 1 1)
					(thickness 0.15)
				)
				(justify mirror)
			)
		)
		(sheetname "/USB/")
		(sheetfile "usb.kicad_sch")
		(attr smd)
		(fp_rect
			(start -0.925 0.47)
			(end 0.925 -0.47)
			(stroke
				(width 0.05)
				(type default)
			)
			(fill no)
			(layer "B.CrtYd")
		)
		(fp_line
			(start 0.504 -0.248)
			(end -0.494 -0.248)
			(stroke
				(width 0.15)
				(type solid)
			)
			(layer "B.Fab")
		)
		(fp_line
			(start -0.494 -0.248)
			(end -0.494 0.25)
			(stroke
				(width 0.15)
				(type solid)
			)
			(layer "B.Fab")
		)
		(fp_line
			(start 0.504 0.25)
			(end 0.504 -0.248)
			(stroke
				(width 0.15)
				(type solid)
			)
			(layer "B.Fab")
		)
		(fp_line
			(start -0.494 0.25)
			(end 0.504 0.25)
			(stroke
				(width 0.15)
				(type solid)
			)
			(layer "B.Fab")
		)
		(fp_text user "${REFERENCE}"
			(at -0.939 -4.599 270)
			(layer "B.Fab")
			(effects
				(font
					(size 0.7 0.7)
					(thickness 0.15)
				)
				(justify left bottom mirror)
			)
		)
		(fp_text user "License: Apache-2.0"
			(at -0.939 -5.799 270)
			(layer "B.Fab")
			(effects
				(font
					(size 0.7 0.7)
					(thickness 0.15)
				)
				(justify left bottom mirror)
			)
		)
		(fp_text user "Author: Antmicro"
			(at -0.939 -3.399 270)
			(layer "B.Fab")
			(effects
				(font
					(size 0.7 0.7)
					(thickness 0.15)
				)
				(justify left bottom mirror)
			)
		)
		(pad "1" smd roundrect
			(at -0.48 0 90)
			(size 0.59 0.64)
			(layers "B.Cu" "B.Mask" "B.Paste")
			(roundrect_rratio 0.25)
			(net 417 "GND")
			(pintype "passive")
		)
		(pad "2" smd roundrect
			(at 0.48 0 90)
			(size 0.59 0.64)
			(layers "B.Cu" "B.Mask" "B.Paste")
			(roundrect_rratio 0.25)
			(net 179 "Net-(U28-PLLFILT)")
			(pintype "passive")
		)
	)
	(footprint "antmicro-footprints:R_0402_1005Metric"
		(layer "B.Cu")
		(at 216.515 141.1)
		(descr "Resistor SMD 0402")
		(tags "resistor SMD 0402")
		(property "Reference" "R65"
			(at -1.075 -0.53 0)
			(layer "B.SilkS")
			(effects
				(font
					(size 0.7 0.7)
					(thickness 0.15)
				)
				(justify right bottom mirror)
			)
		)
		(property "Value" "R_27R_0402"
			(at -1.011843 -1.772047 0)
			(layer "B.Fab")
			(hide yes)
			(effects
				(font
					(size 0.7 0.7)
					(thickness 0.15)
				)
				(justify right bottom mirror)
			)
		)
		(property "Datasheet" "https://www.bourns.com/docs/product-datasheets/cr.pdf"
			(at 0 0 0)
			(layer "F.Fab")
			(hide yes)
			(effects
				(font
					(size 1.27 1.27)
					(thickness 0.15)
				)
			)
		)
		(property "Description" "SMD Chip Resistor, 27 ohm, ± 1%, 63 mW, 0402 [1005 Metric], Thick Film, General Purpose"
			(at 0 0 0)
			(layer "F.Fab")
			(hide yes)
			(effects
				(font
					(size 1.27 1.27)
					(thickness 0.15)
				)
			)
		)
		(property "Author" "Antmicro"
			(at 0 0 0)
			(layer "B.Fab")
			(hide yes)
			(effects
				(font
					(size 1 1)
					(thickness 0.15)
				)
				(justify mirror)
			)
		)
		(property "License" "Apache-2.0"
			(at 0 0 0)
			(layer "B.Fab")
			(hide yes)
			(effects
				(font
					(size 1 1)
					(thickness 0.15)
				)
				(justify mirror)
			)
		)
		(property "MPN" "CR0402-FX-27R0GLF"
			(at 0 0 0)
			(layer "B.Fab")
			(hide yes)
			(effects
				(font
					(size 1 1)
					(thickness 0.15)
				)
				(justify mirror)
			)
		)
		(property "Manufacturer" "Bourns"
			(at 0 0 0)
			(layer "B.Fab")
			(hide yes)
			(effects
				(font
					(size 1 1)
					(thickness 0.15)
				)
				(justify mirror)
			)
		)
		(property "Public" ""
			(at 0 0 0)
			(layer "B.Fab")
			(hide yes)
			(effects
				(font
					(size 1 1)
					(thickness 0.15)
				)
				(justify mirror)
			)
		)
		(property "Tolerance" "1%"
			(at 0 0 0)
			(layer "B.Fab")
			(hide yes)
			(effects
				(font
					(size 1 1)
					(thickness 0.15)
				)
				(justify mirror)
			)
		)
		(property "Val" "27R"
			(at 0 0 0)
			(layer "B.Fab")
			(hide yes)
			(effects
				(font
					(size 1 1)
					(thickness 0.15)
				)
				(justify mirror)
			)
		)
		(sheetname "/USB/")
		(sheetfile "usb.kicad_sch")
		(attr smd)
		(fp_rect
			(start -0.925 0.47)
			(end 0.925 -0.47)
			(stroke
				(width 0.05)
				(type default)
			)
			(fill no)
			(layer "B.CrtYd")
		)
		(fp_rect
			(start -0.5 0.25)
			(end 0.5 -0.25)
			(stroke
				(width 0.15)
				(type solid)
			)
			(fill no)
			(layer "B.Fab")
		)
		(fp_text user "${REFERENCE}"
			(at -0.95 -3.168 180)
			(layer "B.Fab")
			(effects
				(font
					(size 0.7 0.7)
					(thickness 0.15)
				)
				(justify left bottom mirror)
			)
		)
		(fp_text user "Author: Antmicro"
			(at -0.95 -4.169 180)
			(layer "B.Fab")
			(effects
				(font
					(size 0.7 0.7)
					(thickness 0.15)
				)
				(justify left bottom mirror)
			)
		)
		(fp_text user "License: Apache-2.0"
			(at -0.95 -5.169 180)
			(layer "B.Fab")
			(effects
				(font
					(size 0.7 0.7)
					(thickness 0.15)
				)
				(justify left bottom mirror)
			)
		)
		(pad "1" smd roundrect
			(at -0.48 0)
			(size 0.59 0.64)
			(layers "B.Cu" "B.Mask" "B.Paste")
			(roundrect_rratio 0.25)
			(net 636 "/FPGA GPIO/ULPI.CLK")
			(pintype "passive")
		)
		(pad "2" smd roundrect
			(at 0.48 0)
			(size 0.59 0.64)
			(layers "B.Cu" "B.Mask" "B.Paste")
			(roundrect_rratio 0.25)
			(net 279 "Net-(U13-CLKOUT)")
			(pintype "passive")
		)
	)
	(footprint "antmicro-footprints:C_0402_1005Metric"
		(layer "B.Cu")
		(at 205.25 147.41 180)
		(descr "Capacitor SMD 0402")
		(tags "capacitor SMD 0402")
		(property "Reference" "C210"
			(at -1.8 8.64 0)
			(layer "B.SilkS")
			(effects
				(font
					(size 0.7 0.7)
					(thickness 0.15)
				)
				(justify left bottom mirror)
			)
		)
		(property "Value" "C_100n_0402"
			(at -1.022927 -2.155213 0)
			(layer "B.Fab")
			(hide yes)
			(effects
				(font
					(size 0.7 0.7)
					(thickness 0.15)
				)
				(justify left bottom mirror)
			)
		)
		(property "Datasheet" "https://www.murata.com/products/productdetail?partno=GRM155R61H104KE14%23"
			(at 0 0 180)
			(layer "F.Fab")
			(hide yes)
			(effects
				(font
					(size 1.27 1.27)
					(thickness 0.15)
				)
			)
		)
		(property "Description" "SMD Multilayer Ceramic Capacitor, 0.1 µF, 50 V, 0402 [1005 Metric], ± 10%, X5R, GRM Series"
			(at 0 0 180)
			(layer "F.Fab")
			(hide yes)
			(effects
				(font
					(size 1.27 1.27)
					(thickness 0.15)
				)
			)
		)
		(property "Author" "Antmicro"
			(at 410.5 294.82 0)
			(layer "B.Fab")
			(hide yes)
			(effects
				(font
					(size 1 1)
					(thickness 0.15)
				)
				(justify mirror)
			)
		)
		(property "Dielectric" "X5R"
			(at 410.5 294.82 0)
			(layer "B.Fab")
			(hide yes)
			(effects
				(font
					(size 1 1)
					(thickness 0.15)
				)
				(justify mirror)
			)
		)
		(property "License" "Apache-2.0"
			(at 410.5 294.82 0)
			(layer "B.Fab")
			(hide yes)
			(effects
				(font
					(size 1 1)
					(thickness 0.15)
				)
				(justify mirror)
			)
		)
		(property "MPN" "GRM155R61H104KE14D"
			(at 410.5 294.82 0)
			(layer "B.Fab")
			(hide yes)
			(effects
				(font
					(size 1 1)
					(thickness 0.15)
				)
				(justify mirror)
			)
		)
		(property "Manufacturer" "Murata"
			(at 410.5 294.82 0)
			(layer "B.Fab")
			(hide yes)
			(effects
				(font
					(size 1 1)
					(thickness 0.15)
				)
				(justify mirror)
			)
		)
		(property "Public" ""
			(at 410.5 294.82 0)
			(layer "B.Fab")
			(hide yes)
			(effects
				(font
					(size 1 1)
					(thickness 0.15)
				)
				(justify mirror)
			)
		)
		(property "Val" "100n"
			(at 410.5 294.82 0)
			(layer "B.Fab")
			(hide yes)
			(effects
				(font
					(size 1 1)
					(thickness 0.15)
				)
				(justify mirror)
			)
		)
		(property "Voltage" "50V"
			(at 410.5 294.82 0)
			(layer "B.Fab")
			(hide yes)
			(effects
				(font
					(size 1 1)
					(thickness 0.15)
				)
				(justify mirror)
			)
		)
		(sheetname "/MIPI CrossLink/")
		(sheetfile "crosslink.kicad_sch")
		(attr smd)
		(fp_rect
			(start -0.925 0.47)
			(end 0.925 -0.47)
			(stroke
				(width 0.05)
				(type default)
			)
			(fill no)
			(layer "B.CrtYd")
		)
		(fp_line
			(start 0.504 0.25)
			(end 0.504 -0.248)
			(stroke
				(width 0.15)
				(type solid)
			)
			(layer "B.Fab")
		)
		(fp_line
			(start 0.504 -0.248)
			(end -0.494 -0.248)
			(stroke
				(width 0.15)
				(type solid)
			)
			(layer "B.Fab")
		)
		(fp_line
			(start -0.494 0.25)
			(end 0.504 0.25)
			(stroke
				(width 0.15)
				(type solid)
			)
			(layer "B.Fab")
		)
		(fp_line
			(start -0.494 -0.248)
			(end -0.494 0.25)
			(stroke
				(width 0.15)
				(type solid)
			)
			(layer "B.Fab")
		)
		(fp_text user "${REFERENCE}"
			(at -0.939 -4.599 0)
			(layer "B.Fab")
			(effects
				(font
					(size 0.7 0.7)
					(thickness 0.15)
				)
				(justify left bottom mirror)
			)
		)
		(fp_text user "License: Apache-2.0"
			(at -0.939 -5.799 0)
			(layer "B.Fab")
			(effects
				(font
					(size 0.7 0.7)
					(thickness 0.15)
				)
				(justify left bottom mirror)
			)
		)
		(fp_text user "Author: Antmicro"
			(at -0.939 -3.399 0)
			(layer "B.Fab")
			(effects
				(font
					(size 0.7 0.7)
					(thickness 0.15)
				)
				(justify left bottom mirror)
			)
		)
		(pad "1" smd roundrect
			(at -0.48 0 180)
			(size 0.59 0.64)
			(layers "B.Cu" "B.Mask" "B.Paste")
			(roundrect_rratio 0.25)
			(net 417 "GND")
			(pintype "passive")
		)
		(pad "2" smd roundrect
			(at 0.48 0 180)
			(size 0.59 0.64)
			(layers "B.Cu" "B.Mask" "B.Paste")
			(roundrect_rratio 0.25)
			(net 176 "/MIPI CrossLink/CL_VCC")
			(pintype "passive")
		)
	)
	(footprint "antmicro-footprints:C_0402_1005Metric"
		(layer "B.Cu")
		(at 183.25 134.1 90)
		(descr "Capacitor SMD 0402")
		(tags "capacitor SMD 0402")
		(property "Reference" "C158"
			(at -1.21 -0.56 90)
			(layer "B.SilkS")
			(effects
				(font
					(size 0.7 0.7)
					(thickness 0.15)
				)
				(justify right bottom mirror)
			)
		)
		(property "Value" "C_1u_0402"
			(at -1.022927 -2.155213 90)
			(layer "B.Fab")
			(hide yes)
			(effects
				(font
					(size 0.7 0.7)
					(thickness 0.15)
				)
				(justify right bottom mirror)
			)
		)
		(property "Datasheet" "https://product.tdk.com/en/search/capacitor/ceramic/mlcc/info?part_no=C1005X6S1A105K050BC"
			(at 0 0 90)
			(layer "F.Fab")
			(hide yes)
			(effects
				(font
					(size 1.27 1.27)
					(thickness 0.15)
				)
			)
		)
		(property "Description" "SMD Multilayer Ceramic Capacitor, 1 µF, 10 V, 0402 [1005 Metric], ± 10%, X6S, C"
			(at 0 0 90)
			(layer "F.Fab")
			(hide yes)
			(effects
				(font
					(size 1.27 1.27)
					(thickness 0.15)
				)
			)
		)
		(property "Author" "Antmicro"
			(at 317.35 -49.15 0)
			(layer "B.Fab")
			(hide yes)
			(effects
				(font
					(size 1 1)
					(thickness 0.15)
				)
				(justify mirror)
			)
		)
		(property "Dielectric" "X5R"
			(at 317.35 -49.15 0)
			(layer "B.Fab")
			(hide yes)
			(effects
				(font
					(size 1 1)
					(thickness 0.15)
				)
				(justify mirror)
			)
		)
		(property "License" "Apache-2.0"
			(at 317.35 -49.15 0)
			(layer "B.Fab")
			(hide yes)
			(effects
				(font
					(size 1 1)
					(thickness 0.15)
				)
				(justify mirror)
			)
		)
		(property "MPN" "C1005X6S1A105K050BC"
			(at 317.35 -49.15 0)
			(layer "B.Fab")
			(hide yes)
			(effects
				(font
					(size 1 1)
					(thickness 0.15)
				)
				(justify mirror)
			)
		)
		(property "Manufacturer" "TDK"
			(at 317.35 -49.15 0)
			(layer "B.Fab")
			(hide yes)
			(effects
				(font
					(size 1 1)
					(thickness 0.15)
				)
				(justify mirror)
			)
		)
		(property "Public" ""
			(at 317.35 -49.15 0)
			(layer "B.Fab")
			(hide yes)
			(effects
				(font
					(size 1 1)
					(thickness 0.15)
				)
				(justify mirror)
			)
		)
		(property "Val" "1u"
			(at 317.35 -49.15 0)
			(layer "B.Fab")
			(hide yes)
			(effects
				(font
					(size 1 1)
					(thickness 0.15)
				)
				(justify mirror)
			)
		)
		(property "Voltage" "16V"
			(at 317.35 -49.15 0)
			(layer "B.Fab")
			(hide yes)
			(effects
				(font
					(size 1 1)
					(thickness 0.15)
				)
				(justify mirror)
			)
		)
		(sheetname "/LPDDR4/")
		(sheetfile "lpddr.kicad_sch")
		(attr smd)
		(fp_rect
			(start -0.925 0.47)
			(end 0.925 -0.47)
			(stroke
				(width 0.05)
				(type default)
			)
			(fill no)
			(layer "B.CrtYd")
		)
		(fp_line
			(start 0.504 -0.248)
			(end -0.494 -0.248)
			(stroke
				(width 0.15)
				(type solid)
			)
			(layer "B.Fab")
		)
		(fp_line
			(start -0.494 -0.248)
			(end -0.494 0.25)
			(stroke
				(width 0.15)
				(type solid)
			)
			(layer "B.Fab")
		)
		(fp_line
			(start 0.504 0.25)
			(end 0.504 -0.248)
			(stroke
				(width 0.15)
				(type solid)
			)
			(layer "B.Fab")
		)
		(fp_line
			(start -0.494 0.25)
			(end 0.504 0.25)
			(stroke
				(width 0.15)
				(type solid)
			)
			(layer "B.Fab")
		)
		(fp_text user "License: Apache-2.0"
			(at -0.939 -5.799 270)
			(layer "B.Fab")
			(effects
				(font
					(size 0.7 0.7)
					(thickness 0.15)
				)
				(justify left bottom mirror)
			)
		)
		(fp_text user "${REFERENCE}"
			(at -0.939 -4.599 270)
			(layer "B.Fab")
			(effects
				(font
					(size 0.7 0.7)
					(thickness 0.15)
				)
				(justify left bottom mirror)
			)
		)
		(fp_text user "Author: Antmicro"
			(at -0.939 -3.399 270)
			(layer "B.Fab")
			(effects
				(font
					(size 0.7 0.7)
					(thickness 0.15)
				)
				(justify left bottom mirror)
			)
		)
		(pad "1" smd roundrect
			(at -0.48 0 90)
			(size 0.59 0.64)
			(layers "B.Cu" "B.Mask" "B.Paste")
			(roundrect_rratio 0.25)
			(net 417 "GND")
			(pintype "passive")
		)
		(pad "2" smd roundrect
			(at 0.48 0 90)
			(size 0.59 0.64)
			(layers "B.Cu" "B.Mask" "B.Paste")
			(roundrect_rratio 0.25)
			(net 2 "+1V1")
			(pintype "passive")
		)
	)
	(footprint "antmicro-footprints:SOT-583"
		(layer "B.Cu")
		(at 222.175 138.875 -90)
		(property "Reference" "U9"
			(at -1.225 1.35 90)
			(layer "B.SilkS")
			(effects
				(font
					(size 0.7 0.7)
					(thickness 0.15)
				)
				(justify left bottom mirror)
			)
		)
		(property "Value" "TPS2117DRLR"
			(at 0 -2.3 90)
			(layer "B.Fab")
			(hide yes)
			(effects
				(font
					(size 0.7 0.7)
					(thickness 0.15)
				)
				(justify left bottom mirror)
			)
		)
		(property "Datasheet" "https://www.ti.com/lit/ds/symlink/tps2117.pdf"
			(at 0 0 270)
			(layer "F.Fab")
			(hide yes)
			(effects
				(font
					(size 1.27 1.27)
					(thickness 0.15)
				)
			)
		)
		(property "Description" "TPS2117 1.6-V to 5.5-V, 4-A Low IQ Power Mux With Manual and Priority Switchover"
			(at 0 0 270)
			(layer "F.Fab")
			(hide yes)
			(effects
				(font
					(size 1.27 1.27)
					(thickness 0.15)
				)
			)
		)
		(property "Author" "Antmicro"
			(at 83.3 361.05 0)
			(layer "B.Fab")
			(hide yes)
			(effects
				(font
					(size 1 1)
					(thickness 0.15)
				)
				(justify mirror)
			)
		)
		(property "License" "Apache-2.0"
			(at 83.3 361.05 0)
			(layer "B.Fab")
			(hide yes)
			(effects
				(font
					(size 1 1)
					(thickness 0.15)
				)
				(justify mirror)
			)
		)
		(property "MPN" "TPS2117DRLR"
			(at 83.3 361.05 0)
			(layer "B.Fab")
			(hide yes)
			(effects
				(font
					(size 1 1)
					(thickness 0.15)
				)
				(justify mirror)
			)
		)
		(property "Manufacturer" "Texas Instruments"
			(at 83.3 361.05 0)
			(layer "B.Fab")
			(hide yes)
			(effects
				(font
					(size 1 1)
					(thickness 0.15)
				)
				(justify mirror)
			)
		)
		(property ki_fp_filters "DRL0008A-MFG")
		(sheetname "/Memory/")
		(sheetfile "memory.kicad_sch")
		(attr smd)
		(fp_line
			(start -0.65 1.15)
			(end 0.65 1.15)
			(stroke
				(width 0.15)
				(type solid)
			)
			(layer "B.SilkS")
		)
		(fp_line
			(start -0.651 -1.15)
			(end 0.651 -1.15)
			(stroke
				(width 0.15)
				(type solid)
			)
			(layer "B.SilkS")
		)
		(fp_circle
			(center -0.9 1.1)
			(end -0.85 1.05)
			(stroke
				(width 0.15)
				(type solid)
			)
			(fill yes)
			(layer "B.SilkS")
		)
		(fp_rect
			(start -1.15 1.3)
			(end 1.15 -1.3)
			(stroke
				(width 0.05)
				(type solid)
			)
			(fill no)
			(layer "B.CrtYd")
		)
		(fp_line
			(start -0.651 1.1005)
			(end 0.651 1.1005)
			(stroke
				(width 0.15)
				(type solid)
			)
			(layer "B.Fab")
		)
		(fp_line
			(start -0.651 -1.1005)
			(end -0.651 1.1005)
			(stroke
				(width 0.15)
				(type solid)
			)
			(layer "B.Fab")
		)
		(fp_line
			(start -0.651 -1.1005)
			(end 0.651 -1.1005)
			(stroke
				(width 0.15)
				(type solid)
			)
			(layer "B.Fab")
		)
		(fp_line
			(start 0.651 -1.1005)
			(end 0.651 1.1005)
			(stroke
				(width 0.15)
				(type solid)
			)
			(layer "B.Fab")
		)
		(fp_text user "Author: Antmicro"
			(at -0.06 -5.025 90)
			(layer "B.Fab")
			(effects
				(font
					(size 0.7 0.7)
					(thickness 0.15)
				)
				(justify left bottom mirror)
			)
		)
		(fp_text user "${REFERENCE}"
			(at -0.06 -4.025 90)
			(layer "B.Fab")
			(effects
				(font
					(size 0.7 0.7)
					(thickness 0.15)
				)
				(justify left bottom mirror)
			)
		)
		(fp_text user "License: Apache-2.0"
			(at -0.06 -6.025 90)
			(layer "B.Fab")
			(effects
				(font
					(size 0.7 0.7)
					(thickness 0.15)
				)
				(justify left bottom mirror)
			)
		)
		(pad "1" smd roundrect
			(at -0.739 0.7495 270)
			(size 0.670001 0.299999)
			(layers "B.Cu" "B.Mask" "B.Paste")
			(roundrect_rratio 0.25)
			(net 417 "GND")
			(pinfunction "GND")
			(pintype "power_in")
		)
		(pad "2" smd roundrect
			(at -0.739 0.2505 270)
			(size 0.670001 0.299999)
			(layers "B.Cu" "B.Mask" "B.Paste")
			(roundrect_rratio 0.25)
			(net 516 "Net-(R50-Pad1)")
			(pinfunction "VOUT")
			(pintype "power_out")
		)
		(pad "3" smd roundrect
			(at -0.739 -0.2495 270)
			(size 0.670001 0.299999)
			(layers "B.Cu" "B.Mask" "B.Paste")
			(roundrect_rratio 0.25)
			(net 48 "+1V8")
			(pinfunction "VIN1")
			(pintype "power_in")
		)
		(pad "4" smd roundrect
			(at -0.739 -0.7495 270)
			(size 0.670001 0.299999)
			(layers "B.Cu" "B.Mask" "B.Paste")
			(roundrect_rratio 0.25)
			(net 246 "SD_VDD_OVERRIDE")
			(pinfunction "PR1")
			(pintype "input")
		)
		(pad "5" smd roundrect
			(at 0.74 -0.7495 270)
			(size 0.670001 0.299999)
			(layers "B.Cu" "B.Mask" "B.Paste")
			(roundrect_rratio 0.25)
			(net 50 "+3V3")
			(pinfunction "MODE")
			(pintype "input")
		)
		(pad "6" smd roundrect
			(at 0.74 -0.2495 270)
			(size 0.670001 0.299999)
			(layers "B.Cu" "B.Mask" "B.Paste")
			(roundrect_rratio 0.25)
			(net 50 "+3V3")
			(pinfunction "VIN2")
			(pintype "power_in")
		)
		(pad "7" smd roundrect
			(at 0.74 0.2505 270)
			(size 0.670001 0.299999)
			(layers "B.Cu" "B.Mask" "B.Paste")
			(roundrect_rratio 0.25)
			(net 516 "Net-(R50-Pad1)")
			(pinfunction "VOUT")
			(pintype "passive")
		)
		(pad "8" smd roundrect
			(at 0.74 0.7495 270)
			(size 0.670001 0.299999)
			(layers "B.Cu" "B.Mask" "B.Paste")
			(roundrect_rratio 0.25)
			(net 517 "SD_VDD_FLAG")
			(pinfunction "ST")
			(pintype "output")
		)
	)
	(footprint "antmicro-footprints:C_0402_1005Metric"
		(layer "B.Cu")
		(at 223.75 123 90)
		(descr "Capacitor SMD 0402")
		(tags "capacitor SMD 0402")
		(property "Reference" "C18"
			(at 0.95 0.55 270)
			(layer "B.SilkS")
			(effects
				(font
					(size 0.7 0.7)
					(thickness 0.15)
				)
				(justify right bottom mirror)
			)
		)
		(property "Value" "C_100n_0402"
			(at -1.022927 -2.155213 90)
			(layer "B.Fab")
			(hide yes)
			(effects
				(font
					(size 0.7 0.7)
					(thickness 0.15)
				)
				(justify right bottom mirror)
			)
		)
		(property "Datasheet" "https://www.murata.com/products/productdetail?partno=GRM155R61H104KE14%23"
			(at 0 0 90)
			(layer "F.Fab")
			(hide yes)
			(effects
				(font
					(size 1.27 1.27)
					(thickness 0.15)
				)
			)
		)
		(property "Description" "SMD Multilayer Ceramic Capacitor, 0.1 µF, 50 V, 0402 [1005 Metric], ± 10%, X5R, GRM Series"
			(at 0 0 90)
			(layer "F.Fab")
			(hide yes)
			(effects
				(font
					(size 1.27 1.27)
					(thickness 0.15)
				)
			)
		)
		(property "Author" "Antmicro"
			(at 346.75 -100.75 0)
			(layer "B.Fab")
			(hide yes)
			(effects
				(font
					(size 1 1)
					(thickness 0.15)
				)
				(justify mirror)
			)
		)
		(property "Dielectric" "X5R"
			(at 346.75 -100.75 0)
			(layer "B.Fab")
			(hide yes)
			(effects
				(font
					(size 1 1)
					(thickness 0.15)
				)
				(justify mirror)
			)
		)
		(property "License" "Apache-2.0"
			(at 346.75 -100.75 0)
			(layer "B.Fab")
			(hide yes)
			(effects
				(font
					(size 1 1)
					(thickness 0.15)
				)
				(justify mirror)
			)
		)
		(property "MPN" "GRM155R61H104KE14D"
			(at 346.75 -100.75 0)
			(layer "B.Fab")
			(hide yes)
			(effects
				(font
					(size 1 1)
					(thickness 0.15)
				)
				(justify mirror)
			)
		)
		(property "Manufacturer" "Murata"
			(at 346.75 -100.75 0)
			(layer "B.Fab")
			(hide yes)
			(effects
				(font
					(size 1 1)
					(thickness 0.15)
				)
				(justify mirror)
			)
		)
		(property "Public" ""
			(at 346.75 -100.75 0)
			(layer "B.Fab")
			(hide yes)
			(effects
				(font
					(size 1 1)
					(thickness 0.15)
				)
				(justify mirror)
			)
		)
		(property "Val" "100n"
			(at 346.75 -100.75 0)
			(layer "B.Fab")
			(hide yes)
			(effects
				(font
					(size 1 1)
					(thickness 0.15)
				)
				(justify mirror)
			)
		)
		(property "Voltage" "50V"
			(at 346.75 -100.75 0)
			(layer "B.Fab")
			(hide yes)
			(effects
				(font
					(size 1 1)
					(thickness 0.15)
				)
				(justify mirror)
			)
		)
		(sheetname "/FPGA GPIO/")
		(sheetfile "fpga-gpio.kicad_sch")
		(attr smd)
		(fp_rect
			(start -0.925 0.47)
			(end 0.925 -0.47)
			(stroke
				(width 0.05)
				(type default)
			)
			(fill no)
			(layer "B.CrtYd")
		)
		(fp_line
			(start 0.504 -0.248)
			(end -0.494 -0.248)
			(stroke
				(width 0.15)
				(type solid)
			)
			(layer "B.Fab")
		)
		(fp_line
			(start -0.494 -0.248)
			(end -0.494 0.25)
			(stroke
				(width 0.15)
				(type solid)
			)
			(layer "B.Fab")
		)
		(fp_line
			(start 0.504 0.25)
			(end 0.504 -0.248)
			(stroke
				(width 0.15)
				(type solid)
			)
			(layer "B.Fab")
		)
		(fp_line
			(start -0.494 0.25)
			(end 0.504 0.25)
			(stroke
				(width 0.15)
				(type solid)
			)
			(layer "B.Fab")
		)
		(fp_text user "Author: Antmicro"
			(at -0.939 -3.399 270)
			(layer "B.Fab")
			(effects
				(font
					(size 0.7 0.7)
					(thickness 0.15)
				)
				(justify left bottom mirror)
			)
		)
		(fp_text user "License: Apache-2.0"
			(at -0.939 -5.799 270)
			(layer "B.Fab")
			(effects
				(font
					(size 0.7 0.7)
					(thickness 0.15)
				)
				(justify left bottom mirror)
			)
		)
		(fp_text user "${REFERENCE}"
			(at -0.939 -4.599 270)
			(layer "B.Fab")
			(effects
				(font
					(size 0.7 0.7)
					(thickness 0.15)
				)
				(justify left bottom mirror)
			)
		)
		(pad "1" smd roundrect
			(at -0.48 0 90)
			(size 0.59 0.64)
			(layers "B.Cu" "B.Mask" "B.Paste")
			(roundrect_rratio 0.25)
			(net 649 "VDD")
			(pintype "passive")
		)
		(pad "2" smd roundrect
			(at 0.48 0 90)
			(size 0.59 0.64)
			(layers "B.Cu" "B.Mask" "B.Paste")
			(roundrect_rratio 0.25)
			(net 417 "GND")
			(pintype "passive")
		)
	)
	(footprint "antmicro-footprints:C_0402_1005Metric"
		(layer "B.Cu")
		(at 201.4 147.45)
		(descr "Capacitor SMD 0402")
		(tags "capacitor SMD 0402")
		(property "Reference" "C208"
			(at -1.74 2.53 0)
			(layer "B.SilkS")
			(effects
				(font
					(size 0.7 0.7)
					(thickness 0.15)
				)
				(justify right bottom mirror)
			)
		)
		(property "Value" "C_10u_10V_0402"
			(at -1.022927 -2.155213 0)
			(layer "B.Fab")
			(hide yes)
			(effects
				(font
					(size 0.7 0.7)
					(thickness 0.15)
				)
				(justify right bottom mirror)
			)
		)
		(property "Datasheet" "https://www.murata.com/products/productdetail?partno=GRM155R61A106ME11%23"
			(at 0 0 0)
			(layer "F.Fab")
			(hide yes)
			(effects
				(font
					(size 1.27 1.27)
					(thickness 0.15)
				)
			)
		)
		(property "Description" "Multilayer Ceramic Capacitors MLCC - SMD/SMT 10 uF 10 VDC 20% 0402 X5R"
			(at 0 0 0)
			(layer "F.Fab")
			(hide yes)
			(effects
				(font
					(size 1.27 1.27)
					(thickness 0.15)
				)
			)
		)
		(property "Author" "Antmicro"
			(at 0 0 0)
			(layer "B.Fab")
			(hide yes)
			(effects
				(font
					(size 1 1)
					(thickness 0.15)
				)
				(justify mirror)
			)
		)
		(property "Dielectric" "X5R"
			(at 0 0 0)
			(layer "B.Fab")
			(hide yes)
			(effects
				(font
					(size 1 1)
					(thickness 0.15)
				)
				(justify mirror)
			)
		)
		(property "License" "Apache-2.0"
			(at 0 0 0)
			(layer "B.Fab")
			(hide yes)
			(effects
				(font
					(size 1 1)
					(thickness 0.15)
				)
				(justify mirror)
			)
		)
		(property "MPN" "GRM155R61A106ME11D"
			(at 0 0 0)
			(layer "B.Fab")
			(hide yes)
			(effects
				(font
					(size 1 1)
					(thickness 0.15)
				)
				(justify mirror)
			)
		)
		(property "Manufacturer" "Murata"
			(at 0 0 0)
			(layer "B.Fab")
			(hide yes)
			(effects
				(font
					(size 1 1)
					(thickness 0.15)
				)
				(justify mirror)
			)
		)
		(property "Public" ""
			(at 0 0 0)
			(layer "B.Fab")
			(hide yes)
			(effects
				(font
					(size 1 1)
					(thickness 0.15)
				)
				(justify mirror)
			)
		)
		(property "Val" "10u"
			(at 0 0 0)
			(layer "B.Fab")
			(hide yes)
			(effects
				(font
					(size 1 1)
					(thickness 0.15)
				)
				(justify mirror)
			)
		)
		(property "Voltage" "10V"
			(at 0 0 0)
			(layer "B.Fab")
			(hide yes)
			(effects
				(font
					(size 1 1)
					(thickness 0.15)
				)
				(justify mirror)
			)
		)
		(sheetname "/MIPI CrossLink/")
		(sheetfile "crosslink.kicad_sch")
		(attr smd)
		(fp_rect
			(start -0.925 0.47)
			(end 0.925 -0.47)
			(stroke
				(width 0.05)
				(type default)
			)
			(fill no)
			(layer "B.CrtYd")
		)
		(fp_line
			(start -0.494 -0.248)
			(end -0.494 0.25)
			(stroke
				(width 0.15)
				(type solid)
			)
			(layer "B.Fab")
		)
		(fp_line
			(start -0.494 0.25)
			(end 0.504 0.25)
			(stroke
				(width 0.15)
				(type solid)
			)
			(layer "B.Fab")
		)
		(fp_line
			(start 0.504 -0.248)
			(end -0.494 -0.248)
			(stroke
				(width 0.15)
				(type solid)
			)
			(layer "B.Fab")
		)
		(fp_line
			(start 0.504 0.25)
			(end 0.504 -0.248)
			(stroke
				(width 0.15)
				(type solid)
			)
			(layer "B.Fab")
		)
		(fp_text user "License: Apache-2.0"
			(at -0.939 -5.799 180)
			(layer "B.Fab")
			(effects
				(font
					(size 0.7 0.7)
					(thickness 0.15)
				)
				(justify left bottom mirror)
			)
		)
		(fp_text user "${REFERENCE}"
			(at -0.939 -4.599 180)
			(layer "B.Fab")
			(effects
				(font
					(size 0.7 0.7)
					(thickness 0.15)
				)
				(justify left bottom mirror)
			)
		)
		(fp_text user "Author: Antmicro"
			(at -0.939 -3.399 180)
			(layer "B.Fab")
			(effects
				(font
					(size 0.7 0.7)
					(thickness 0.15)
				)
				(justify left bottom mirror)
			)
		)
		(pad "1" smd roundrect
			(at -0.48 0)
			(size 0.59 0.64)
			(layers "B.Cu" "B.Mask" "B.Paste")
			(roundrect_rratio 0.25)
			(net 417 "GND")
			(pintype "passive")
		)
		(pad "2" smd roundrect
			(at 0.48 0)
			(size 0.59 0.64)
			(layers "B.Cu" "B.Mask" "B.Paste")
			(roundrect_rratio 0.25)
			(net 203 "/MIPI CrossLink/CL_VCCA_DPHY0")
			(pintype "passive")
		)
	)
	(footprint "antmicro-footprints:R_0402_1005Metric"
		(layer "B.Cu")
		(at 184.275 152.05 -90)
		(descr "Resistor SMD 0402")
		(tags "resistor SMD 0402")
		(property "Reference" "R19"
			(at -2.95 -0.425 90)
			(layer "B.SilkS")
			(effects
				(font
					(size 0.7 0.7)
					(thickness 0.15)
				)
				(justify left bottom mirror)
			)
		)
		(property "Value" "R_205k_0402"
			(at -1.011843 -1.772047 90)
			(layer "B.Fab")
			(hide yes)
			(effects
				(font
					(size 0.7 0.7)
					(thickness 0.15)
				)
				(justify left bottom mirror)
			)
		)
		(property "Datasheet" "https://www.bourns.com/docs/product-datasheets/cr.pdf"
			(at 0 0 270)
			(layer "F.Fab")
			(hide yes)
			(effects
				(font
					(size 1.27 1.27)
					(thickness 0.15)
				)
			)
		)
		(property "Description" "SMD Chip Resistor"
			(at 0 0 270)
			(layer "F.Fab")
			(hide yes)
			(effects
				(font
					(size 1.27 1.27)
					(thickness 0.15)
				)
			)
		)
		(property "Author" "Antmicro"
			(at 32.225 336.325 0)
			(layer "B.Fab")
			(hide yes)
			(effects
				(font
					(size 1 1)
					(thickness 0.15)
				)
				(justify mirror)
			)
		)
		(property "License" "Apache-2.0"
			(at 32.225 336.325 0)
			(layer "B.Fab")
			(hide yes)
			(effects
				(font
					(size 1 1)
					(thickness 0.15)
				)
				(justify mirror)
			)
		)
		(property "MPN" "CR0402-FX-2053GLF"
			(at 32.225 336.325 0)
			(layer "B.Fab")
			(hide yes)
			(effects
				(font
					(size 1 1)
					(thickness 0.15)
				)
				(justify mirror)
			)
		)
		(property "Manufacturer" "Bourns"
			(at 32.225 336.325 0)
			(layer "B.Fab")
			(hide yes)
			(effects
				(font
					(size 1 1)
					(thickness 0.15)
				)
				(justify mirror)
			)
		)
		(property "Public" ""
			(at 32.225 336.325 0)
			(layer "B.Fab")
			(hide yes)
			(effects
				(font
					(size 1 1)
					(thickness 0.15)
				)
				(justify mirror)
			)
		)
		(property "Tolerance" "1%"
			(at 32.225 336.325 0)
			(layer "B.Fab")
			(hide yes)
			(effects
				(font
					(size 1 1)
					(thickness 0.15)
				)
				(justify mirror)
			)
		)
		(property "Val" "205k"
			(at 32.225 336.325 0)
			(layer "B.Fab")
			(hide yes)
			(effects
				(font
					(size 1 1)
					(thickness 0.15)
				)
				(justify mirror)
			)
		)
		(sheetname "/Supply/")
		(sheetfile "supply.kicad_sch")
		(attr smd)
		(fp_rect
			(start -0.925 0.47)
			(end 0.925 -0.47)
			(stroke
				(width 0.05)
				(type default)
			)
			(fill no)
			(layer "B.CrtYd")
		)
		(fp_rect
			(start -0.5 0.25)
			(end 0.5 -0.25)
			(stroke
				(width 0.15)
				(type solid)
			)
			(fill no)
			(layer "B.Fab")
		)
		(fp_text user "${REFERENCE}"
			(at -0.95 -3.168 90)
			(layer "B.Fab")
			(effects
				(font
					(size 0.7 0.7)
					(thickness 0.15)
				)
				(justify left bottom mirror)
			)
		)
		(fp_text user "License: Apache-2.0"
			(at -0.95 -5.169 90)
			(layer "B.Fab")
			(effects
				(font
					(size 0.7 0.7)
					(thickness 0.15)
				)
				(justify left bottom mirror)
			)
		)
		(fp_text user "Author: Antmicro"
			(at -0.95 -4.169 90)
			(layer "B.Fab")
			(effects
				(font
					(size 0.7 0.7)
					(thickness 0.15)
				)
				(justify left bottom mirror)
			)
		)
		(pad "1" smd roundrect
			(at -0.48 0 270)
			(size 0.59 0.64)
			(layers "B.Cu" "B.Mask" "B.Paste")
			(roundrect_rratio 0.25)
			(net 417 "GND")
			(pintype "passive")
		)
		(pad "2" smd roundrect
			(at 0.48 0 270)
			(size 0.59 0.64)
			(layers "B.Cu" "B.Mask" "B.Paste")
			(roundrect_rratio 0.25)
			(net 14 "Net-(C111-Pad1)")
			(pintype "passive")
		)
	)
	(footprint "antmicro-footprints:R_0402_1005Metric"
		(layer "B.Cu")
		(at 178.75 145.55 -90)
		(descr "Resistor SMD 0402")
		(tags "resistor SMD 0402")
		(property "Reference" "R69"
			(at 3.62 -1.32 90)
			(layer "B.SilkS")
			(effects
				(font
					(size 0.7 0.7)
					(thickness 0.15)
				)
				(justify left bottom mirror)
			)
		)
		(property "Value" "R_100k_0402"
			(at -1.011843 -1.772047 90)
			(layer "B.Fab")
			(hide yes)
			(effects
				(font
					(size 0.7 0.7)
					(thickness 0.15)
				)
				(justify left bottom mirror)
			)
		)
		(property "Datasheet" "https://www.bourns.com/docs/product-datasheets/cr.pdf"
			(at 0 0 270)
			(layer "F.Fab")
			(hide yes)
			(effects
				(font
					(size 1.27 1.27)
					(thickness 0.15)
				)
			)
		)
		(property "Description" "SMD Chip Resistor, 100 kohm, ± 1%, 62.5 mW, 0402 [1005 Metric], Thick Film, General Purpose"
			(at 0 0 270)
			(layer "F.Fab")
			(hide yes)
			(effects
				(font
					(size 1.27 1.27)
					(thickness 0.15)
				)
			)
		)
		(property "Author" "Antmicro"
			(at 33.2 324.3 0)
			(layer "B.Fab")
			(hide yes)
			(effects
				(font
					(size 1 1)
					(thickness 0.15)
				)
				(justify mirror)
			)
		)
		(property "License" "Apache-2.0"
			(at 33.2 324.3 0)
			(layer "B.Fab")
			(hide yes)
			(effects
				(font
					(size 1 1)
					(thickness 0.15)
				)
				(justify mirror)
			)
		)
		(property "MPN" "CR0402-FX-1003GLF"
			(at 33.2 324.3 0)
			(layer "B.Fab")
			(hide yes)
			(effects
				(font
					(size 1 1)
					(thickness 0.15)
				)
				(justify mirror)
			)
		)
		(property "Manufacturer" "Bourns"
			(at 33.2 324.3 0)
			(layer "B.Fab")
			(hide yes)
			(effects
				(font
					(size 1 1)
					(thickness 0.15)
				)
				(justify mirror)
			)
		)
		(property "Public" ""
			(at 33.2 324.3 0)
			(layer "B.Fab")
			(hide yes)
			(effects
				(font
					(size 1 1)
					(thickness 0.15)
				)
				(justify mirror)
			)
		)
		(property "Tolerance" "1%"
			(at 33.2 324.3 0)
			(layer "B.Fab")
			(hide yes)
			(effects
				(font
					(size 1 1)
					(thickness 0.15)
				)
				(justify mirror)
			)
		)
		(property "Val" "100k"
			(at 33.2 324.3 0)
			(layer "B.Fab")
			(hide yes)
			(effects
				(font
					(size 1 1)
					(thickness 0.15)
				)
				(justify mirror)
			)
		)
		(sheetname "/Supply/")
		(sheetfile "supply.kicad_sch")
		(attr smd)
		(fp_rect
			(start -0.925 0.47)
			(end 0.925 -0.47)
			(stroke
				(width 0.05)
				(type default)
			)
			(fill no)
			(layer "B.CrtYd")
		)
		(fp_rect
			(start -0.5 0.25)
			(end 0.5 -0.25)
			(stroke
				(width 0.15)
				(type solid)
			)
			(fill no)
			(layer "B.Fab")
		)
		(fp_text user "Author: Antmicro"
			(at -0.95 -4.169 90)
			(layer "B.Fab")
			(effects
				(font
					(size 0.7 0.7)
					(thickness 0.15)
				)
				(justify left bottom mirror)
			)
		)
		(fp_text user "License: Apache-2.0"
			(at -0.95 -5.169 90)
			(layer "B.Fab")
			(effects
				(font
					(size 0.7 0.7)
					(thickness 0.15)
				)
				(justify left bottom mirror)
			)
		)
		(fp_text user "${REFERENCE}"
			(at -0.95 -3.168 90)
			(layer "B.Fab")
			(effects
				(font
					(size 0.7 0.7)
					(thickness 0.15)
				)
				(justify left bottom mirror)
			)
		)
		(pad "1" smd roundrect
			(at -0.48 0 270)
			(size 0.59 0.64)
			(layers "B.Cu" "B.Mask" "B.Paste")
			(roundrect_rratio 0.25)
			(net 417 "GND")
			(pintype "passive")
		)
		(pad "2" smd roundrect
			(at 0.48 0 270)
			(size 0.59 0.64)
			(layers "B.Cu" "B.Mask" "B.Paste")
			(roundrect_rratio 0.25)
			(net 656 "/Supply/PG")
			(pintype "passive")
		)
	)
	(footprint "antmicro-footprints:C_0402_1005Metric"
		(layer "B.Cu")
		(at 191.384 125.101 180)
		(descr "Capacitor SMD 0402")
		(tags "capacitor SMD 0402")
		(property "Reference" "C1"
			(at -1.116 0.526 0)
			(layer "B.SilkS")
			(effects
				(font
					(size 0.7 0.7)
					(thickness 0.15)
				)
				(justify left bottom mirror)
			)
		)
		(property "Value" "C_1n_0402"
			(at -1.022927 -2.155213 0)
			(layer "B.Fab")
			(hide yes)
			(effects
				(font
					(size 0.7 0.7)
					(thickness 0.15)
				)
				(justify left bottom mirror)
			)
		)
		(property "Datasheet" "https://www.murata.com/products/productdetail?partno=GRM1555C1H102JA01%23"
			(at 0 0 180)
			(layer "F.Fab")
			(hide yes)
			(effects
				(font
					(size 1.27 1.27)
					(thickness 0.15)
				)
			)
		)
		(property "Description" "SMD Multilayer Ceramic Capacitor, 1000 pF, 50 V, 0402 [1005 Metric], ± 5%, C0G / NP0, GRM Series"
			(at 0 0 180)
			(layer "F.Fab")
			(hide yes)
			(effects
				(font
					(size 1.27 1.27)
					(thickness 0.15)
				)
			)
		)
		(property "Author" "Antmicro"
			(at 382.768 250.202 0)
			(layer "B.Fab")
			(hide yes)
			(effects
				(font
					(size 1 1)
					(thickness 0.15)
				)
				(justify mirror)
			)
		)
		(property "Dielectric" "C0G"
			(at 382.768 250.202 0)
			(layer "B.Fab")
			(hide yes)
			(effects
				(font
					(size 1 1)
					(thickness 0.15)
				)
				(justify mirror)
			)
		)
		(property "License" "Apache-2.0"
			(at 382.768 250.202 0)
			(layer "B.Fab")
			(hide yes)
			(effects
				(font
					(size 1 1)
					(thickness 0.15)
				)
				(justify mirror)
			)
		)
		(property "MPN" "GRM1555C1H102JA01D"
			(at 382.768 250.202 0)
			(layer "B.Fab")
			(hide yes)
			(effects
				(font
					(size 1 1)
					(thickness 0.15)
				)
				(justify mirror)
			)
		)
		(property "Manufacturer" "Murata"
			(at 382.768 250.202 0)
			(layer "B.Fab")
			(hide yes)
			(effects
				(font
					(size 1 1)
					(thickness 0.15)
				)
				(justify mirror)
			)
		)
		(property "Public" ""
			(at 382.768 250.202 0)
			(layer "B.Fab")
			(hide yes)
			(effects
				(font
					(size 1 1)
					(thickness 0.15)
				)
				(justify mirror)
			)
		)
		(property "Val" "1n"
			(at 382.768 250.202 0)
			(layer "B.Fab")
			(hide yes)
			(effects
				(font
					(size 1 1)
					(thickness 0.15)
				)
				(justify mirror)
			)
		)
		(property "Voltage" "50V"
			(at 382.768 250.202 0)
			(layer "B.Fab")
			(hide yes)
			(effects
				(font
					(size 1 1)
					(thickness 0.15)
				)
				(justify mirror)
			)
		)
		(sheetname "/FPGA Supply/")
		(sheetfile "fpga-supply.kicad_sch")
		(attr smd)
		(fp_rect
			(start -0.925 0.47)
			(end 0.925 -0.47)
			(stroke
				(width 0.05)
				(type default)
			)
			(fill no)
			(layer "B.CrtYd")
		)
		(fp_line
			(start 0.504 0.25)
			(end 0.504 -0.248)
			(stroke
				(width 0.15)
				(type solid)
			)
			(layer "B.Fab")
		)
		(fp_line
			(start 0.504 -0.248)
			(end -0.494 -0.248)
			(stroke
				(width 0.15)
				(type solid)
			)
			(layer "B.Fab")
		)
		(fp_line
			(start -0.494 0.25)
			(end 0.504 0.25)
			(stroke
				(width 0.15)
				(type solid)
			)
			(layer "B.Fab")
		)
		(fp_line
			(start -0.494 -0.248)
			(end -0.494 0.25)
			(stroke
				(width 0.15)
				(type solid)
			)
			(layer "B.Fab")
		)
		(fp_text user "Author: Antmicro"
			(at -0.939 -3.399 0)
			(layer "B.Fab")
			(effects
				(font
					(size 0.7 0.7)
					(thickness 0.15)
				)
				(justify left bottom mirror)
			)
		)
		(fp_text user "License: Apache-2.0"
			(at -0.939 -5.799 0)
			(layer "B.Fab")
			(effects
				(font
					(size 0.7 0.7)
					(thickness 0.15)
				)
				(justify left bottom mirror)
			)
		)
		(fp_text user "${REFERENCE}"
			(at -0.939 -4.599 0)
			(layer "B.Fab")
			(effects
				(font
					(size 0.7 0.7)
					(thickness 0.15)
				)
				(justify left bottom mirror)
			)
		)
		(pad "1" smd roundrect
			(at -0.48 0 180)
			(size 0.59 0.64)
			(layers "B.Cu" "B.Mask" "B.Paste")
			(roundrect_rratio 0.25)
			(net 417 "GND")
			(pintype "passive")
		)
		(pad "2" smd roundrect
			(at 0.48 0 180)
			(size 0.59 0.64)
			(layers "B.Cu" "B.Mask" "B.Paste")
			(roundrect_rratio 0.25)
			(net 2 "+1V1")
			(pintype "passive")
		)
	)
	(footprint "antmicro-footprints:R_0402_1005Metric"
		(layer "B.Cu")
		(at 225.075 147.825 90)
		(descr "Resistor SMD 0402")
		(tags "resistor SMD 0402")
		(property "Reference" "R99"
			(at 0.915 2.465 90)
			(layer "B.SilkS")
			(effects
				(font
					(size 0.7 0.7)
					(thickness 0.15)
				)
				(justify left bottom mirror)
			)
		)
		(property "Value" "R_0R_0402"
			(at -1.011843 -1.772047 270)
			(layer "B.Fab")
			(hide yes)
			(effects
				(font
					(size 0.7 0.7)
					(thickness 0.15)
				)
				(justify left bottom mirror)
			)
		)
		(property "Datasheet" "https://industrial.panasonic.com/cdbs/www-data/pdf/RDA0000/AOA0000C301.pdf"
			(at 0 0 90)
			(layer "F.Fab")
			(hide yes)
			(effects
				(font
					(size 1.27 1.27)
					(thickness 0.15)
				)
			)
		)
		(property "Description" "SMD Chip Resistor, Jumper, 0 ohm, 100 mW, 0402 [1005 Metric], Thick Film, General Purpose"
			(at 0 0 90)
			(layer "F.Fab")
			(hide yes)
			(effects
				(font
					(size 1.27 1.27)
					(thickness 0.15)
				)
			)
		)
		(property "Author" "Antmicro"
			(at 372.9 -77.25 0)
			(layer "B.Fab")
			(hide yes)
			(effects
				(font
					(size 1 1)
					(thickness 0.15)
				)
				(justify mirror)
			)
		)
		(property "Current" "1A"
			(at 372.9 -77.25 0)
			(layer "B.Fab")
			(hide yes)
			(effects
				(font
					(size 1 1)
					(thickness 0.15)
				)
				(justify mirror)
			)
		)
		(property "License" "Apache-2.0"
			(at 372.9 -77.25 0)
			(layer "B.Fab")
			(hide yes)
			(effects
				(font
					(size 1 1)
					(thickness 0.15)
				)
				(justify mirror)
			)
		)
		(property "MPN" "ERJ2GE0R00X"
			(at 372.9 -77.25 0)
			(layer "B.Fab")
			(hide yes)
			(effects
				(font
					(size 1 1)
					(thickness 0.15)
				)
				(justify mirror)
			)
		)
		(property "Manufacturer" "Panasonic"
			(at 372.9 -77.25 0)
			(layer "B.Fab")
			(hide yes)
			(effects
				(font
					(size 1 1)
					(thickness 0.15)
				)
				(justify mirror)
			)
		)
		(property "Public" ""
			(at 372.9 -77.25 0)
			(layer "B.Fab")
			(hide yes)
			(effects
				(font
					(size 1 1)
					(thickness 0.15)
				)
				(justify mirror)
			)
		)
		(property "Tolerance" "~"
			(at 372.9 -77.25 0)
			(layer "B.Fab")
			(hide yes)
			(effects
				(font
					(size 1 1)
					(thickness 0.15)
				)
				(justify mirror)
			)
		)
		(property "Val" "0R"
			(at 372.9 -77.25 0)
			(layer "B.Fab")
			(hide yes)
			(effects
				(font
					(size 1 1)
					(thickness 0.15)
				)
				(justify mirror)
			)
		)
		(sheetname "/FPGA MSSIO/")
		(sheetfile "fpga-mssio.kicad_sch")
		(attr smd)
		(fp_rect
			(start -0.925 0.47)
			(end 0.925 -0.47)
			(stroke
				(width 0.05)
				(type default)
			)
			(fill no)
			(layer "B.CrtYd")
		)
		(fp_rect
			(start -0.5 0.25)
			(end 0.5 -0.25)
			(stroke
				(width 0.15)
				(type solid)
			)
			(fill no)
			(layer "B.Fab")
		)
		(fp_text user "${REFERENCE}"
			(at -0.95 -3.168 270)
			(layer "B.Fab")
			(effects
				(font
					(size 0.7 0.7)
					(thickness 0.15)
				)
				(justify left bottom mirror)
			)
		)
		(fp_text user "License: Apache-2.0"
			(at -0.95 -5.169 270)
			(layer "B.Fab")
			(effects
				(font
					(size 0.7 0.7)
					(thickness 0.15)
				)
				(justify left bottom mirror)
			)
		)
		(fp_text user "Author: Antmicro"
			(at -0.95 -4.169 270)
			(layer "B.Fab")
			(effects
				(font
					(size 0.7 0.7)
					(thickness 0.15)
				)
				(justify left bottom mirror)
			)
		)
		(pad "1" smd roundrect
			(at -0.48 0 90)
			(size 0.59 0.64)
			(layers "B.Cu" "B.Mask" "B.Paste")
			(roundrect_rratio 0.25)
			(net 285 "Net-(U1C-MSSIO35B2)")
			(pintype "passive")
		)
		(pad "2" smd roundrect
			(at 0.48 0 90)
			(size 0.59 0.64)
			(layers "B.Cu" "B.Mask" "B.Paste")
			(roundrect_rratio 0.25)
			(net 193 "/FPGA MSSIO/BT_UART_TX")
			(pintype "passive")
		)
	)
	(footprint "antmicro-footprints:C_0402_1005Metric"
		(layer "B.Cu")
		(at 193.45 146.75 90)
		(descr "Capacitor SMD 0402")
		(tags "capacitor SMD 0402")
		(property "Reference" "C187"
			(at -3.65 0.6 90)
			(layer "B.SilkS")
			(effects
				(font
					(size 0.7 0.7)
					(thickness 0.15)
				)
				(justify right bottom mirror)
			)
		)
		(property "Value" "C_100n_0402"
			(at -1.022927 -2.155213 90)
			(layer "B.Fab")
			(hide yes)
			(effects
				(font
					(size 0.7 0.7)
					(thickness 0.15)
				)
				(justify right bottom mirror)
			)
		)
		(property "Datasheet" "https://www.murata.com/products/productdetail?partno=GRM155R61H104KE14%23"
			(at 0 0 90)
			(layer "F.Fab")
			(hide yes)
			(effects
				(font
					(size 1.27 1.27)
					(thickness 0.15)
				)
			)
		)
		(property "Description" "SMD Multilayer Ceramic Capacitor, 0.1 µF, 50 V, 0402 [1005 Metric], ± 10%, X5R, GRM Series"
			(at 0 0 90)
			(layer "F.Fab")
			(hide yes)
			(effects
				(font
					(size 1.27 1.27)
					(thickness 0.15)
				)
			)
		)
		(property "Author" "Antmicro"
			(at 340.2 -46.7 0)
			(layer "B.Fab")
			(hide yes)
			(effects
				(font
					(size 1 1)
					(thickness 0.15)
				)
				(justify mirror)
			)
		)
		(property "Dielectric" "X5R"
			(at 340.2 -46.7 0)
			(layer "B.Fab")
			(hide yes)
			(effects
				(font
					(size 1 1)
					(thickness 0.15)
				)
				(justify mirror)
			)
		)
		(property "License" "Apache-2.0"
			(at 340.2 -46.7 0)
			(layer "B.Fab")
			(hide yes)
			(effects
				(font
					(size 1 1)
					(thickness 0.15)
				)
				(justify mirror)
			)
		)
		(property "MPN" "GRM155R61H104KE14D"
			(at 340.2 -46.7 0)
			(layer "B.Fab")
			(hide yes)
			(effects
				(font
					(size 1 1)
					(thickness 0.15)
				)
				(justify mirror)
			)
		)
		(property "Manufacturer" "Murata"
			(at 340.2 -46.7 0)
			(layer "B.Fab")
			(hide yes)
			(effects
				(font
					(size 1 1)
					(thickness 0.15)
				)
				(justify mirror)
			)
		)
		(property "Public" ""
			(at 340.2 -46.7 0)
			(layer "B.Fab")
			(hide yes)
			(effects
				(font
					(size 1 1)
					(thickness 0.15)
				)
				(justify mirror)
			)
		)
		(property "Val" "100n"
			(at 340.2 -46.7 0)
			(layer "B.Fab")
			(hide yes)
			(effects
				(font
					(size 1 1)
					(thickness 0.15)
				)
				(justify mirror)
			)
		)
		(property "Voltage" "50V"
			(at 340.2 -46.7 0)
			(layer "B.Fab")
			(hide yes)
			(effects
				(font
					(size 1 1)
					(thickness 0.15)
				)
				(justify mirror)
			)
		)
		(sheetname "/HDMI/")
		(sheetfile "hdmi.kicad_sch")
		(attr smd)
		(fp_rect
			(start -0.925 0.47)
			(end 0.925 -0.47)
			(stroke
				(width 0.05)
				(type default)
			)
			(fill no)
			(layer "B.CrtYd")
		)
		(fp_line
			(start 0.504 -0.248)
			(end -0.494 -0.248)
			(stroke
				(width 0.15)
				(type solid)
			)
			(layer "B.Fab")
		)
		(fp_line
			(start -0.494 -0.248)
			(end -0.494 0.25)
			(stroke
				(width 0.15)
				(type solid)
			)
			(layer "B.Fab")
		)
		(fp_line
			(start 0.504 0.25)
			(end 0.504 -0.248)
			(stroke
				(width 0.15)
				(type solid)
			)
			(layer "B.Fab")
		)
		(fp_line
			(start -0.494 0.25)
			(end 0.504 0.25)
			(stroke
				(width 0.15)
				(type solid)
			)
			(layer "B.Fab")
		)
		(fp_text user "${REFERENCE}"
			(at -0.939 -4.599 270)
			(layer "B.Fab")
			(effects
				(font
					(size 0.7 0.7)
					(thickness 0.15)
				)
				(justify left bottom mirror)
			)
		)
		(fp_text user "Author: Antmicro"
			(at -0.939 -3.399 270)
			(layer "B.Fab")
			(effects
				(font
					(size 0.7 0.7)
					(thickness 0.15)
				)
				(justify left bottom mirror)
			)
		)
		(fp_text user "License: Apache-2.0"
			(at -0.939 -5.799 270)
			(layer "B.Fab")
			(effects
				(font
					(size 0.7 0.7)
					(thickness 0.15)
				)
				(justify left bottom mirror)
			)
		)
		(pad "1" smd roundrect
			(at -0.48 0 90)
			(size 0.59 0.64)
			(layers "B.Cu" "B.Mask" "B.Paste")
			(roundrect_rratio 0.25)
			(net 553 "/HDMI/HDMI_3V3")
			(pintype "passive")
		)
		(pad "2" smd roundrect
			(at 0.48 0 90)
			(size 0.59 0.64)
			(layers "B.Cu" "B.Mask" "B.Paste")
			(roundrect_rratio 0.25)
			(net 417 "GND")
			(pintype "passive")
		)
	)
	(footprint "antmicro-footprints:C_0402_1005Metric"
		(layer "B.Cu")
		(at 197.99 136.664 90)
		(descr "Capacitor SMD 0402")
		(tags "capacitor SMD 0402")
		(property "Reference" "C37"
			(at 4.564 -9.615 90)
			(layer "B.SilkS")
			(effects
				(font
					(size 0.7 0.7)
					(thickness 0.15)
				)
				(justify right bottom mirror)
			)
		)
		(property "Value" "C_100n_0402"
			(at -1.022927 -2.155213 90)
			(layer "B.Fab")
			(hide yes)
			(effects
				(font
					(size 0.7 0.7)
					(thickness 0.15)
				)
				(justify right bottom mirror)
			)
		)
		(property "Datasheet" "https://www.murata.com/products/productdetail?partno=GRM155R61H104KE14%23"
			(at 0 0 90)
			(layer "F.Fab")
			(hide yes)
			(effects
				(font
					(size 1.27 1.27)
					(thickness 0.15)
				)
			)
		)
		(property "Description" "SMD Multilayer Ceramic Capacitor, 0.1 µF, 50 V, 0402 [1005 Metric], ± 10%, X5R, GRM Series"
			(at 0 0 90)
			(layer "F.Fab")
			(hide yes)
			(effects
				(font
					(size 1.27 1.27)
					(thickness 0.15)
				)
			)
		)
		(property "Author" "Antmicro"
			(at 334.654 -61.326 0)
			(layer "B.Fab")
			(hide yes)
			(effects
				(font
					(size 1 1)
					(thickness 0.15)
				)
				(justify mirror)
			)
		)
		(property "Dielectric" "X5R"
			(at 334.654 -61.326 0)
			(layer "B.Fab")
			(hide yes)
			(effects
				(font
					(size 1 1)
					(thickness 0.15)
				)
				(justify mirror)
			)
		)
		(property "License" "Apache-2.0"
			(at 334.654 -61.326 0)
			(layer "B.Fab")
			(hide yes)
			(effects
				(font
					(size 1 1)
					(thickness 0.15)
				)
				(justify mirror)
			)
		)
		(property "MPN" "GRM155R61H104KE14D"
			(at 334.654 -61.326 0)
			(layer "B.Fab")
			(hide yes)
			(effects
				(font
					(size 1 1)
					(thickness 0.15)
				)
				(justify mirror)
			)
		)
		(property "Manufacturer" "Murata"
			(at 334.654 -61.326 0)
			(layer "B.Fab")
			(hide yes)
			(effects
				(font
					(size 1 1)
					(thickness 0.15)
				)
				(justify mirror)
			)
		)
		(property "Public" ""
			(at 334.654 -61.326 0)
			(layer "B.Fab")
			(hide yes)
			(effects
				(font
					(size 1 1)
					(thickness 0.15)
				)
				(justify mirror)
			)
		)
		(property "Val" "100n"
			(at 334.654 -61.326 0)
			(layer "B.Fab")
			(hide yes)
			(effects
				(font
					(size 1 1)
					(thickness 0.15)
				)
				(justify mirror)
			)
		)
		(property "Voltage" "50V"
			(at 334.654 -61.326 0)
			(layer "B.Fab")
			(hide yes)
			(effects
				(font
					(size 1 1)
					(thickness 0.15)
				)
				(justify mirror)
			)
		)
		(sheetname "/FPGA Supply/")
		(sheetfile "fpga-supply.kicad_sch")
		(attr smd)
		(fp_rect
			(start -0.925 0.47)
			(end 0.925 -0.47)
			(stroke
				(width 0.05)
				(type default)
			)
			(fill no)
			(layer "B.CrtYd")
		)
		(fp_line
			(start 0.504 -0.248)
			(end -0.494 -0.248)
			(stroke
				(width 0.15)
				(type solid)
			)
			(layer "B.Fab")
		)
		(fp_line
			(start -0.494 -0.248)
			(end -0.494 0.25)
			(stroke
				(width 0.15)
				(type solid)
			)
			(layer "B.Fab")
		)
		(fp_line
			(start 0.504 0.25)
			(end 0.504 -0.248)
			(stroke
				(width 0.15)
				(type solid)
			)
			(layer "B.Fab")
		)
		(fp_line
			(start -0.494 0.25)
			(end 0.504 0.25)
			(stroke
				(width 0.15)
				(type solid)
			)
			(layer "B.Fab")
		)
		(fp_text user "Author: Antmicro"
			(at -0.939 -3.399 270)
			(layer "B.Fab")
			(effects
				(font
					(size 0.7 0.7)
					(thickness 0.15)
				)
				(justify left bottom mirror)
			)
		)
		(fp_text user "${REFERENCE}"
			(at -0.939 -4.599 270)
			(layer "B.Fab")
			(effects
				(font
					(size 0.7 0.7)
					(thickness 0.15)
				)
				(justify left bottom mirror)
			)
		)
		(fp_text user "License: Apache-2.0"
			(at -0.939 -5.799 270)
			(layer "B.Fab")
			(effects
				(font
					(size 0.7 0.7)
					(thickness 0.15)
				)
				(justify left bottom mirror)
			)
		)
		(pad "1" smd roundrect
			(at -0.48 0 90)
			(size 0.59 0.64)
			(layers "B.Cu" "B.Mask" "B.Paste")
			(roundrect_rratio 0.25)
			(net 417 "GND")
			(pintype "passive")
		)
		(pad "2" smd roundrect
			(at 0.48 0 90)
			(size 0.59 0.64)
			(layers "B.Cu" "B.Mask" "B.Paste")
			(roundrect_rratio 0.25)
			(net 418 "+2V5")
			(pintype "passive")
		)
	)
	(footprint "antmicro-footprints:C_0402_1005Metric"
		(layer "B.Cu")
		(at 179.934359 147.659391 180)
		(descr "Capacitor SMD 0402")
		(tags "capacitor SMD 0402")
		(property "Reference" "C91"
			(at -1.805641 -1.450609 0)
			(layer "B.SilkS")
			(effects
				(font
					(size 0.7 0.7)
					(thickness 0.15)
				)
				(justify left bottom mirror)
			)
		)
		(property "Value" "C_22u_0402"
			(at -1.022927 -2.155213 0)
			(layer "B.Fab")
			(hide yes)
			(effects
				(font
					(size 0.7 0.7)
					(thickness 0.15)
				)
				(justify left bottom mirror)
			)
		)
		(property "Datasheet" "https://www.murata.com/products/productdetail?partno=GRM158R60J226ME01%23"
			(at 0 0 180)
			(layer "F.Fab")
			(hide yes)
			(effects
				(font
					(size 1.27 1.27)
					(thickness 0.15)
				)
			)
		)
		(property "Description" "SMD Multilayer Ceramic Capacitor, 22 uF, 4 V, 0402 [1005 Metric], X6S"
			(at 0 0 180)
			(layer "F.Fab")
			(hide yes)
			(effects
				(font
					(size 1.27 1.27)
					(thickness 0.15)
				)
			)
		)
		(property "Author" "Antmicro"
			(at 359.868718 295.318782 0)
			(layer "B.Fab")
			(hide yes)
			(effects
				(font
					(size 1 1)
					(thickness 0.15)
				)
				(justify mirror)
			)
		)
		(property "Dielectric" ""
			(at 359.868718 295.318782 0)
			(layer "B.Fab")
			(hide yes)
			(effects
				(font
					(size 1 1)
					(thickness 0.15)
				)
				(justify mirror)
			)
		)
		(property "License" "Apache-2.0"
			(at 359.868718 295.318782 0)
			(layer "B.Fab")
			(hide yes)
			(effects
				(font
					(size 1 1)
					(thickness 0.15)
				)
				(justify mirror)
			)
		)
		(property "MPN" "GRM158R60J226ME01D"
			(at 359.868718 295.318782 0)
			(layer "B.Fab")
			(hide yes)
			(effects
				(font
					(size 1 1)
					(thickness 0.15)
				)
				(justify mirror)
			)
		)
		(property "Manufacturer" "Murata"
			(at 359.868718 295.318782 0)
			(layer "B.Fab")
			(hide yes)
			(effects
				(font
					(size 1 1)
					(thickness 0.15)
				)
				(justify mirror)
			)
		)
		(property "Public" ""
			(at 359.868718 295.318782 0)
			(layer "B.Fab")
			(hide yes)
			(effects
				(font
					(size 1 1)
					(thickness 0.15)
				)
				(justify mirror)
			)
		)
		(property "Val" "22u"
			(at 359.868718 295.318782 0)
			(layer "B.Fab")
			(hide yes)
			(effects
				(font
					(size 1 1)
					(thickness 0.15)
				)
				(justify mirror)
			)
		)
		(property "Voltage" ""
			(at 359.868718 295.318782 0)
			(layer "B.Fab")
			(hide yes)
			(effects
				(font
					(size 1 1)
					(thickness 0.15)
				)
				(justify mirror)
			)
		)
		(sheetname "/Supply/")
		(sheetfile "supply.kicad_sch")
		(attr smd)
		(fp_rect
			(start -0.925 0.47)
			(end 0.925 -0.47)
			(stroke
				(width 0.05)
				(type default)
			)
			(fill no)
			(layer "B.CrtYd")
		)
		(fp_line
			(start 0.504 0.25)
			(end 0.504 -0.248)
			(stroke
				(width 0.15)
				(type solid)
			)
			(layer "B.Fab")
		)
		(fp_line
			(start 0.504 -0.248)
			(end -0.494 -0.248)
			(stroke
				(width 0.15)
				(type solid)
			)
			(layer "B.Fab")
		)
		(fp_line
			(start -0.494 0.25)
			(end 0.504 0.25)
			(stroke
				(width 0.15)
				(type solid)
			)
			(layer "B.Fab")
		)
		(fp_line
			(start -0.494 -0.248)
			(end -0.494 0.25)
			(stroke
				(width 0.15)
				(type solid)
			)
			(layer "B.Fab")
		)
		(fp_text user "${REFERENCE}"
			(at -0.939 -4.599 0)
			(layer "B.Fab")
			(effects
				(font
					(size 0.7 0.7)
					(thickness 0.15)
				)
				(justify left bottom mirror)
			)
		)
		(fp_text user "License: Apache-2.0"
			(at -0.939 -5.799 0)
			(layer "B.Fab")
			(effects
				(font
					(size 0.7 0.7)
					(thickness 0.15)
				)
				(justify left bottom mirror)
			)
		)
		(fp_text user "Author: Antmicro"
			(at -0.939 -3.399 0)
			(layer "B.Fab")
			(effects
				(font
					(size 0.7 0.7)
					(thickness 0.15)
				)
				(justify left bottom mirror)
			)
		)
		(pad "1" smd roundrect
			(at -0.48 0 180)
			(size 0.59 0.64)
			(layers "B.Cu" "B.Mask" "B.Paste")
			(roundrect_rratio 0.25)
			(net 417 "GND")
			(pintype "passive")
		)
		(pad "2" smd roundrect
			(at 0.48 0 180)
			(size 0.59 0.64)
			(layers "B.Cu" "B.Mask" "B.Paste")
			(roundrect_rratio 0.25)
			(net 90 "+5V")
			(pintype "passive")
		)
	)
	(footprint "antmicro-footprints:R_0402_1005Metric"
		(layer "B.Cu")
		(at 212.6425 126.812 -90)
		(descr "Resistor SMD 0402")
		(tags "resistor SMD 0402")
		(property "Reference" "R35"
			(at 0.688 -0.3825 90)
			(layer "B.SilkS")
			(effects
				(font
					(size 0.7 0.7)
					(thickness 0.15)
				)
				(justify left bottom mirror)
			)
		)
		(property "Value" "R_49k9_0402"
			(at -1.011843 -1.772047 90)
			(layer "B.Fab")
			(hide yes)
			(effects
				(font
					(size 0.7 0.7)
					(thickness 0.15)
				)
				(justify left bottom mirror)
			)
		)
		(property "Datasheet" "https://www.bourns.com/docs/product-datasheets/cr.pdf"
			(at 0 0 270)
			(layer "F.Fab")
			(hide yes)
			(effects
				(font
					(size 1.27 1.27)
					(thickness 0.15)
				)
			)
		)
		(property "Description" "SMD Chip Resistor, 49.9 kohm, ± 1%, 63 mW, 0402 [1005 Metric], Thick Film, General Purpose"
			(at 0 0 270)
			(layer "F.Fab")
			(hide yes)
			(effects
				(font
					(size 1.27 1.27)
					(thickness 0.15)
				)
			)
		)
		(property "Author" "Antmicro"
			(at 85.8305 339.4545 0)
			(layer "B.Fab")
			(hide yes)
			(effects
				(font
					(size 1 1)
					(thickness 0.15)
				)
				(justify mirror)
			)
		)
		(property "License" "Apache-2.0"
			(at 85.8305 339.4545 0)
			(layer "B.Fab")
			(hide yes)
			(effects
				(font
					(size 1 1)
					(thickness 0.15)
				)
				(justify mirror)
			)
		)
		(property "MPN" "CR0402-FX-4992GLF"
			(at 85.8305 339.4545 0)
			(layer "B.Fab")
			(hide yes)
			(effects
				(font
					(size 1 1)
					(thickness 0.15)
				)
				(justify mirror)
			)
		)
		(property "Manufacturer" "Bourns"
			(at 85.8305 339.4545 0)
			(layer "B.Fab")
			(hide yes)
			(effects
				(font
					(size 1 1)
					(thickness 0.15)
				)
				(justify mirror)
			)
		)
		(property "Public" ""
			(at 85.8305 339.4545 0)
			(layer "B.Fab")
			(hide yes)
			(effects
				(font
					(size 1 1)
					(thickness 0.15)
				)
				(justify mirror)
			)
		)
		(property "Tolerance" "1%"
			(at 85.8305 339.4545 0)
			(layer "B.Fab")
			(hide yes)
			(effects
				(font
					(size 1 1)
					(thickness 0.15)
				)
				(justify mirror)
			)
		)
		(property "Val" "49k9"
			(at 85.8305 339.4545 0)
			(layer "B.Fab")
			(hide yes)
			(effects
				(font
					(size 1 1)
					(thickness 0.15)
				)
				(justify mirror)
			)
		)
		(sheetname "/Memory/")
		(sheetfile "memory.kicad_sch")
		(attr smd)
		(fp_rect
			(start -0.925 0.47)
			(end 0.925 -0.47)
			(stroke
				(width 0.05)
				(type default)
			)
			(fill no)
			(layer "B.CrtYd")
		)
		(fp_rect
			(start -0.5 0.25)
			(end 0.5 -0.25)
			(stroke
				(width 0.15)
				(type solid)
			)
			(fill no)
			(layer "B.Fab")
		)
		(fp_text user "Author: Antmicro"
			(at -0.95 -4.169 90)
			(layer "B.Fab")
			(effects
				(font
					(size 0.7 0.7)
					(thickness 0.15)
				)
				(justify left bottom mirror)
			)
		)
		(fp_text user "License: Apache-2.0"
			(at -0.95 -5.169 90)
			(layer "B.Fab")
			(effects
				(font
					(size 0.7 0.7)
					(thickness 0.15)
				)
				(justify left bottom mirror)
			)
		)
		(fp_text user "${REFERENCE}"
			(at -0.95 -3.168 90)
			(layer "B.Fab")
			(effects
				(font
					(size 0.7 0.7)
					(thickness 0.15)
				)
				(justify left bottom mirror)
			)
		)
		(pad "1" smd roundrect
			(at -0.48 0 270)
			(size 0.59 0.64)
			(layers "B.Cu" "B.Mask" "B.Paste")
			(roundrect_rratio 0.25)
			(net 207 "/FPGA MSSIO/EMMC.DAT3")
			(pintype "passive")
		)
		(pad "2" smd roundrect
			(at 0.48 0 270)
			(size 0.59 0.64)
			(layers "B.Cu" "B.Mask" "B.Paste")
			(roundrect_rratio 0.25)
			(net 137 "SD_VDD")
			(pintype "passive")
		)
	)
	(footprint "antmicro-footprints:C_0402_1005Metric"
		(layer "B.Cu")
		(at 177.625 122.5)
		(descr "Capacitor SMD 0402")
		(tags "capacitor SMD 0402")
		(property "Reference" "C154"
			(at -0.925 -0.58 0)
			(layer "B.SilkS")
			(effects
				(font
					(size 0.7 0.7)
					(thickness 0.15)
				)
				(justify right bottom mirror)
			)
		)
		(property "Value" "C_1u_0402"
			(at -1.022927 -2.155213 0)
			(layer "B.Fab")
			(hide yes)
			(effects
				(font
					(size 0.7 0.7)
					(thickness 0.15)
				)
				(justify right bottom mirror)
			)
		)
		(property "Datasheet" "https://product.tdk.com/en/search/capacitor/ceramic/mlcc/info?part_no=C1005X6S1A105K050BC"
			(at 0 0 0)
			(layer "F.Fab")
			(hide yes)
			(effects
				(font
					(size 1.27 1.27)
					(thickness 0.15)
				)
			)
		)
		(property "Description" "SMD Multilayer Ceramic Capacitor, 1 µF, 10 V, 0402 [1005 Metric], ± 10%, X6S, C"
			(at 0 0 0)
			(layer "F.Fab")
			(hide yes)
			(effects
				(font
					(size 1.27 1.27)
					(thickness 0.15)
				)
			)
		)
		(property "Author" "Antmicro"
			(at 0 0 0)
			(layer "B.Fab")
			(hide yes)
			(effects
				(font
					(size 1 1)
					(thickness 0.15)
				)
				(justify mirror)
			)
		)
		(property "Dielectric" "X5R"
			(at 0 0 0)
			(layer "B.Fab")
			(hide yes)
			(effects
				(font
					(size 1 1)
					(thickness 0.15)
				)
				(justify mirror)
			)
		)
		(property "License" "Apache-2.0"
			(at 0 0 0)
			(layer "B.Fab")
			(hide yes)
			(effects
				(font
					(size 1 1)
					(thickness 0.15)
				)
				(justify mirror)
			)
		)
		(property "MPN" "C1005X6S1A105K050BC"
			(at 0 0 0)
			(layer "B.Fab")
			(hide yes)
			(effects
				(font
					(size 1 1)
					(thickness 0.15)
				)
				(justify mirror)
			)
		)
		(property "Manufacturer" "TDK"
			(at 0 0 0)
			(layer "B.Fab")
			(hide yes)
			(effects
				(font
					(size 1 1)
					(thickness 0.15)
				)
				(justify mirror)
			)
		)
		(property "Public" ""
			(at 0 0 0)
			(layer "B.Fab")
			(hide yes)
			(effects
				(font
					(size 1 1)
					(thickness 0.15)
				)
				(justify mirror)
			)
		)
		(property "Val" "1u"
			(at 0 0 0)
			(layer "B.Fab")
			(hide yes)
			(effects
				(font
					(size 1 1)
					(thickness 0.15)
				)
				(justify mirror)
			)
		)
		(property "Voltage" "16V"
			(at 0 0 0)
			(layer "B.Fab")
			(hide yes)
			(effects
				(font
					(size 1 1)
					(thickness 0.15)
				)
				(justify mirror)
			)
		)
		(sheetname "/LPDDR4/")
		(sheetfile "lpddr.kicad_sch")
		(attr smd)
		(fp_rect
			(start -0.925 0.47)
			(end 0.925 -0.47)
			(stroke
				(width 0.05)
				(type default)
			)
			(fill no)
			(layer "B.CrtYd")
		)
		(fp_line
			(start -0.494 -0.248)
			(end -0.494 0.25)
			(stroke
				(width 0.15)
				(type solid)
			)
			(layer "B.Fab")
		)
		(fp_line
			(start -0.494 0.25)
			(end 0.504 0.25)
			(stroke
				(width 0.15)
				(type solid)
			)
			(layer "B.Fab")
		)
		(fp_line
			(start 0.504 -0.248)
			(end -0.494 -0.248)
			(stroke
				(width 0.15)
				(type solid)
			)
			(layer "B.Fab")
		)
		(fp_line
			(start 0.504 0.25)
			(end 0.504 -0.248)
			(stroke
				(width 0.15)
				(type solid)
			)
			(layer "B.Fab")
		)
		(fp_text user "License: Apache-2.0"
			(at -0.939 -5.799 180)
			(layer "B.Fab")
			(effects
				(font
					(size 0.7 0.7)
					(thickness 0.15)
				)
				(justify left bottom mirror)
			)
		)
		(fp_text user "Author: Antmicro"
			(at -0.939 -3.399 180)
			(layer "B.Fab")
			(effects
				(font
					(size 0.7 0.7)
					(thickness 0.15)
				)
				(justify left bottom mirror)
			)
		)
		(fp_text user "${REFERENCE}"
			(at -0.939 -4.599 180)
			(layer "B.Fab")
			(effects
				(font
					(size 0.7 0.7)
					(thickness 0.15)
				)
				(justify left bottom mirror)
			)
		)
		(pad "1" smd roundrect
			(at -0.48 0)
			(size 0.59 0.64)
			(layers "B.Cu" "B.Mask" "B.Paste")
			(roundrect_rratio 0.25)
			(net 417 "GND")
			(pintype "passive")
		)
		(pad "2" smd roundrect
			(at 0.48 0)
			(size 0.59 0.64)
			(layers "B.Cu" "B.Mask" "B.Paste")
			(roundrect_rratio 0.25)
			(net 2 "+1V1")
			(pintype "passive")
		)
	)
	(footprint "antmicro-footprints:C_0402_1005Metric"
		(layer "B.Cu")
		(at 179.1 142.8875)
		(descr "Capacitor SMD 0402")
		(tags "capacitor SMD 0402")
		(property "Reference" "C87"
			(at -1.275 -0.4875 0)
			(layer "B.SilkS")
			(effects
				(font
					(size 0.7 0.7)
					(thickness 0.15)
				)
				(justify right bottom mirror)
			)
		)
		(property "Value" "C_22u_0402"
			(at -1.022927 -2.155213 0)
			(layer "B.Fab")
			(hide yes)
			(effects
				(font
					(size 0.7 0.7)
					(thickness 0.15)
				)
				(justify right bottom mirror)
			)
		)
		(property "Datasheet" "https://www.murata.com/products/productdetail?partno=GRM158R60J226ME01%23"
			(at 0 0 0)
			(layer "F.Fab")
			(hide yes)
			(effects
				(font
					(size 1.27 1.27)
					(thickness 0.15)
				)
			)
		)
		(property "Description" "SMD Multilayer Ceramic Capacitor, 22 uF, 4 V, 0402 [1005 Metric], X6S"
			(at 0 0 0)
			(layer "F.Fab")
			(hide yes)
			(effects
				(font
					(size 1.27 1.27)
					(thickness 0.15)
				)
			)
		)
		(property "Author" "Antmicro"
			(at 0 0 0)
			(layer "B.Fab")
			(hide yes)
			(effects
				(font
					(size 1 1)
					(thickness 0.15)
				)
				(justify mirror)
			)
		)
		(property "Dielectric" ""
			(at 0 0 0)
			(layer "B.Fab")
			(hide yes)
			(effects
				(font
					(size 1 1)
					(thickness 0.15)
				)
				(justify mirror)
			)
		)
		(property "License" "Apache-2.0"
			(at 0 0 0)
			(layer "B.Fab")
			(hide yes)
			(effects
				(font
					(size 1 1)
					(thickness 0.15)
				)
				(justify mirror)
			)
		)
		(property "MPN" "GRM158R60J226ME01D"
			(at 0 0 0)
			(layer "B.Fab")
			(hide yes)
			(effects
				(font
					(size 1 1)
					(thickness 0.15)
				)
				(justify mirror)
			)
		)
		(property "Manufacturer" "Murata"
			(at 0 0 0)
			(layer "B.Fab")
			(hide yes)
			(effects
				(font
					(size 1 1)
					(thickness 0.15)
				)
				(justify mirror)
			)
		)
		(property "Public" ""
			(at 0 0 0)
			(layer "B.Fab")
			(hide yes)
			(effects
				(font
					(size 1 1)
					(thickness 0.15)
				)
				(justify mirror)
			)
		)
		(property "Val" "22u"
			(at 0 0 0)
			(layer "B.Fab")
			(hide yes)
			(effects
				(font
					(size 1 1)
					(thickness 0.15)
				)
				(justify mirror)
			)
		)
		(property "Voltage" ""
			(at 0 0 0)
			(layer "B.Fab")
			(hide yes)
			(effects
				(font
					(size 1 1)
					(thickness 0.15)
				)
				(justify mirror)
			)
		)
		(sheetname "/Supply/")
		(sheetfile "supply.kicad_sch")
		(attr smd)
		(fp_rect
			(start -0.925 0.47)
			(end 0.925 -0.47)
			(stroke
				(width 0.05)
				(type default)
			)
			(fill no)
			(layer "B.CrtYd")
		)
		(fp_line
			(start -0.494 -0.248)
			(end -0.494 0.25)
			(stroke
				(width 0.15)
				(type solid)
			)
			(layer "B.Fab")
		)
		(fp_line
			(start -0.494 0.25)
			(end 0.504 0.25)
			(stroke
				(width 0.15)
				(type solid)
			)
			(layer "B.Fab")
		)
		(fp_line
			(start 0.504 -0.248)
			(end -0.494 -0.248)
			(stroke
				(width 0.15)
				(type solid)
			)
			(layer "B.Fab")
		)
		(fp_line
			(start 0.504 0.25)
			(end 0.504 -0.248)
			(stroke
				(width 0.15)
				(type solid)
			)
			(layer "B.Fab")
		)
		(fp_text user "Author: Antmicro"
			(at -0.939 -3.399 180)
			(layer "B.Fab")
			(effects
				(font
					(size 0.7 0.7)
					(thickness 0.15)
				)
				(justify left bottom mirror)
			)
		)
		(fp_text user "${REFERENCE}"
			(at -0.939 -4.599 180)
			(layer "B.Fab")
			(effects
				(font
					(size 0.7 0.7)
					(thickness 0.15)
				)
				(justify left bottom mirror)
			)
		)
		(fp_text user "License: Apache-2.0"
			(at -0.939 -5.799 180)
			(layer "B.Fab")
			(effects
				(font
					(size 0.7 0.7)
					(thickness 0.15)
				)
				(justify left bottom mirror)
			)
		)
		(pad "1" smd roundrect
			(at -0.48 0)
			(size 0.59 0.64)
			(layers "B.Cu" "B.Mask" "B.Paste")
			(roundrect_rratio 0.25)
			(net 417 "GND")
			(pintype "passive")
		)
		(pad "2" smd roundrect
			(at 0.48 0)
			(size 0.59 0.64)
			(layers "B.Cu" "B.Mask" "B.Paste")
			(roundrect_rratio 0.25)
			(net 90 "+5V")
			(pintype "passive")
		)
	)
	(footprint "antmicro-footprints:C_0402_1005Metric"
		(layer "B.Cu")
		(at 181.1 142.8875 180)
		(descr "Capacitor SMD 0402")
		(tags "capacitor SMD 0402")
		(property "Reference" "C90"
			(at -1.175 0.4875 180)
			(layer "B.SilkS")
			(effects
				(font
					(size 0.7 0.7)
					(thickness 0.15)
				)
				(justify left bottom mirror)
			)
		)
		(property "Value" "C_22u_0402"
			(at -1.022927 -2.155213 0)
			(layer "B.Fab")
			(hide yes)
			(effects
				(font
					(size 0.7 0.7)
					(thickness 0.15)
				)
				(justify left bottom mirror)
			)
		)
		(property "Datasheet" "https://www.murata.com/products/productdetail?partno=GRM158R60J226ME01%23"
			(at 0 0 180)
			(layer "F.Fab")
			(hide yes)
			(effects
				(font
					(size 1.27 1.27)
					(thickness 0.15)
				)
			)
		)
		(property "Description" "SMD Multilayer Ceramic Capacitor, 22 uF, 4 V, 0402 [1005 Metric], X6S"
			(at 0 0 180)
			(layer "F.Fab")
			(hide yes)
			(effects
				(font
					(size 1.27 1.27)
					(thickness 0.15)
				)
			)
		)
		(property "Author" "Antmicro"
			(at 362.2 285.775 0)
			(layer "B.Fab")
			(hide yes)
			(effects
				(font
					(size 1 1)
					(thickness 0.15)
				)
				(justify mirror)
			)
		)
		(property "Dielectric" ""
			(at 362.2 285.775 0)
			(layer "B.Fab")
			(hide yes)
			(effects
				(font
					(size 1 1)
					(thickness 0.15)
				)
				(justify mirror)
			)
		)
		(property "License" "Apache-2.0"
			(at 362.2 285.775 0)
			(layer "B.Fab")
			(hide yes)
			(effects
				(font
					(size 1 1)
					(thickness 0.15)
				)
				(justify mirror)
			)
		)
		(property "MPN" "GRM158R60J226ME01D"
			(at 362.2 285.775 0)
			(layer "B.Fab")
			(hide yes)
			(effects
				(font
					(size 1 1)
					(thickness 0.15)
				)
				(justify mirror)
			)
		)
		(property "Manufacturer" "Murata"
			(at 362.2 285.775 0)
			(layer "B.Fab")
			(hide yes)
			(effects
				(font
					(size 1 1)
					(thickness 0.15)
				)
				(justify mirror)
			)
		)
		(property "Public" ""
			(at 362.2 285.775 0)
			(layer "B.Fab")
			(hide yes)
			(effects
				(font
					(size 1 1)
					(thickness 0.15)
				)
				(justify mirror)
			)
		)
		(property "Val" "22u"
			(at 362.2 285.775 0)
			(layer "B.Fab")
			(hide yes)
			(effects
				(font
					(size 1 1)
					(thickness 0.15)
				)
				(justify mirror)
			)
		)
		(property "Voltage" ""
			(at 362.2 285.775 0)
			(layer "B.Fab")
			(hide yes)
			(effects
				(font
					(size 1 1)
					(thickness 0.15)
				)
				(justify mirror)
			)
		)
		(sheetname "/Supply/")
		(sheetfile "supply.kicad_sch")
		(attr smd)
		(fp_rect
			(start -0.925 0.47)
			(end 0.925 -0.47)
			(stroke
				(width 0.05)
				(type default)
			)
			(fill no)
			(layer "B.CrtYd")
		)
		(fp_line
			(start 0.504 0.25)
			(end 0.504 -0.248)
			(stroke
				(width 0.15)
				(type solid)
			)
			(layer "B.Fab")
		)
		(fp_line
			(start 0.504 -0.248)
			(end -0.494 -0.248)
			(stroke
				(width 0.15)
				(type solid)
			)
			(layer "B.Fab")
		)
		(fp_line
			(start -0.494 0.25)
			(end 0.504 0.25)
			(stroke
				(width 0.15)
				(type solid)
			)
			(layer "B.Fab")
		)
		(fp_line
			(start -0.494 -0.248)
			(end -0.494 0.25)
			(stroke
				(width 0.15)
				(type solid)
			)
			(layer "B.Fab")
		)
		(fp_text user "${REFERENCE}"
			(at -0.939 -4.599 0)
			(layer "B.Fab")
			(effects
				(font
					(size 0.7 0.7)
					(thickness 0.15)
				)
				(justify left bottom mirror)
			)
		)
		(fp_text user "License: Apache-2.0"
			(at -0.939 -5.799 0)
			(layer "B.Fab")
			(effects
				(font
					(size 0.7 0.7)
					(thickness 0.15)
				)
				(justify left bottom mirror)
			)
		)
		(fp_text user "Author: Antmicro"
			(at -0.939 -3.399 0)
			(layer "B.Fab")
			(effects
				(font
					(size 0.7 0.7)
					(thickness 0.15)
				)
				(justify left bottom mirror)
			)
		)
		(pad "1" smd roundrect
			(at -0.48 0 180)
			(size 0.59 0.64)
			(layers "B.Cu" "B.Mask" "B.Paste")
			(roundrect_rratio 0.25)
			(net 417 "GND")
			(pintype "passive")
		)
		(pad "2" smd roundrect
			(at 0.48 0 180)
			(size 0.59 0.64)
			(layers "B.Cu" "B.Mask" "B.Paste")
			(roundrect_rratio 0.25)
			(net 90 "+5V")
			(pintype "passive")
		)
	)
	(footprint "antmicro-footprints:R_0402_1005Metric"
		(layer "B.Cu")
		(at 183.425 132.175)
		(descr "Resistor SMD 0402")
		(tags "resistor SMD 0402")
		(property "Reference" "R104"
			(at -0.815 -0.505 0)
			(layer "B.SilkS")
			(effects
				(font
					(size 0.7 0.7)
					(thickness 0.15)
				)
				(justify right bottom mirror)
			)
		)
		(property "Value" "R_10k_0402"
			(at -1.011843 -1.772047 0)
			(layer "B.Fab")
			(hide yes)
			(effects
				(font
					(size 0.7 0.7)
					(thickness 0.15)
				)
				(justify right bottom mirror)
			)
		)
		(property "Datasheet" "https://www.bourns.com/docs/product-datasheets/cr.pdf"
			(at 0 0 0)
			(layer "F.Fab")
			(hide yes)
			(effects
				(font
					(size 1.27 1.27)
					(thickness 0.15)
				)
			)
		)
		(property "Description" "SMD Chip Resistor, 10 kohm, ± 1%, 62.5 mW, 0402 [1005 Metric], Thick Film, General Purpose"
			(at 0 0 0)
			(layer "F.Fab")
			(hide yes)
			(effects
				(font
					(size 1.27 1.27)
					(thickness 0.15)
				)
			)
		)
		(property "Author" "Antmicro"
			(at 0 0 0)
			(layer "B.Fab")
			(hide yes)
			(effects
				(font
					(size 1 1)
					(thickness 0.15)
				)
				(justify mirror)
			)
		)
		(property "License" "Apache-2.0"
			(at 0 0 0)
			(layer "B.Fab")
			(hide yes)
			(effects
				(font
					(size 1 1)
					(thickness 0.15)
				)
				(justify mirror)
			)
		)
		(property "MPN" "CR0402-FX-1002GLF"
			(at 0 0 0)
			(layer "B.Fab")
			(hide yes)
			(effects
				(font
					(size 1 1)
					(thickness 0.15)
				)
				(justify mirror)
			)
		)
		(property "Manufacturer" "Bourns"
			(at 0 0 0)
			(layer "B.Fab")
			(hide yes)
			(effects
				(font
					(size 1 1)
					(thickness 0.15)
				)
				(justify mirror)
			)
		)
		(property "Public" ""
			(at 0 0 0)
			(layer "B.Fab")
			(hide yes)
			(effects
				(font
					(size 1 1)
					(thickness 0.15)
				)
				(justify mirror)
			)
		)
		(property "Tolerance" "1%"
			(at 0 0 0)
			(layer "B.Fab")
			(hide yes)
			(effects
				(font
					(size 1 1)
					(thickness 0.15)
				)
				(justify mirror)
			)
		)
		(property "Val" "10k"
			(at 0 0 0)
			(layer "B.Fab")
			(hide yes)
			(effects
				(font
					(size 1 1)
					(thickness 0.15)
				)
				(justify mirror)
			)
		)
		(sheetname "/LPDDR4/")
		(sheetfile "lpddr.kicad_sch")
		(attr smd)
		(fp_rect
			(start -0.925 0.47)
			(end 0.925 -0.47)
			(stroke
				(width 0.05)
				(type default)
			)
			(fill no)
			(layer "B.CrtYd")
		)
		(fp_rect
			(start -0.5 0.25)
			(end 0.5 -0.25)
			(stroke
				(width 0.15)
				(type solid)
			)
			(fill no)
			(layer "B.Fab")
		)
		(fp_text user "License: Apache-2.0"
			(at -0.95 -5.169 180)
			(layer "B.Fab")
			(effects
				(font
					(size 0.7 0.7)
					(thickness 0.15)
				)
				(justify left bottom mirror)
			)
		)
		(fp_text user "${REFERENCE}"
			(at -0.95 -3.168 180)
			(layer "B.Fab")
			(effects
				(font
					(size 0.7 0.7)
					(thickness 0.15)
				)
				(justify left bottom mirror)
			)
		)
		(fp_text user "Author: Antmicro"
			(at -0.95 -4.169 180)
			(layer "B.Fab")
			(effects
				(font
					(size 0.7 0.7)
					(thickness 0.15)
				)
				(justify left bottom mirror)
			)
		)
		(pad "1" smd roundrect
			(at -0.48 0)
			(size 0.59 0.64)
			(layers "B.Cu" "B.Mask" "B.Paste")
			(roundrect_rratio 0.25)
			(net 417 "GND")
			(pintype "passive")
		)
		(pad "2" smd roundrect
			(at 0.48 0)
			(size 0.59 0.64)
			(layers "B.Cu" "B.Mask" "B.Paste")
			(roundrect_rratio 0.25)
			(net 394 "/FPGA MSS/LPDDR4.RESET_n")
			(pintype "passive")
		)
	)
	(footprint "antmicro-footprints:C_0603_1608Metric"
		(layer "B.Cu")
		(at 196.45 129.1)
		(descr "Capacitor SMD 0603")
		(tags "capacitor 0603")
		(property "Reference" "C262"
			(at -2.45 -0.8 0)
			(layer "B.SilkS")
			(effects
				(font
					(size 0.7 0.7)
					(thickness 0.15)
				)
				(justify right bottom mirror)
			)
		)
		(property "Value" "C_47u_0603"
			(at -1.42757 -1.770288 0)
			(layer "B.Fab")
			(hide yes)
			(effects
				(font
					(size 0.7 0.7)
					(thickness 0.15)
				)
				(justify right bottom mirror)
			)
		)
		(property "Datasheet" "https://www.murata.com/products/productdetail?partno=GRM188R60J476ME15%23"
			(at 0 0 0)
			(layer "F.Fab")
			(hide yes)
			(effects
				(font
					(size 1.27 1.27)
					(thickness 0.15)
				)
			)
		)
		(property "Description" "SMD Multilayer Ceramic Capacitor, 47 µF, 6.3 V, 0603 [1608 Metric], ± 20%, X5R, GRM Series"
			(at 0 0 0)
			(layer "F.Fab")
			(hide yes)
			(effects
				(font
					(size 1.27 1.27)
					(thickness 0.15)
				)
			)
		)
		(property "Author" "Antmicro"
			(at 0 0 0)
			(layer "B.Fab")
			(hide yes)
			(effects
				(font
					(size 1 1)
					(thickness 0.15)
				)
				(justify mirror)
			)
		)
		(property "Capacitance" "47u"
			(at 0 0 0)
			(layer "B.Fab")
			(hide yes)
			(effects
				(font
					(size 1 1)
					(thickness 0.15)
				)
				(justify mirror)
			)
		)
		(property "Dielectric" "X7R"
			(at 0 0 0)
			(layer "B.Fab")
			(hide yes)
			(effects
				(font
					(size 1 1)
					(thickness 0.15)
				)
				(justify mirror)
			)
		)
		(property "License" "Apache-2.0"
			(at 0 0 0)
			(layer "B.Fab")
			(hide yes)
			(effects
				(font
					(size 1 1)
					(thickness 0.15)
				)
				(justify mirror)
			)
		)
		(property "MPN" "GRM188R60J476ME15D"
			(at 0 0 0)
			(layer "B.Fab")
			(hide yes)
			(effects
				(font
					(size 1 1)
					(thickness 0.15)
				)
				(justify mirror)
			)
		)
		(property "Manufacturer" "Murata"
			(at 0 0 0)
			(layer "B.Fab")
			(hide yes)
			(effects
				(font
					(size 1 1)
					(thickness 0.15)
				)
				(justify mirror)
			)
		)
		(property "Public" ""
			(at 0 0 0)
			(layer "B.Fab")
			(hide yes)
			(effects
				(font
					(size 1 1)
					(thickness 0.15)
				)
				(justify mirror)
			)
		)
		(property "Val" "47u"
			(at 0 0 0)
			(layer "B.Fab")
			(hide yes)
			(effects
				(font
					(size 1 1)
					(thickness 0.15)
				)
				(justify mirror)
			)
		)
		(property "Voltage" "50V"
			(at 0 0 0)
			(layer "B.Fab")
			(hide yes)
			(effects
				(font
					(size 1 1)
					(thickness 0.15)
				)
				(justify mirror)
			)
		)
		(sheetname "/FPGA Supply/")
		(sheetfile "fpga-supply.kicad_sch")
		(attr smd)
		(fp_line
			(start -0.15 -0.4)
			(end 0.15 -0.4)
			(stroke
				(width 0.15)
				(type solid)
			)
			(layer "B.SilkS")
		)
		(fp_line
			(start -0.15 0.4)
			(end 0.15 0.4)
			(stroke
				(width 0.15)
				(type solid)
			)
			(layer "B.SilkS")
		)
		(fp_rect
			(start -1.25 0.65)
			(end 1.25 -0.65)
			(stroke
				(width 0.05)
				(type solid)
			)
			(fill no)
			(layer "B.CrtYd")
		)
		(fp_rect
			(start -0.8 0.4)
			(end 0.8 -0.4)
			(stroke
				(width 0.15)
				(type solid)
			)
			(fill no)
			(layer "B.Fab")
		)
		(fp_text user "Author: Antmicro"
			(at -1.682 -4.894 180)
			(layer "B.Fab")
			(effects
				(font
					(size 0.7 0.7)
					(thickness 0.15)
				)
				(justify left bottom mirror)
			)
		)
		(fp_text user "${REFERENCE}"
			(at -1.682 -3.895 180)
			(layer "B.Fab")
			(effects
				(font
					(size 0.7 0.7)
					(thickness 0.15)
				)
				(justify left bottom mirror)
			)
		)
		(fp_text user "License: Apache-2.0"
			(at -1.682 -5.895 180)
			(layer "B.Fab")
			(effects
				(font
					(size 0.7 0.7)
					(thickness 0.15)
				)
				(justify left bottom mirror)
			)
		)
		(pad "1" smd roundrect
			(at -0.7 0)
			(size 0.8 1)
			(layers "B.Cu" "B.Mask" "B.Paste")
			(roundrect_rratio 0.2)
			(net 417 "GND")
			(pintype "passive")
		)
		(pad "2" smd roundrect
			(at 0.7 0)
			(size 0.8 1)
			(layers "B.Cu" "B.Mask" "B.Paste")
			(roundrect_rratio 0.2)
			(net 49 "VDDAUX")
			(pintype "passive")
		)
	)
	(footprint "antmicro-footprints:TP_SMD_0.75mm"
		(layer "B.Cu")
		(at 203 123.1 180)
		(property "Reference" "TP25"
			(at 0.47 1.01 180)
			(layer "B.SilkS")
			(hide yes)
			(effects
				(font
					(size 0.65 0.65)
					(thickness 0.15)
				)
				(justify left bottom mirror)
			)
		)
		(property "Value" "TP_0.75mm_SMD"
			(at 0 -1.2 0)
			(layer "B.Fab")
			(hide yes)
			(effects
				(font
					(size 0.7 0.7)
					(thickness 0.15)
				)
				(justify left bottom mirror)
			)
		)
		(property "Description" "SMT test point"
			(at 0 0 0)
			(layer "B.Fab")
			(hide yes)
			(effects
				(font
					(size 1.27 1.27)
					(thickness 0.15)
				)
				(justify mirror)
			)
		)
		(property "MPN" ""
			(at 0 0 0)
			(unlocked yes)
			(layer "B.Fab")
			(hide yes)
			(effects
				(font
					(size 1 1)
					(thickness 0.15)
				)
				(justify mirror)
			)
		)
		(property "Manufacturer" ""
			(at 0 0 0)
			(unlocked yes)
			(layer "B.Fab")
			(hide yes)
			(effects
				(font
					(size 1 1)
					(thickness 0.15)
				)
				(justify mirror)
			)
		)
		(property "Author" "Antmicro"
			(at 0 0 0)
			(unlocked yes)
			(layer "B.Fab")
			(hide yes)
			(effects
				(font
					(size 1 1)
					(thickness 0.15)
				)
				(justify mirror)
			)
		)
		(property "License" "Apache-2.0"
			(at 0 0 0)
			(unlocked yes)
			(layer "B.Fab")
			(hide yes)
			(effects
				(font
					(size 1 1)
					(thickness 0.15)
				)
				(justify mirror)
			)
		)
		(property "Public" "False"
			(at 0 0 0)
			(unlocked yes)
			(layer "B.Fab")
			(hide yes)
			(effects
				(font
					(size 1 1)
					(thickness 0.15)
				)
				(justify mirror)
			)
		)
		(sheetname "/Supply/")
		(sheetfile "supply.kicad_sch")
		(attr exclude_from_pos_files exclude_from_bom)
		(fp_circle
			(center 0 0)
			(end 0.475 0)
			(stroke
				(width 0.05)
				(type default)
			)
			(fill no)
			(layer "B.CrtYd")
		)
		(fp_text user "License: Apache-2.0"
			(at -0.4 -5.101 0)
			(layer "B.Fab")
			(effects
				(font
					(size 0.7 0.7)
					(thickness 0.15)
				)
				(justify left bottom mirror)
			)
		)
		(fp_text user "Author: Antmicro"
			(at -0.4 -3.901 0)
			(layer "B.Fab")
			(effects
				(font
					(size 0.7 0.7)
					(thickness 0.15)
				)
				(justify left bottom mirror)
			)
		)
		(fp_text user "${REFERENCE}"
			(at -0.4 -2.7 0)
			(layer "B.Fab")
			(effects
				(font
					(size 0.7 0.7)
					(thickness 0.15)
				)
				(justify left bottom mirror)
			)
		)
		(pad "1" smd circle
			(at 0 0 180)
			(size 0.75 0.75)
			(layers "B.Cu" "B.Mask")
			(net 92 "/FPGA MSSIO/SUPPLY.SCL")
			(pinfunction "1")
			(pintype "passive")
		)
	)
	(footprint "antmicro-footprints:C_0402_1005Metric"
		(layer "B.Cu")
		(at 194.85 146.75 90)
		(descr "Capacitor SMD 0402")
		(tags "capacitor SMD 0402")
		(property "Reference" "C188"
			(at -3.65 0.1 90)
			(layer "B.SilkS")
			(effects
				(font
					(size 0.7 0.7)
					(thickness 0.15)
				)
				(justify right bottom mirror)
			)
		)
		(property "Value" "C_10u_10V_0402"
			(at -1.022927 -2.155213 90)
			(layer "B.Fab")
			(hide yes)
			(effects
				(font
					(size 0.7 0.7)
					(thickness 0.15)
				)
				(justify right bottom mirror)
			)
		)
		(property "Datasheet" "https://www.murata.com/products/productdetail?partno=GRM155R61A106ME11%23"
			(at 0 0 90)
			(layer "F.Fab")
			(hide yes)
			(effects
				(font
					(size 1.27 1.27)
					(thickness 0.15)
				)
			)
		)
		(property "Description" "Multilayer Ceramic Capacitors MLCC - SMD/SMT 10 uF 10 VDC 20% 0402 X5R"
			(at 0 0 90)
			(layer "F.Fab")
			(hide yes)
			(effects
				(font
					(size 1.27 1.27)
					(thickness 0.15)
				)
			)
		)
		(property "Author" "Antmicro"
			(at 341.6 -48.1 0)
			(layer "B.Fab")
			(hide yes)
			(effects
				(font
					(size 1 1)
					(thickness 0.15)
				)
				(justify mirror)
			)
		)
		(property "Dielectric" "X5R"
			(at 341.6 -48.1 0)
			(layer "B.Fab")
			(hide yes)
			(effects
				(font
					(size 1 1)
					(thickness 0.15)
				)
				(justify mirror)
			)
		)
		(property "License" "Apache-2.0"
			(at 341.6 -48.1 0)
			(layer "B.Fab")
			(hide yes)
			(effects
				(font
					(size 1 1)
					(thickness 0.15)
				)
				(justify mirror)
			)
		)
		(property "MPN" "GRM155R61A106ME11D"
			(at 341.6 -48.1 0)
			(layer "B.Fab")
			(hide yes)
			(effects
				(font
					(size 1 1)
					(thickness 0.15)
				)
				(justify mirror)
			)
		)
		(property "Manufacturer" "Murata"
			(at 341.6 -48.1 0)
			(layer "B.Fab")
			(hide yes)
			(effects
				(font
					(size 1 1)
					(thickness 0.15)
				)
				(justify mirror)
			)
		)
		(property "Public" ""
			(at 341.6 -48.1 0)
			(layer "B.Fab")
			(hide yes)
			(effects
				(font
					(size 1 1)
					(thickness 0.15)
				)
				(justify mirror)
			)
		)
		(property "Val" "10u"
			(at 341.6 -48.1 0)
			(layer "B.Fab")
			(hide yes)
			(effects
				(font
					(size 1 1)
					(thickness 0.15)
				)
				(justify mirror)
			)
		)
		(property "Voltage" "10V"
			(at 341.6 -48.1 0)
			(layer "B.Fab")
			(hide yes)
			(effects
				(font
					(size 1 1)
					(thickness 0.15)
				)
				(justify mirror)
			)
		)
		(sheetname "/HDMI/")
		(sheetfile "hdmi.kicad_sch")
		(attr smd)
		(fp_rect
			(start -0.925 0.47)
			(end 0.925 -0.47)
			(stroke
				(width 0.05)
				(type default)
			)
			(fill no)
			(layer "B.CrtYd")
		)
		(fp_line
			(start 0.504 -0.248)
			(end -0.494 -0.248)
			(stroke
				(width 0.15)
				(type solid)
			)
			(layer "B.Fab")
		)
		(fp_line
			(start -0.494 -0.248)
			(end -0.494 0.25)
			(stroke
				(width 0.15)
				(type solid)
			)
			(layer "B.Fab")
		)
		(fp_line
			(start 0.504 0.25)
			(end 0.504 -0.248)
			(stroke
				(width 0.15)
				(type solid)
			)
			(layer "B.Fab")
		)
		(fp_line
			(start -0.494 0.25)
			(end 0.504 0.25)
			(stroke
				(width 0.15)
				(type solid)
			)
			(layer "B.Fab")
		)
		(fp_text user "Author: Antmicro"
			(at -0.939 -3.399 270)
			(layer "B.Fab")
			(effects
				(font
					(size 0.7 0.7)
					(thickness 0.15)
				)
				(justify left bottom mirror)
			)
		)
		(fp_text user "${REFERENCE}"
			(at -0.939 -4.599 270)
			(layer "B.Fab")
			(effects
				(font
					(size 0.7 0.7)
					(thickness 0.15)
				)
				(justify left bottom mirror)
			)
		)
		(fp_text user "License: Apache-2.0"
			(at -0.939 -5.799 270)
			(layer "B.Fab")
			(effects
				(font
					(size 0.7 0.7)
					(thickness 0.15)
				)
				(justify left bottom mirror)
			)
		)
		(pad "1" smd roundrect
			(at -0.48 0 90)
			(size 0.59 0.64)
			(layers "B.Cu" "B.Mask" "B.Paste")
			(roundrect_rratio 0.25)
			(net 417 "GND")
			(pintype "passive")
		)
		(pad "2" smd roundrect
			(at 0.48 0 90)
			(size 0.59 0.64)
			(layers "B.Cu" "B.Mask" "B.Paste")
			(roundrect_rratio 0.25)
			(net 553 "/HDMI/HDMI_3V3")
			(pintype "passive")
		)
	)
	(footprint "antmicro-footprints:C_0402_1005Metric"
		(layer "B.Cu")
		(at 203.21 126.71 180)
		(descr "Capacitor SMD 0402")
		(tags "capacitor SMD 0402")
		(property "Reference" "C15"
			(at -3.04 -0.865 0)
			(layer "B.SilkS")
			(effects
				(font
					(size 0.7 0.7)
					(thickness 0.15)
				)
				(justify left bottom mirror)
			)
		)
		(property "Value" "C_100n_0402"
			(at -1.022927 -2.155213 0)
			(layer "B.Fab")
			(hide yes)
			(effects
				(font
					(size 0.7 0.7)
					(thickness 0.15)
				)
				(justify left bottom mirror)
			)
		)
		(property "Datasheet" "https://www.murata.com/products/productdetail?partno=GRM155R61H104KE14%23"
			(at 0 0 180)
			(layer "F.Fab")
			(hide yes)
			(effects
				(font
					(size 1.27 1.27)
					(thickness 0.15)
				)
			)
		)
		(property "Description" "SMD Multilayer Ceramic Capacitor, 0.1 µF, 50 V, 0402 [1005 Metric], ± 10%, X5R, GRM Series"
			(at 0 0 180)
			(layer "F.Fab")
			(hide yes)
			(effects
				(font
					(size 1.27 1.27)
					(thickness 0.15)
				)
			)
		)
		(property "Author" "Antmicro"
			(at 406.42 253.42 0)
			(layer "B.Fab")
			(hide yes)
			(effects
				(font
					(size 1 1)
					(thickness 0.15)
				)
				(justify mirror)
			)
		)
		(property "Dielectric" "X5R"
			(at 406.42 253.42 0)
			(layer "B.Fab")
			(hide yes)
			(effects
				(font
					(size 1 1)
					(thickness 0.15)
				)
				(justify mirror)
			)
		)
		(property "License" "Apache-2.0"
			(at 406.42 253.42 0)
			(layer "B.Fab")
			(hide yes)
			(effects
				(font
					(size 1 1)
					(thickness 0.15)
				)
				(justify mirror)
			)
		)
		(property "MPN" "GRM155R61H104KE14D"
			(at 406.42 253.42 0)
			(layer "B.Fab")
			(hide yes)
			(effects
				(font
					(size 1 1)
					(thickness 0.15)
				)
				(justify mirror)
			)
		)
		(property "Manufacturer" "Murata"
			(at 406.42 253.42 0)
			(layer "B.Fab")
			(hide yes)
			(effects
				(font
					(size 1 1)
					(thickness 0.15)
				)
				(justify mirror)
			)
		)
		(property "Public" ""
			(at 406.42 253.42 0)
			(layer "B.Fab")
			(hide yes)
			(effects
				(font
					(size 1 1)
					(thickness 0.15)
				)
				(justify mirror)
			)
		)
		(property "Val" "100n"
			(at 406.42 253.42 0)
			(layer "B.Fab")
			(hide yes)
			(effects
				(font
					(size 1 1)
					(thickness 0.15)
				)
				(justify mirror)
			)
		)
		(property "Voltage" "50V"
			(at 406.42 253.42 0)
			(layer "B.Fab")
			(hide yes)
			(effects
				(font
					(size 1 1)
					(thickness 0.15)
				)
				(justify mirror)
			)
		)
		(sheetname "/FPGA Supply/")
		(sheetfile "fpga-supply.kicad_sch")
		(attr smd)
		(fp_rect
			(start -0.925 0.47)
			(end 0.925 -0.47)
			(stroke
				(width 0.05)
				(type default)
			)
			(fill no)
			(layer "B.CrtYd")
		)
		(fp_line
			(start 0.504 0.25)
			(end 0.504 -0.248)
			(stroke
				(width 0.15)
				(type solid)
			)
			(layer "B.Fab")
		)
		(fp_line
			(start 0.504 -0.248)
			(end -0.494 -0.248)
			(stroke
				(width 0.15)
				(type solid)
			)
			(layer "B.Fab")
		)
		(fp_line
			(start -0.494 0.25)
			(end 0.504 0.25)
			(stroke
				(width 0.15)
				(type solid)
			)
			(layer "B.Fab")
		)
		(fp_line
			(start -0.494 -0.248)
			(end -0.494 0.25)
			(stroke
				(width 0.15)
				(type solid)
			)
			(layer "B.Fab")
		)
		(fp_text user "${REFERENCE}"
			(at -0.939 -4.599 0)
			(layer "B.Fab")
			(effects
				(font
					(size 0.7 0.7)
					(thickness 0.15)
				)
				(justify left bottom mirror)
			)
		)
		(fp_text user "Author: Antmicro"
			(at -0.939 -3.399 0)
			(layer "B.Fab")
			(effects
				(font
					(size 0.7 0.7)
					(thickness 0.15)
				)
				(justify left bottom mirror)
			)
		)
		(fp_text user "License: Apache-2.0"
			(at -0.939 -5.799 0)
			(layer "B.Fab")
			(effects
				(font
					(size 0.7 0.7)
					(thickness 0.15)
				)
				(justify left bottom mirror)
			)
		)
		(pad "1" smd roundrect
			(at -0.48 0 180)
			(size 0.59 0.64)
			(layers "B.Cu" "B.Mask" "B.Paste")
			(roundrect_rratio 0.25)
			(net 417 "GND")
			(pintype "passive")
		)
		(pad "2" smd roundrect
			(at 0.48 0 180)
			(size 0.59 0.64)
			(layers "B.Cu" "B.Mask" "B.Paste")
			(roundrect_rratio 0.25)
			(net 649 "VDD")
			(pintype "passive")
		)
	)
	(footprint "antmicro-footprints:FB_0603_1608Metric"
		(layer "B.Cu")
		(at 213.1 142.95 180)
		(property "Reference" "FB1"
			(at 1.25 -0.65 0)
			(layer "B.SilkS")
			(effects
				(font
					(size 0.7 0.7)
					(thickness 0.15)
				)
				(justify left bottom mirror)
			)
		)
		(property "Value" "FB_470Z_1A_Murata-BLM18PG_0603"
			(at 0 -1.5 0)
			(layer "B.Fab")
			(hide yes)
			(effects
				(font
					(size 0.7 0.7)
					(thickness 0.15)
				)
				(justify left bottom mirror)
			)
		)
		(property "Datasheet" "https://www.murata.com/en-us/products/productdata/8796738650142/ENFA0003.pdf"
			(at 0 0 180)
			(layer "F.Fab")
			(hide yes)
			(effects
				(font
					(size 1.27 1.27)
					(thickness 0.15)
				)
			)
		)
		(property "Description" "Ferrite Bead, 0603 [1608 Metric], 470 ohm, 1 A, BLM18P, 0.2 ohm, ± 25%, DC power line"
			(at 0 0 180)
			(layer "F.Fab")
			(hide yes)
			(effects
				(font
					(size 1.27 1.27)
					(thickness 0.15)
				)
			)
		)
		(property "Author" "Antmicro"
			(at 426.2 285.9 0)
			(layer "B.Fab")
			(hide yes)
			(effects
				(font
					(size 1 1)
					(thickness 0.15)
				)
				(justify mirror)
			)
		)
		(property "Current" ""
			(at 426.2 285.9 0)
			(layer "B.Fab")
			(hide yes)
			(effects
				(font
					(size 1 1)
					(thickness 0.15)
				)
				(justify mirror)
			)
		)
		(property "License" "Apache-2.0"
			(at 426.2 285.9 0)
			(layer "B.Fab")
			(hide yes)
			(effects
				(font
					(size 1 1)
					(thickness 0.15)
				)
				(justify mirror)
			)
		)
		(property "MPN" "BLM18PG471SN1D"
			(at 426.2 285.9 0)
			(layer "B.Fab")
			(hide yes)
			(effects
				(font
					(size 1 1)
					(thickness 0.15)
				)
				(justify mirror)
			)
		)
		(property "Manufacturer" "Murata"
			(at 426.2 285.9 0)
			(layer "B.Fab")
			(hide yes)
			(effects
				(font
					(size 1 1)
					(thickness 0.15)
				)
				(justify mirror)
			)
		)
		(property "Public" ""
			(at 426.2 285.9 0)
			(layer "B.Fab")
			(hide yes)
			(effects
				(font
					(size 1 1)
					(thickness 0.15)
				)
				(justify mirror)
			)
		)
		(property "Val" "470Z/1A"
			(at 426.2 285.9 0)
			(layer "B.Fab")
			(hide yes)
			(effects
				(font
					(size 1 1)
					(thickness 0.15)
				)
				(justify mirror)
			)
		)
		(sheetname "/USB/")
		(sheetfile "usb.kicad_sch")
		(attr smd)
		(fp_line
			(start -0.15 0.4)
			(end 0.15 0.4)
			(stroke
				(width 0.15)
				(type solid)
			)
			(layer "B.SilkS")
		)
		(fp_line
			(start -0.15 -0.4)
			(end 0.15 -0.4)
			(stroke
				(width 0.15)
				(type solid)
			)
			(layer "B.SilkS")
		)
		(fp_rect
			(start -1.25 0.65)
			(end 1.25 -0.65)
			(stroke
				(width 0.05)
				(type solid)
			)
			(fill no)
			(layer "B.CrtYd")
		)
		(fp_line
			(start 0.8 0.408)
			(end 0.8 -0.406)
			(stroke
				(width 0.15)
				(type solid)
			)
			(layer "B.Fab")
		)
		(fp_line
			(start 0.8 0.408)
			(end -0.803 0.408)
			(stroke
				(width 0.15)
				(type solid)
			)
			(layer "B.Fab")
		)
		(fp_line
			(start 0.8 -0.406)
			(end -0.803 -0.406)
			(stroke
				(width 0.15)
				(type solid)
			)
			(layer "B.Fab")
		)
		(fp_line
			(start -0.803 -0.406)
			(end -0.803 0.408)
			(stroke
				(width 0.15)
				(type solid)
			)
			(layer "B.Fab")
		)
		(fp_text user "${REFERENCE}"
			(at -1.653 -4.6 0)
			(layer "B.Fab")
			(effects
				(font
					(size 0.7 0.7)
					(thickness 0.15)
				)
				(justify left bottom mirror)
			)
		)
		(fp_text user "Author: Antmicro"
			(at -1.653 -3.162 0)
			(layer "B.Fab")
			(effects
				(font
					(size 0.7 0.7)
					(thickness 0.15)
				)
				(justify left bottom mirror)
			)
		)
		(fp_text user "License: Apache-2.0"
			(at -1.653 -5.9 0)
			(layer "B.Fab")
			(effects
				(font
					(size 0.7 0.7)
					(thickness 0.15)
				)
				(justify left bottom mirror)
			)
		)
		(pad "1" smd roundrect
			(at -0.7 0 180)
			(size 0.8 1)
			(layers "B.Cu" "B.Mask" "B.Paste")
			(roundrect_rratio 0.2)
			(net 152 "/USB/VDDIO")
			(pintype "passive")
		)
		(pad "2" smd roundrect
			(at 0.7 0 180)
			(size 0.8 1)
			(layers "B.Cu" "B.Mask" "B.Paste")
			(roundrect_rratio 0.2)
			(net 649 "VDD")
			(pintype "passive")
		)
	)
	(footprint "antmicro-footprints:R_0402_1005Metric"
		(layer "B.Cu")
		(at 210.1775 134.347)
		(descr "Resistor SMD 0402")
		(tags "resistor SMD 0402")
		(property "Reference" "R28"
			(at 1.6225 3.353 180)
			(layer "B.SilkS")
			(effects
				(font
					(size 0.7 0.7)
					(thickness 0.15)
				)
				(justify left bottom mirror)
			)
		)
		(property "Value" "R_10k_0402"
			(at -1.011843 -1.772047 180)
			(layer "B.Fab")
			(hide yes)
			(effects
				(font
					(size 0.7 0.7)
					(thickness 0.15)
				)
				(justify left bottom mirror)
			)
		)
		(property "Datasheet" "https://www.bourns.com/docs/product-datasheets/cr.pdf"
			(at 0 0 0)
			(layer "F.Fab")
			(hide yes)
			(effects
				(font
					(size 1.27 1.27)
					(thickness 0.15)
				)
			)
		)
		(property "Description" "SMD Chip Resistor, 10 kohm, ± 1%, 62.5 mW, 0402 [1005 Metric], Thick Film, General Purpose"
			(at 0 0 0)
			(layer "F.Fab")
			(hide yes)
			(effects
				(font
					(size 1.27 1.27)
					(thickness 0.15)
				)
			)
		)
		(property "Author" "Antmicro"
			(at 0 0 0)
			(layer "B.Fab")
			(hide yes)
			(effects
				(font
					(size 1 1)
					(thickness 0.15)
				)
				(justify mirror)
			)
		)
		(property "License" "Apache-2.0"
			(at 0 0 0)
			(layer "B.Fab")
			(hide yes)
			(effects
				(font
					(size 1 1)
					(thickness 0.15)
				)
				(justify mirror)
			)
		)
		(property "MPN" "CR0402-FX-1002GLF"
			(at 0 0 0)
			(layer "B.Fab")
			(hide yes)
			(effects
				(font
					(size 1 1)
					(thickness 0.15)
				)
				(justify mirror)
			)
		)
		(property "Manufacturer" "Bourns"
			(at 0 0 0)
			(layer "B.Fab")
			(hide yes)
			(effects
				(font
					(size 1 1)
					(thickness 0.15)
				)
				(justify mirror)
			)
		)
		(property "Public" ""
			(at 0 0 0)
			(layer "B.Fab")
			(hide yes)
			(effects
				(font
					(size 1 1)
					(thickness 0.15)
				)
				(justify mirror)
			)
		)
		(property "Tolerance" "1%"
			(at 0 0 0)
			(layer "B.Fab")
			(hide yes)
			(effects
				(font
					(size 1 1)
					(thickness 0.15)
				)
				(justify mirror)
			)
		)
		(property "Val" "10k"
			(at 0 0 0)
			(layer "B.Fab")
			(hide yes)
			(effects
				(font
					(size 1 1)
					(thickness 0.15)
				)
				(justify mirror)
			)
		)
		(sheetname "/Memory/")
		(sheetfile "memory.kicad_sch")
		(attr smd)
		(fp_rect
			(start -0.925 0.47)
			(end 0.925 -0.47)
			(stroke
				(width 0.05)
				(type default)
			)
			(fill no)
			(layer "B.CrtYd")
		)
		(fp_rect
			(start -0.5 0.25)
			(end 0.5 -0.25)
			(stroke
				(width 0.15)
				(type solid)
			)
			(fill no)
			(layer "B.Fab")
		)
		(fp_text user "License: Apache-2.0"
			(at -0.95 -5.169 180)
			(layer "B.Fab")
			(effects
				(font
					(size 0.7 0.7)
					(thickness 0.15)
				)
				(justify left bottom mirror)
			)
		)
		(fp_text user "Author: Antmicro"
			(at -0.95 -4.169 180)
			(layer "B.Fab")
			(effects
				(font
					(size 0.7 0.7)
					(thickness 0.15)
				)
				(justify left bottom mirror)
			)
		)
		(fp_text user "${REFERENCE}"
			(at -0.95 -3.168 180)
			(layer "B.Fab")
			(effects
				(font
					(size 0.7 0.7)
					(thickness 0.15)
				)
				(justify left bottom mirror)
			)
		)
		(pad "1" smd roundrect
			(at -0.48 0)
			(size 0.59 0.64)
			(layers "B.Cu" "B.Mask" "B.Paste")
			(roundrect_rratio 0.25)
			(net 387 "/FPGA MSSIO/EMMC.RST_n")
			(pintype "passive")
		)
		(pad "2" smd roundrect
			(at 0.48 0)
			(size 0.59 0.64)
			(layers "B.Cu" "B.Mask" "B.Paste")
			(roundrect_rratio 0.25)
			(net 137 "SD_VDD")
			(pintype "passive")
		)
	)
	(footprint "antmicro-footprints:C_0402_1005Metric"
		(layer "B.Cu")
		(at 196.65 140.55 90)
		(descr "Capacitor SMD 0402")
		(tags "capacitor SMD 0402")
		(property "Reference" "C35"
			(at 1.45 -2.47 270)
			(layer "B.SilkS")
			(effects
				(font
					(size 0.7 0.7)
					(thickness 0.15)
				)
				(justify left bottom mirror)
			)
		)
		(property "Value" "C_100n_0402"
			(at -1.022927 -2.155213 270)
			(layer "B.Fab")
			(hide yes)
			(effects
				(font
					(size 0.7 0.7)
					(thickness 0.15)
				)
				(justify left bottom mirror)
			)
		)
		(property "Datasheet" "https://www.murata.com/products/productdetail?partno=GRM155R61H104KE14%23"
			(at 0 0 90)
			(layer "F.Fab")
			(hide yes)
			(effects
				(font
					(size 1.27 1.27)
					(thickness 0.15)
				)
			)
		)
		(property "Description" "SMD Multilayer Ceramic Capacitor, 0.1 µF, 50 V, 0402 [1005 Metric], ± 10%, X5R, GRM Series"
			(at 0 0 90)
			(layer "F.Fab")
			(hide yes)
			(effects
				(font
					(size 1.27 1.27)
					(thickness 0.15)
				)
			)
		)
		(property "Author" "Antmicro"
			(at 337.2 -56.1 0)
			(layer "B.Fab")
			(hide yes)
			(effects
				(font
					(size 1 1)
					(thickness 0.15)
				)
				(justify mirror)
			)
		)
		(property "Dielectric" "X5R"
			(at 337.2 -56.1 0)
			(layer "B.Fab")
			(hide yes)
			(effects
				(font
					(size 1 1)
					(thickness 0.15)
				)
				(justify mirror)
			)
		)
		(property "License" "Apache-2.0"
			(at 337.2 -56.1 0)
			(layer "B.Fab")
			(hide yes)
			(effects
				(font
					(size 1 1)
					(thickness 0.15)
				)
				(justify mirror)
			)
		)
		(property "MPN" "GRM155R61H104KE14D"
			(at 337.2 -56.1 0)
			(layer "B.Fab")
			(hide yes)
			(effects
				(font
					(size 1 1)
					(thickness 0.15)
				)
				(justify mirror)
			)
		)
		(property "Manufacturer" "Murata"
			(at 337.2 -56.1 0)
			(layer "B.Fab")
			(hide yes)
			(effects
				(font
					(size 1 1)
					(thickness 0.15)
				)
				(justify mirror)
			)
		)
		(property "Public" ""
			(at 337.2 -56.1 0)
			(layer "B.Fab")
			(hide yes)
			(effects
				(font
					(size 1 1)
					(thickness 0.15)
				)
				(justify mirror)
			)
		)
		(property "Val" "100n"
			(at 337.2 -56.1 0)
			(layer "B.Fab")
			(hide yes)
			(effects
				(font
					(size 1 1)
					(thickness 0.15)
				)
				(justify mirror)
			)
		)
		(property "Voltage" "50V"
			(at 337.2 -56.1 0)
			(layer "B.Fab")
			(hide yes)
			(effects
				(font
					(size 1 1)
					(thickness 0.15)
				)
				(justify mirror)
			)
		)
		(sheetname "/FPGA Supply/")
		(sheetfile "fpga-supply.kicad_sch")
		(attr smd)
		(fp_rect
			(start -0.925 0.47)
			(end 0.925 -0.47)
			(stroke
				(width 0.05)
				(type default)
			)
			(fill no)
			(layer "B.CrtYd")
		)
		(fp_line
			(start 0.504 -0.248)
			(end -0.494 -0.248)
			(stroke
				(width 0.15)
				(type solid)
			)
			(layer "B.Fab")
		)
		(fp_line
			(start -0.494 -0.248)
			(end -0.494 0.25)
			(stroke
				(width 0.15)
				(type solid)
			)
			(layer "B.Fab")
		)
		(fp_line
			(start 0.504 0.25)
			(end 0.504 -0.248)
			(stroke
				(width 0.15)
				(type solid)
			)
			(layer "B.Fab")
		)
		(fp_line
			(start -0.494 0.25)
			(end 0.504 0.25)
			(stroke
				(width 0.15)
				(type solid)
			)
			(layer "B.Fab")
		)
		(fp_text user "${REFERENCE}"
			(at -0.939 -4.599 270)
			(layer "B.Fab")
			(effects
				(font
					(size 0.7 0.7)
					(thickness 0.15)
				)
				(justify left bottom mirror)
			)
		)
		(fp_text user "Author: Antmicro"
			(at -0.939 -3.399 270)
			(layer "B.Fab")
			(effects
				(font
					(size 0.7 0.7)
					(thickness 0.15)
				)
				(justify left bottom mirror)
			)
		)
		(fp_text user "License: Apache-2.0"
			(at -0.939 -5.799 270)
			(layer "B.Fab")
			(effects
				(font
					(size 0.7 0.7)
					(thickness 0.15)
				)
				(justify left bottom mirror)
			)
		)
		(pad "1" smd roundrect
			(at -0.48 0 90)
			(size 0.59 0.64)
			(layers "B.Cu" "B.Mask" "B.Paste")
			(roundrect_rratio 0.25)
			(net 417 "GND")
			(pintype "passive")
		)
		(pad "2" smd roundrect
			(at 0.48 0 90)
			(size 0.59 0.64)
			(layers "B.Cu" "B.Mask" "B.Paste")
			(roundrect_rratio 0.25)
			(net 47 "+1V05")
			(pintype "passive")
		)
	)
	(footprint "antmicro-footprints:C_0402_1005Metric"
		(layer "B.Cu")
		(at 212.1925 132.697)
		(descr "Capacitor SMD 0402")
		(tags "capacitor SMD 0402")
		(property "Reference" "C80"
			(at 0.8175 0.913 135)
			(layer "B.SilkS")
			(effects
				(font
					(size 0.7 0.7)
					(thickness 0.15)
				)
				(justify right bottom mirror)
			)
		)
		(property "Value" "C_10u_0402"
			(at -1.022927 -2.155213 0)
			(layer "B.Fab")
			(hide yes)
			(effects
				(font
					(size 0.7 0.7)
					(thickness 0.15)
				)
				(justify right bottom mirror)
			)
		)
		(property "Datasheet" "https://www.yageo.com/en/Chart/Download/pdf/CC0402MRX5R5BB106"
			(at 0 0 0)
			(layer "F.Fab")
			(hide yes)
			(effects
				(font
					(size 1.27 1.27)
					(thickness 0.15)
				)
			)
		)
		(property "Description" "SMD Multilayer Ceramic Capacitor, 10 µF, 6.3 V, 0402 [1005 Metric], ± 20%, X5R, CC Series"
			(at 0 0 0)
			(layer "F.Fab")
			(hide yes)
			(effects
				(font
					(size 1.27 1.27)
					(thickness 0.15)
				)
			)
		)
		(property "Author" "Antmicro"
			(at 0 0 0)
			(layer "B.Fab")
			(hide yes)
			(effects
				(font
					(size 1 1)
					(thickness 0.15)
				)
				(justify mirror)
			)
		)
		(property "Dielectric" ""
			(at 0 0 0)
			(layer "B.Fab")
			(hide yes)
			(effects
				(font
					(size 1 1)
					(thickness 0.15)
				)
				(justify mirror)
			)
		)
		(property "License" "Apache-2.0"
			(at 0 0 0)
			(layer "B.Fab")
			(hide yes)
			(effects
				(font
					(size 1 1)
					(thickness 0.15)
				)
				(justify mirror)
			)
		)
		(property "MPN" "CC0402MRX5R5BB106"
			(at 0 0 0)
			(layer "B.Fab")
			(hide yes)
			(effects
				(font
					(size 1 1)
					(thickness 0.15)
				)
				(justify mirror)
			)
		)
		(property "Manufacturer" "YAGEO"
			(at 0 0 0)
			(layer "B.Fab")
			(hide yes)
			(effects
				(font
					(size 1 1)
					(thickness 0.15)
				)
				(justify mirror)
			)
		)
		(property "Public" ""
			(at 0 0 0)
			(layer "B.Fab")
			(hide yes)
			(effects
				(font
					(size 1 1)
					(thickness 0.15)
				)
				(justify mirror)
			)
		)
		(property "Val" "10u"
			(at 0 0 0)
			(layer "B.Fab")
			(hide yes)
			(effects
				(font
					(size 1 1)
					(thickness 0.15)
				)
				(justify mirror)
			)
		)
		(property "Voltage" ""
			(at 0 0 0)
			(layer "B.Fab")
			(hide yes)
			(effects
				(font
					(size 1 1)
					(thickness 0.15)
				)
				(justify mirror)
			)
		)
		(sheetname "/Memory/")
		(sheetfile "memory.kicad_sch")
		(attr smd)
		(fp_rect
			(start -0.925 0.47)
			(end 0.925 -0.47)
			(stroke
				(width 0.05)
				(type default)
			)
			(fill no)
			(layer "B.CrtYd")
		)
		(fp_line
			(start -0.494 -0.248)
			(end -0.494 0.25)
			(stroke
				(width 0.15)
				(type solid)
			)
			(layer "B.Fab")
		)
		(fp_line
			(start -0.494 0.25)
			(end 0.504 0.25)
			(stroke
				(width 0.15)
				(type solid)
			)
			(layer "B.Fab")
		)
		(fp_line
			(start 0.504 -0.248)
			(end -0.494 -0.248)
			(stroke
				(width 0.15)
				(type solid)
			)
			(layer "B.Fab")
		)
		(fp_line
			(start 0.504 0.25)
			(end 0.504 -0.248)
			(stroke
				(width 0.15)
				(type solid)
			)
			(layer "B.Fab")
		)
		(fp_text user "Author: Antmicro"
			(at -0.939 -3.399 180)
			(layer "B.Fab")
			(effects
				(font
					(size 0.7 0.7)
					(thickness 0.15)
				)
				(justify left bottom mirror)
			)
		)
		(fp_text user "${REFERENCE}"
			(at -0.939 -4.599 180)
			(layer "B.Fab")
			(effects
				(font
					(size 0.7 0.7)
					(thickness 0.15)
				)
				(justify left bottom mirror)
			)
		)
		(fp_text user "License: Apache-2.0"
			(at -0.939 -5.799 180)
			(layer "B.Fab")
			(effects
				(font
					(size 0.7 0.7)
					(thickness 0.15)
				)
				(justify left bottom mirror)
			)
		)
		(pad "1" smd roundrect
			(at -0.48 0)
			(size 0.59 0.64)
			(layers "B.Cu" "B.Mask" "B.Paste")
			(roundrect_rratio 0.25)
			(net 417 "GND")
			(pintype "passive")
		)
		(pad "2" smd roundrect
			(at 0.48 0)
			(size 0.59 0.64)
			(layers "B.Cu" "B.Mask" "B.Paste")
			(roundrect_rratio 0.25)
			(net 137 "SD_VDD")
			(pintype "passive")
		)
	)
	(footprint "antmicro-footprints:R_0402_1005Metric"
		(layer "B.Cu")
		(at 206.15 142.6 180)
		(descr "Resistor SMD 0402")
		(tags "resistor SMD 0402")
		(property "Reference" "R117"
			(at -0.3 -1.34 0)
			(layer "B.SilkS")
			(effects
				(font
					(size 0.7 0.7)
					(thickness 0.15)
				)
				(justify left bottom mirror)
			)
		)
		(property "Value" "R_10k_0402"
			(at -1.011843 -1.772047 0)
			(layer "B.Fab")
			(hide yes)
			(effects
				(font
					(size 0.7 0.7)
					(thickness 0.15)
				)
				(justify left bottom mirror)
			)
		)
		(property "Datasheet" "https://www.bourns.com/docs/product-datasheets/cr.pdf"
			(at 0 0 180)
			(layer "F.Fab")
			(hide yes)
			(effects
				(font
					(size 1.27 1.27)
					(thickness 0.15)
				)
			)
		)
		(property "Description" "SMD Chip Resistor, 10 kohm, ± 1%, 62.5 mW, 0402 [1005 Metric], Thick Film, General Purpose"
			(at 0 0 180)
			(layer "F.Fab")
			(hide yes)
			(effects
				(font
					(size 1.27 1.27)
					(thickness 0.15)
				)
			)
		)
		(property "Author" "Antmicro"
			(at 412.3 285.2 0)
			(layer "B.Fab")
			(hide yes)
			(effects
				(font
					(size 1 1)
					(thickness 0.15)
				)
				(justify mirror)
			)
		)
		(property "License" "Apache-2.0"
			(at 412.3 285.2 0)
			(layer "B.Fab")
			(hide yes)
			(effects
				(font
					(size 1 1)
					(thickness 0.15)
				)
				(justify mirror)
			)
		)
		(property "MPN" "CR0402-FX-1002GLF"
			(at 412.3 285.2 0)
			(layer "B.Fab")
			(hide yes)
			(effects
				(font
					(size 1 1)
					(thickness 0.15)
				)
				(justify mirror)
			)
		)
		(property "Manufacturer" "Bourns"
			(at 412.3 285.2 0)
			(layer "B.Fab")
			(hide yes)
			(effects
				(font
					(size 1 1)
					(thickness 0.15)
				)
				(justify mirror)
			)
		)
		(property "Public" ""
			(at 412.3 285.2 0)
			(layer "B.Fab")
			(hide yes)
			(effects
				(font
					(size 1 1)
					(thickness 0.15)
				)
				(justify mirror)
			)
		)
		(property "Tolerance" "1%"
			(at 412.3 285.2 0)
			(layer "B.Fab")
			(hide yes)
			(effects
				(font
					(size 1 1)
					(thickness 0.15)
				)
				(justify mirror)
			)
		)
		(property "Val" "10k"
			(at 412.3 285.2 0)
			(layer "B.Fab")
			(hide yes)
			(effects
				(font
					(size 1 1)
					(thickness 0.15)
				)
				(justify mirror)
			)
		)
		(sheetname "/MIPI CrossLink/")
		(sheetfile "crosslink.kicad_sch")
		(attr smd)
		(fp_rect
			(start -0.925 0.47)
			(end 0.925 -0.47)
			(stroke
				(width 0.05)
				(type default)
			)
			(fill no)
			(layer "B.CrtYd")
		)
		(fp_rect
			(start -0.5 0.25)
			(end 0.5 -0.25)
			(stroke
				(width 0.15)
				(type solid)
			)
			(fill no)
			(layer "B.Fab")
		)
		(fp_text user "Author: Antmicro"
			(at -0.95 -4.169 0)
			(layer "B.Fab")
			(effects
				(font
					(size 0.7 0.7)
					(thickness 0.15)
				)
				(justify left bottom mirror)
			)
		)
		(fp_text user "${REFERENCE}"
			(at -0.95 -3.168 0)
			(layer "B.Fab")
			(effects
				(font
					(size 0.7 0.7)
					(thickness 0.15)
				)
				(justify left bottom mirror)
			)
		)
		(fp_text user "License: Apache-2.0"
			(at -0.95 -5.169 0)
			(layer "B.Fab")
			(effects
				(font
					(size 0.7 0.7)
					(thickness 0.15)
				)
				(justify left bottom mirror)
			)
		)
		(pad "1" smd roundrect
			(at -0.48 0 180)
			(size 0.59 0.64)
			(layers "B.Cu" "B.Mask" "B.Paste")
			(roundrect_rratio 0.25)
			(net 417 "GND")
			(pintype "passive")
		)
		(pad "2" smd roundrect
			(at 0.48 0 180)
			(size 0.59 0.64)
			(layers "B.Cu" "B.Mask" "B.Paste")
			(roundrect_rratio 0.25)
			(net 289 "~{Crosslink_RESET}")
			(pintype "passive")
		)
	)
	(footprint "antmicro-footprints:C_0402_1005Metric"
		(layer "B.Cu")
		(at 223.9 147.295 90)
		(descr "Capacitor SMD 0402")
		(tags "capacitor SMD 0402")
		(property "Reference" "C230"
			(at -3.735 0.8 90)
			(layer "B.SilkS")
			(effects
				(font
					(size 0.7 0.7)
					(thickness 0.15)
				)
				(justify right bottom mirror)
			)
		)
		(property "Value" "C_100n_0402"
			(at -1.022927 -2.155213 90)
			(layer "B.Fab")
			(hide yes)
			(effects
				(font
					(size 0.7 0.7)
					(thickness 0.15)
				)
				(justify right bottom mirror)
			)
		)
		(property "Datasheet" "https://www.murata.com/products/productdetail?partno=GRM155R61H104KE14%23"
			(at 0 0 90)
			(layer "F.Fab")
			(hide yes)
			(effects
				(font
					(size 1.27 1.27)
					(thickness 0.15)
				)
			)
		)
		(property "Description" "SMD Multilayer Ceramic Capacitor, 0.1 µF, 50 V, 0402 [1005 Metric], ± 10%, X5R, GRM Series"
			(at 0 0 90)
			(layer "F.Fab")
			(hide yes)
			(effects
				(font
					(size 1.27 1.27)
					(thickness 0.15)
				)
			)
		)
		(property "Author" "Antmicro"
			(at 371.195 -76.605 0)
			(layer "B.Fab")
			(hide yes)
			(effects
				(font
					(size 1 1)
					(thickness 0.15)
				)
				(justify mirror)
			)
		)
		(property "Dielectric" "X5R"
			(at 371.195 -76.605 0)
			(layer "B.Fab")
			(hide yes)
			(effects
				(font
					(size 1 1)
					(thickness 0.15)
				)
				(justify mirror)
			)
		)
		(property "License" "Apache-2.0"
			(at 371.195 -76.605 0)
			(layer "B.Fab")
			(hide yes)
			(effects
				(font
					(size 1 1)
					(thickness 0.15)
				)
				(justify mirror)
			)
		)
		(property "MPN" "GRM155R61H104KE14D"
			(at 371.195 -76.605 0)
			(layer "B.Fab")
			(hide yes)
			(effects
				(font
					(size 1 1)
					(thickness 0.15)
				)
				(justify mirror)
			)
		)
		(property "Manufacturer" "Murata"
			(at 371.195 -76.605 0)
			(layer "B.Fab")
			(hide yes)
			(effects
				(font
					(size 1 1)
					(thickness 0.15)
				)
				(justify mirror)
			)
		)
		(property "Public" ""
			(at 371.195 -76.605 0)
			(layer "B.Fab")
			(hide yes)
			(effects
				(font
					(size 1 1)
					(thickness 0.15)
				)
				(justify mirror)
			)
		)
		(property "Val" "100n"
			(at 371.195 -76.605 0)
			(layer "B.Fab")
			(hide yes)
			(effects
				(font
					(size 1 1)
					(thickness 0.15)
				)
				(justify mirror)
			)
		)
		(property "Voltage" "50V"
			(at 371.195 -76.605 0)
			(layer "B.Fab")
			(hide yes)
			(effects
				(font
					(size 1 1)
					(thickness 0.15)
				)
				(justify mirror)
			)
		)
		(sheetname "/WiFi_Bluetooth/")
		(sheetfile "wifi_bt.kicad_sch")
		(attr smd)
		(fp_rect
			(start -0.925 0.47)
			(end 0.925 -0.47)
			(stroke
				(width 0.05)
				(type default)
			)
			(fill no)
			(layer "B.CrtYd")
		)
		(fp_line
			(start 0.504 -0.248)
			(end -0.494 -0.248)
			(stroke
				(width 0.15)
				(type solid)
			)
			(layer "B.Fab")
		)
		(fp_line
			(start -0.494 -0.248)
			(end -0.494 0.25)
			(stroke
				(width 0.15)
				(type solid)
			)
			(layer "B.Fab")
		)
		(fp_line
			(start 0.504 0.25)
			(end 0.504 -0.248)
			(stroke
				(width 0.15)
				(type solid)
			)
			(layer "B.Fab")
		)
		(fp_line
			(start -0.494 0.25)
			(end 0.504 0.25)
			(stroke
				(width 0.15)
				(type solid)
			)
			(layer "B.Fab")
		)
		(fp_text user "Author: Antmicro"
			(at -0.939 -3.399 270)
			(layer "B.Fab")
			(effects
				(font
					(size 0.7 0.7)
					(thickness 0.15)
				)
				(justify left bottom mirror)
			)
		)
		(fp_text user "${REFERENCE}"
			(at -0.939 -4.599 270)
			(layer "B.Fab")
			(effects
				(font
					(size 0.7 0.7)
					(thickness 0.15)
				)
				(justify left bottom mirror)
			)
		)
		(fp_text user "License: Apache-2.0"
			(at -0.939 -5.799 270)
			(layer "B.Fab")
			(effects
				(font
					(size 0.7 0.7)
					(thickness 0.15)
				)
				(justify left bottom mirror)
			)
		)
		(pad "1" smd roundrect
			(at -0.48 0 90)
			(size 0.59 0.64)
			(layers "B.Cu" "B.Mask" "B.Paste")
			(roundrect_rratio 0.25)
			(net 417 "GND")
			(pintype "passive")
		)
		(pad "2" smd roundrect
			(at 0.48 0 90)
			(size 0.59 0.64)
			(layers "B.Cu" "B.Mask" "B.Paste")
			(roundrect_rratio 0.25)
			(net 50 "+3V3")
			(pintype "passive")
		)
	)
	(footprint "antmicro-footprints:C_0402_1005Metric"
		(layer "B.Cu")
		(at 208.1 148.41 180)
		(descr "Capacitor SMD 0402")
		(tags "capacitor SMD 0402")
		(property "Reference" "C209"
			(at 4.9 18.375 0)
			(layer "B.SilkS")
			(effects
				(font
					(size 0.7 0.7)
					(thickness 0.15)
				)
				(justify left bottom mirror)
			)
		)
		(property "Value" "C_10u_10V_0402"
			(at -1.022927 -2.155213 0)
			(layer "B.Fab")
			(hide yes)
			(effects
				(font
					(size 0.7 0.7)
					(thickness 0.15)
				)
				(justify left bottom mirror)
			)
		)
		(property "Datasheet" "https://www.murata.com/products/productdetail?partno=GRM155R61A106ME11%23"
			(at 0 0 180)
			(layer "F.Fab")
			(hide yes)
			(effects
				(font
					(size 1.27 1.27)
					(thickness 0.15)
				)
			)
		)
		(property "Description" "Multilayer Ceramic Capacitors MLCC - SMD/SMT 10 uF 10 VDC 20% 0402 X5R"
			(at 0 0 180)
			(layer "F.Fab")
			(hide yes)
			(effects
				(font
					(size 1.27 1.27)
					(thickness 0.15)
				)
			)
		)
		(property "Author" "Antmicro"
			(at 416.2 296.82 0)
			(layer "B.Fab")
			(hide yes)
			(effects
				(font
					(size 1 1)
					(thickness 0.15)
				)
				(justify mirror)
			)
		)
		(property "Dielectric" "X5R"
			(at 416.2 296.82 0)
			(layer "B.Fab")
			(hide yes)
			(effects
				(font
					(size 1 1)
					(thickness 0.15)
				)
				(justify mirror)
			)
		)
		(property "License" "Apache-2.0"
			(at 416.2 296.82 0)
			(layer "B.Fab")
			(hide yes)
			(effects
				(font
					(size 1 1)
					(thickness 0.15)
				)
				(justify mirror)
			)
		)
		(property "MPN" "GRM155R61A106ME11D"
			(at 416.2 296.82 0)
			(layer "B.Fab")
			(hide yes)
			(effects
				(font
					(size 1 1)
					(thickness 0.15)
				)
				(justify mirror)
			)
		)
		(property "Manufacturer" "Murata"
			(at 416.2 296.82 0)
			(layer "B.Fab")
			(hide yes)
			(effects
				(font
					(size 1 1)
					(thickness 0.15)
				)
				(justify mirror)
			)
		)
		(property "Public" ""
			(at 416.2 296.82 0)
			(layer "B.Fab")
			(hide yes)
			(effects
				(font
					(size 1 1)
					(thickness 0.15)
				)
				(justify mirror)
			)
		)
		(property "Val" "10u"
			(at 416.2 296.82 0)
			(layer "B.Fab")
			(hide yes)
			(effects
				(font
					(size 1 1)
					(thickness 0.15)
				)
				(justify mirror)
			)
		)
		(property "Voltage" "10V"
			(at 416.2 296.82 0)
			(layer "B.Fab")
			(hide yes)
			(effects
				(font
					(size 1 1)
					(thickness 0.15)
				)
				(justify mirror)
			)
		)
		(sheetname "/MIPI CrossLink/")
		(sheetfile "crosslink.kicad_sch")
		(attr smd)
		(fp_rect
			(start -0.925 0.47)
			(end 0.925 -0.47)
			(stroke
				(width 0.05)
				(type default)
			)
			(fill no)
			(layer "B.CrtYd")
		)
		(fp_line
			(start 0.504 0.25)
			(end 0.504 -0.248)
			(stroke
				(width 0.15)
				(type solid)
			)
			(layer "B.Fab")
		)
		(fp_line
			(start 0.504 -0.248)
			(end -0.494 -0.248)
			(stroke
				(width 0.15)
				(type solid)
			)
			(layer "B.Fab")
		)
		(fp_line
			(start -0.494 0.25)
			(end 0.504 0.25)
			(stroke
				(width 0.15)
				(type solid)
			)
			(layer "B.Fab")
		)
		(fp_line
			(start -0.494 -0.248)
			(end -0.494 0.25)
			(stroke
				(width 0.15)
				(type solid)
			)
			(layer "B.Fab")
		)
		(fp_text user "${REFERENCE}"
			(at -0.939 -4.599 0)
			(layer "B.Fab")
			(effects
				(font
					(size 0.7 0.7)
					(thickness 0.15)
				)
				(justify left bottom mirror)
			)
		)
		(fp_text user "License: Apache-2.0"
			(at -0.939 -5.799 0)
			(layer "B.Fab")
			(effects
				(font
					(size 0.7 0.7)
					(thickness 0.15)
				)
				(justify left bottom mirror)
			)
		)
		(fp_text user "Author: Antmicro"
			(at -0.939 -3.399 0)
			(layer "B.Fab")
			(effects
				(font
					(size 0.7 0.7)
					(thickness 0.15)
				)
				(justify left bottom mirror)
			)
		)
		(pad "1" smd roundrect
			(at -0.48 0 180)
			(size 0.59 0.64)
			(layers "B.Cu" "B.Mask" "B.Paste")
			(roundrect_rratio 0.25)
			(net 417 "GND")
			(pintype "passive")
		)
		(pad "2" smd roundrect
			(at 0.48 0 180)
			(size 0.59 0.64)
			(layers "B.Cu" "B.Mask" "B.Paste")
			(roundrect_rratio 0.25)
			(net 205 "/MIPI CrossLink/CL_VCCA_DPHY1")
			(pintype "passive")
		)
	)
	(footprint "antmicro-footprints:C_0402_1005Metric"
		(layer "B.Cu")
		(at 201.75 145.9 -90)
		(descr "Capacitor SMD 0402")
		(tags "capacitor SMD 0402")
		(property "Reference" "C205"
			(at -3.76 -0.27 270)
			(layer "B.SilkS")
			(effects
				(font
					(size 0.7 0.7)
					(thickness 0.15)
				)
				(justify left bottom mirror)
			)
		)
		(property "Value" "C_100n_0402"
			(at -1.022927 -2.155213 90)
			(layer "B.Fab")
			(hide yes)
			(effects
				(font
					(size 0.7 0.7)
					(thickness 0.15)
				)
				(justify left bottom mirror)
			)
		)
		(property "Datasheet" "https://www.murata.com/products/productdetail?partno=GRM155R61H104KE14%23"
			(at 0 0 270)
			(layer "F.Fab")
			(hide yes)
			(effects
				(font
					(size 1.27 1.27)
					(thickness 0.15)
				)
			)
		)
		(property "Description" "SMD Multilayer Ceramic Capacitor, 0.1 µF, 50 V, 0402 [1005 Metric], ± 10%, X5R, GRM Series"
			(at 0 0 270)
			(layer "F.Fab")
			(hide yes)
			(effects
				(font
					(size 1.27 1.27)
					(thickness 0.15)
				)
			)
		)
		(property "Author" "Antmicro"
			(at 55.85 347.65 0)
			(layer "B.Fab")
			(hide yes)
			(effects
				(font
					(size 1 1)
					(thickness 0.15)
				)
				(justify mirror)
			)
		)
		(property "Dielectric" "X5R"
			(at 55.85 347.65 0)
			(layer "B.Fab")
			(hide yes)
			(effects
				(font
					(size 1 1)
					(thickness 0.15)
				)
				(justify mirror)
			)
		)
		(property "License" "Apache-2.0"
			(at 55.85 347.65 0)
			(layer "B.Fab")
			(hide yes)
			(effects
				(font
					(size 1 1)
					(thickness 0.15)
				)
				(justify mirror)
			)
		)
		(property "MPN" "GRM155R61H104KE14D"
			(at 55.85 347.65 0)
			(layer "B.Fab")
			(hide yes)
			(effects
				(font
					(size 1 1)
					(thickness 0.15)
				)
				(justify mirror)
			)
		)
		(property "Manufacturer" "Murata"
			(at 55.85 347.65 0)
			(layer "B.Fab")
			(hide yes)
			(effects
				(font
					(size 1 1)
					(thickness 0.15)
				)
				(justify mirror)
			)
		)
		(property "Public" ""
			(at 55.85 347.65 0)
			(layer "B.Fab")
			(hide yes)
			(effects
				(font
					(size 1 1)
					(thickness 0.15)
				)
				(justify mirror)
			)
		)
		(property "Val" "100n"
			(at 55.85 347.65 0)
			(layer "B.Fab")
			(hide yes)
			(effects
				(font
					(size 1 1)
					(thickness 0.15)
				)
				(justify mirror)
			)
		)
		(property "Voltage" "50V"
			(at 55.85 347.65 0)
			(layer "B.Fab")
			(hide yes)
			(effects
				(font
					(size 1 1)
					(thickness 0.15)
				)
				(justify mirror)
			)
		)
		(sheetname "/MIPI CrossLink/")
		(sheetfile "crosslink.kicad_sch")
		(attr smd)
		(fp_rect
			(start -0.925 0.47)
			(end 0.925 -0.47)
			(stroke
				(width 0.05)
				(type default)
			)
			(fill no)
			(layer "B.CrtYd")
		)
		(fp_line
			(start -0.494 0.25)
			(end 0.504 0.25)
			(stroke
				(width 0.15)
				(type solid)
			)
			(layer "B.Fab")
		)
		(fp_line
			(start 0.504 0.25)
			(end 0.504 -0.248)
			(stroke
				(width 0.15)
				(type solid)
			)
			(layer "B.Fab")
		)
		(fp_line
			(start -0.494 -0.248)
			(end -0.494 0.25)
			(stroke
				(width 0.15)
				(type solid)
			)
			(layer "B.Fab")
		)
		(fp_line
			(start 0.504 -0.248)
			(end -0.494 -0.248)
			(stroke
				(width 0.15)
				(type solid)
			)
			(layer "B.Fab")
		)
		(fp_text user "Author: Antmicro"
			(at -0.939 -3.399 90)
			(layer "B.Fab")
			(effects
				(font
					(size 0.7 0.7)
					(thickness 0.15)
				)
				(justify left bottom mirror)
			)
		)
		(fp_text user "${REFERENCE}"
			(at -0.939 -4.599 90)
			(layer "B.Fab")
			(effects
				(font
					(size 0.7 0.7)
					(thickness 0.15)
				)
				(justify left bottom mirror)
			)
		)
		(fp_text user "License: Apache-2.0"
			(at -0.939 -5.799 90)
			(layer "B.Fab")
			(effects
				(font
					(size 0.7 0.7)
					(thickness 0.15)
				)
				(justify left bottom mirror)
			)
		)
		(pad "1" smd roundrect
			(at -0.48 0 270)
			(size 0.59 0.64)
			(layers "B.Cu" "B.Mask" "B.Paste")
			(roundrect_rratio 0.25)
			(net 417 "GND")
			(pintype "passive")
		)
		(pad "2" smd roundrect
			(at 0.48 0 270)
			(size 0.59 0.64)
			(layers "B.Cu" "B.Mask" "B.Paste")
			(roundrect_rratio 0.25)
			(net 191 "/MIPI CrossLink/CL_VCCIO2")
			(pintype "passive")
		)
	)
	(footprint "antmicro-footprints:R_0402_1005Metric"
		(layer "B.Cu")
		(at 213.415 146.1 180)
		(descr "Resistor SMD 0402")
		(tags "resistor SMD 0402")
		(property "Reference" "R166"
			(at -1.21 -2.45 0)
			(layer "B.SilkS")
			(effects
				(font
					(size 0.7 0.7)
					(thickness 0.15)
				)
				(justify left bottom mirror)
			)
		)
		(property "Value" "R_12k_0402"
			(at -1.011843 -1.772047 0)
			(layer "B.Fab")
			(hide yes)
			(effects
				(font
					(size 0.7 0.7)
					(thickness 0.15)
				)
				(justify left bottom mirror)
			)
		)
		(property "Datasheet" "https://www.bourns.com/docs/product-datasheets/cr.pdf"
			(at 0 0 180)
			(layer "F.Fab")
			(hide yes)
			(effects
				(font
					(size 1.27 1.27)
					(thickness 0.15)
				)
			)
		)
		(property "Description" "SMD Chip Resistor, 12 kohm, ± 1%, 62.5 mW, 0402 [1005 Metric], Thick Film, General Purpose"
			(at 0 0 180)
			(layer "F.Fab")
			(hide yes)
			(effects
				(font
					(size 1.27 1.27)
					(thickness 0.15)
				)
			)
		)
		(property "Author" "Antmicro"
			(at 426.83 292.2 0)
			(layer "B.Fab")
			(hide yes)
			(effects
				(font
					(size 1 1)
					(thickness 0.15)
				)
				(justify mirror)
			)
		)
		(property "License" "Apache-2.0"
			(at 426.83 292.2 0)
			(layer "B.Fab")
			(hide yes)
			(effects
				(font
					(size 1 1)
					(thickness 0.15)
				)
				(justify mirror)
			)
		)
		(property "MPN" "CR0402-FX-1202GLF"
			(at 426.83 292.2 0)
			(layer "B.Fab")
			(hide yes)
			(effects
				(font
					(size 1 1)
					(thickness 0.15)
				)
				(justify mirror)
			)
		)
		(property "Manufacturer" "Bourns"
			(at 426.83 292.2 0)
			(layer "B.Fab")
			(hide yes)
			(effects
				(font
					(size 1 1)
					(thickness 0.15)
				)
				(justify mirror)
			)
		)
		(property "Public" ""
			(at 426.83 292.2 0)
			(layer "B.Fab")
			(hide yes)
			(effects
				(font
					(size 1 1)
					(thickness 0.15)
				)
				(justify mirror)
			)
		)
		(property "Tolerance" "1%"
			(at 426.83 292.2 0)
			(layer "B.Fab")
			(hide yes)
			(effects
				(font
					(size 1 1)
					(thickness 0.15)
				)
				(justify mirror)
			)
		)
		(property "Val" "12k"
			(at 426.83 292.2 0)
			(layer "B.Fab")
			(hide yes)
			(effects
				(font
					(size 1 1)
					(thickness 0.15)
				)
				(justify mirror)
			)
		)
		(sheetname "/USB/")
		(sheetfile "usb.kicad_sch")
		(attr smd)
		(fp_rect
			(start -0.925 0.47)
			(end 0.925 -0.47)
			(stroke
				(width 0.05)
				(type default)
			)
			(fill no)
			(layer "B.CrtYd")
		)
		(fp_rect
			(start -0.5 0.25)
			(end 0.5 -0.25)
			(stroke
				(width 0.15)
				(type solid)
			)
			(fill no)
			(layer "B.Fab")
		)
		(fp_text user "License: Apache-2.0"
			(at -0.95 -5.169 0)
			(layer "B.Fab")
			(effects
				(font
					(size 0.7 0.7)
					(thickness 0.15)
				)
				(justify left bottom mirror)
			)
		)
		(fp_text user "${REFERENCE}"
			(at -0.95 -3.168 0)
			(layer "B.Fab")
			(effects
				(font
					(size 0.7 0.7)
					(thickness 0.15)
				)
				(justify left bottom mirror)
			)
		)
		(fp_text user "Author: Antmicro"
			(at -0.95 -4.169 0)
			(layer "B.Fab")
			(effects
				(font
					(size 0.7 0.7)
					(thickness 0.15)
				)
				(justify left bottom mirror)
			)
		)
		(pad "1" smd roundrect
			(at -0.48 0 180)
			(size 0.59 0.64)
			(layers "B.Cu" "B.Mask" "B.Paste")
			(roundrect_rratio 0.25)
			(net 417 "GND")
			(pintype "passive")
		)
		(pad "2" smd roundrect
			(at 0.48 0 180)
			(size 0.59 0.64)
			(layers "B.Cu" "B.Mask" "B.Paste")
			(roundrect_rratio 0.25)
			(net 325 "Net-(U28-R_{BIAS})")
			(pintype "passive")
		)
	)
	(footprint "antmicro-footprints:R_0402_1005Metric"
		(layer "B.Cu")
		(at 179.75 145.55 90)
		(descr "Resistor SMD 0402")
		(tags "resistor SMD 0402")
		(property "Reference" "R83"
			(at -2.85 2.2 315)
			(layer "B.SilkS")
			(effects
				(font
					(size 0.7 0.7)
					(thickness 0.15)
				)
				(justify left bottom mirror)
			)
		)
		(property "Value" "R_10k_0402"
			(at -1.011843 -1.772047 270)
			(layer "B.Fab")
			(hide yes)
			(effects
				(font
					(size 0.7 0.7)
					(thickness 0.15)
				)
				(justify left bottom mirror)
			)
		)
		(property "Datasheet" "https://www.bourns.com/docs/product-datasheets/cr.pdf"
			(at 0 0 90)
			(layer "F.Fab")
			(hide yes)
			(effects
				(font
					(size 1.27 1.27)
					(thickness 0.15)
				)
			)
		)
		(property "Description" "SMD Chip Resistor, 10 kohm, ± 1%, 62.5 mW, 0402 [1005 Metric], Thick Film, General Purpose"
			(at 0 0 90)
			(layer "F.Fab")
			(hide yes)
			(effects
				(font
					(size 1.27 1.27)
					(thickness 0.15)
				)
			)
		)
		(property "Author" "Antmicro"
			(at 325.3 -34.2 0)
			(layer "B.Fab")
			(hide yes)
			(effects
				(font
					(size 1 1)
					(thickness 0.15)
				)
				(justify mirror)
			)
		)
		(property "License" "Apache-2.0"
			(at 325.3 -34.2 0)
			(layer "B.Fab")
			(hide yes)
			(effects
				(font
					(size 1 1)
					(thickness 0.15)
				)
				(justify mirror)
			)
		)
		(property "MPN" "CR0402-FX-1002GLF"
			(at 325.3 -34.2 0)
			(layer "B.Fab")
			(hide yes)
			(effects
				(font
					(size 1 1)
					(thickness 0.15)
				)
				(justify mirror)
			)
		)
		(property "Manufacturer" "Bourns"
			(at 325.3 -34.2 0)
			(layer "B.Fab")
			(hide yes)
			(effects
				(font
					(size 1 1)
					(thickness 0.15)
				)
				(justify mirror)
			)
		)
		(property "Public" ""
			(at 325.3 -34.2 0)
			(layer "B.Fab")
			(hide yes)
			(effects
				(font
					(size 1 1)
					(thickness 0.15)
				)
				(justify mirror)
			)
		)
		(property "Tolerance" "1%"
			(at 325.3 -34.2 0)
			(layer "B.Fab")
			(hide yes)
			(effects
				(font
					(size 1 1)
					(thickness 0.15)
				)
				(justify mirror)
			)
		)
		(property "Val" "10k"
			(at 325.3 -34.2 0)
			(layer "B.Fab")
			(hide yes)
			(effects
				(font
					(size 1 1)
					(thickness 0.15)
				)
				(justify mirror)
			)
		)
		(sheetname "/Supply/")
		(sheetfile "supply.kicad_sch")
		(attr smd)
		(fp_rect
			(start -0.925 0.47)
			(end 0.925 -0.47)
			(stroke
				(width 0.05)
				(type default)
			)
			(fill no)
			(layer "B.CrtYd")
		)
		(fp_rect
			(start -0.5 0.25)
			(end 0.5 -0.25)
			(stroke
				(width 0.15)
				(type solid)
			)
			(fill no)
			(layer "B.Fab")
		)
		(fp_text user "${REFERENCE}"
			(at -0.95 -3.168 270)
			(layer "B.Fab")
			(effects
				(font
					(size 0.7 0.7)
					(thickness 0.15)
				)
				(justify left bottom mirror)
			)
		)
		(fp_text user "Author: Antmicro"
			(at -0.95 -4.169 270)
			(layer "B.Fab")
			(effects
				(font
					(size 0.7 0.7)
					(thickness 0.15)
				)
				(justify left bottom mirror)
			)
		)
		(fp_text user "License: Apache-2.0"
			(at -0.95 -5.169 270)
			(layer "B.Fab")
			(effects
				(font
					(size 0.7 0.7)
					(thickness 0.15)
				)
				(justify left bottom mirror)
			)
		)
		(pad "1" smd roundrect
			(at -0.48 0 90)
			(size 0.59 0.64)
			(layers "B.Cu" "B.Mask" "B.Paste")
			(roundrect_rratio 0.25)
			(net 656 "/Supply/PG")
			(pintype "passive")
		)
		(pad "2" smd roundrect
			(at 0.48 0 90)
			(size 0.59 0.64)
			(layers "B.Cu" "B.Mask" "B.Paste")
			(roundrect_rratio 0.25)
			(net 90 "+5V")
			(pintype "passive")
		)
	)
	(footprint "antmicro-footprints:C_0402_1005Metric"
		(layer "B.Cu")
		(at 194.73 133.1)
		(descr "Capacitor SMD 0402")
		(tags "capacitor SMD 0402")
		(property "Reference" "C49"
			(at -1.155 -0.25 180)
			(layer "B.SilkS")
			(effects
				(font
					(size 0.7 0.7)
					(thickness 0.15)
				)
				(justify left bottom mirror)
			)
		)
		(property "Value" "C_10u_0402"
			(at -1.022927 -2.155213 180)
			(layer "B.Fab")
			(hide yes)
			(effects
				(font
					(size 0.7 0.7)
					(thickness 0.15)
				)
				(justify left bottom mirror)
			)
		)
		(property "Datasheet" "https://www.yageo.com/en/Chart/Download/pdf/CC0402MRX5R5BB106"
			(at 0 0 0)
			(layer "F.Fab")
			(hide yes)
			(effects
				(font
					(size 1.27 1.27)
					(thickness 0.15)
				)
			)
		)
		(property "Description" "SMD Multilayer Ceramic Capacitor, 10 µF, 6.3 V, 0402 [1005 Metric], ± 20%, X5R, CC Series"
			(at 0 0 0)
			(layer "F.Fab")
			(hide yes)
			(effects
				(font
					(size 1.27 1.27)
					(thickness 0.15)
				)
			)
		)
		(property "Author" "Antmicro"
			(at 0 0 0)
			(layer "B.Fab")
			(hide yes)
			(effects
				(font
					(size 1 1)
					(thickness 0.15)
				)
				(justify mirror)
			)
		)
		(property "Dielectric" ""
			(at 0 0 0)
			(layer "B.Fab")
			(hide yes)
			(effects
				(font
					(size 1 1)
					(thickness 0.15)
				)
				(justify mirror)
			)
		)
		(property "License" "Apache-2.0"
			(at 0 0 0)
			(layer "B.Fab")
			(hide yes)
			(effects
				(font
					(size 1 1)
					(thickness 0.15)
				)
				(justify mirror)
			)
		)
		(property "MPN" "CC0402MRX5R5BB106"
			(at 0 0 0)
			(layer "B.Fab")
			(hide yes)
			(effects
				(font
					(size 1 1)
					(thickness 0.15)
				)
				(justify mirror)
			)
		)
		(property "Manufacturer" "YAGEO"
			(at 0 0 0)
			(layer "B.Fab")
			(hide yes)
			(effects
				(font
					(size 1 1)
					(thickness 0.15)
				)
				(justify mirror)
			)
		)
		(property "Public" ""
			(at 0 0 0)
			(layer "B.Fab")
			(hide yes)
			(effects
				(font
					(size 1 1)
					(thickness 0.15)
				)
				(justify mirror)
			)
		)
		(property "Val" "10u"
			(at 0 0 0)
			(layer "B.Fab")
			(hide yes)
			(effects
				(font
					(size 1 1)
					(thickness 0.15)
				)
				(justify mirror)
			)
		)
		(property "Voltage" ""
			(at 0 0 0)
			(layer "B.Fab")
			(hide yes)
			(effects
				(font
					(size 1 1)
					(thickness 0.15)
				)
				(justify mirror)
			)
		)
		(sheetname "/FPGA Supply/")
		(sheetfile "fpga-supply.kicad_sch")
		(attr smd)
		(fp_rect
			(start -0.925 0.47)
			(end 0.925 -0.47)
			(stroke
				(width 0.05)
				(type default)
			)
			(fill no)
			(layer "B.CrtYd")
		)
		(fp_line
			(start -0.494 -0.248)
			(end -0.494 0.25)
			(stroke
				(width 0.15)
				(type solid)
			)
			(layer "B.Fab")
		)
		(fp_line
			(start -0.494 0.25)
			(end 0.504 0.25)
			(stroke
				(width 0.15)
				(type solid)
			)
			(layer "B.Fab")
		)
		(fp_line
			(start 0.504 -0.248)
			(end -0.494 -0.248)
			(stroke
				(width 0.15)
				(type solid)
			)
			(layer "B.Fab")
		)
		(fp_line
			(start 0.504 0.25)
			(end 0.504 -0.248)
			(stroke
				(width 0.15)
				(type solid)
			)
			(layer "B.Fab")
		)
		(fp_text user "Author: Antmicro"
			(at -0.939 -3.399 180)
			(layer "B.Fab")
			(effects
				(font
					(size 0.7 0.7)
					(thickness 0.15)
				)
				(justify left bottom mirror)
			)
		)
		(fp_text user "License: Apache-2.0"
			(at -0.939 -5.799 180)
			(layer "B.Fab")
			(effects
				(font
					(size 0.7 0.7)
					(thickness 0.15)
				)
				(justify left bottom mirror)
			)
		)
		(fp_text user "${REFERENCE}"
			(at -0.939 -4.599 180)
			(layer "B.Fab")
			(effects
				(font
					(size 0.7 0.7)
					(thickness 0.15)
				)
				(justify left bottom mirror)
			)
		)
		(pad "1" smd roundrect
			(at -0.48 0)
			(size 0.59 0.64)
			(layers "B.Cu" "B.Mask" "B.Paste")
			(roundrect_rratio 0.25)
			(net 417 "GND")
			(pintype "passive")
		)
		(pad "2" smd roundrect
			(at 0.48 0)
			(size 0.59 0.64)
			(layers "B.Cu" "B.Mask" "B.Paste")
			(roundrect_rratio 0.25)
			(net 48 "+1V8")
			(pintype "passive")
		)
	)
	(footprint "antmicro-footprints:R_0402_1005Metric"
		(layer "B.Cu")
		(at 210.1925 129.35)
		(descr "Resistor SMD 0402")
		(tags "resistor SMD 0402")
		(property "Reference" "R37"
			(at -0.8425 0.628 180)
			(layer "B.SilkS")
			(effects
				(font
					(size 0.7 0.7)
					(thickness 0.15)
				)
				(justify left bottom mirror)
			)
		)
		(property "Value" "R_49k9_0402"
			(at -1.011843 -1.772047 180)
			(layer "B.Fab")
			(hide yes)
			(effects
				(font
					(size 0.7 0.7)
					(thickness 0.15)
				)
				(justify left bottom mirror)
			)
		)
		(property "Datasheet" "https://www.bourns.com/docs/product-datasheets/cr.pdf"
			(at 0 0 0)
			(layer "F.Fab")
			(hide yes)
			(effects
				(font
					(size 1.27 1.27)
					(thickness 0.15)
				)
			)
		)
		(property "Description" "SMD Chip Resistor, 49.9 kohm, ± 1%, 63 mW, 0402 [1005 Metric], Thick Film, General Purpose"
			(at 0 0 0)
			(layer "F.Fab")
			(hide yes)
			(effects
				(font
					(size 1.27 1.27)
					(thickness 0.15)
				)
			)
		)
		(property "Author" "Antmicro"
			(at 0 0 0)
			(layer "B.Fab")
			(hide yes)
			(effects
				(font
					(size 1 1)
					(thickness 0.15)
				)
				(justify mirror)
			)
		)
		(property "License" "Apache-2.0"
			(at 0 0 0)
			(layer "B.Fab")
			(hide yes)
			(effects
				(font
					(size 1 1)
					(thickness 0.15)
				)
				(justify mirror)
			)
		)
		(property "MPN" "CR0402-FX-4992GLF"
			(at 0 0 0)
			(layer "B.Fab")
			(hide yes)
			(effects
				(font
					(size 1 1)
					(thickness 0.15)
				)
				(justify mirror)
			)
		)
		(property "Manufacturer" "Bourns"
			(at 0 0 0)
			(layer "B.Fab")
			(hide yes)
			(effects
				(font
					(size 1 1)
					(thickness 0.15)
				)
				(justify mirror)
			)
		)
		(property "Public" ""
			(at 0 0 0)
			(layer "B.Fab")
			(hide yes)
			(effects
				(font
					(size 1 1)
					(thickness 0.15)
				)
				(justify mirror)
			)
		)
		(property "Tolerance" "1%"
			(at 0 0 0)
			(layer "B.Fab")
			(hide yes)
			(effects
				(font
					(size 1 1)
					(thickness 0.15)
				)
				(justify mirror)
			)
		)
		(property "Val" "49k9"
			(at 0 0 0)
			(layer "B.Fab")
			(hide yes)
			(effects
				(font
					(size 1 1)
					(thickness 0.15)
				)
				(justify mirror)
			)
		)
		(sheetname "/Memory/")
		(sheetfile "memory.kicad_sch")
		(attr smd)
		(fp_rect
			(start -0.925 0.47)
			(end 0.925 -0.47)
			(stroke
				(width 0.05)
				(type default)
			)
			(fill no)
			(layer "B.CrtYd")
		)
		(fp_rect
			(start -0.5 0.25)
			(end 0.5 -0.25)
			(stroke
				(width 0.15)
				(type solid)
			)
			(fill no)
			(layer "B.Fab")
		)
		(fp_text user "License: Apache-2.0"
			(at -0.95 -5.169 180)
			(layer "B.Fab")
			(effects
				(font
					(size 0.7 0.7)
					(thickness 0.15)
				)
				(justify left bottom mirror)
			)
		)
		(fp_text user "${REFERENCE}"
			(at -0.95 -3.168 180)
			(layer "B.Fab")
			(effects
				(font
					(size 0.7 0.7)
					(thickness 0.15)
				)
				(justify left bottom mirror)
			)
		)
		(fp_text user "Author: Antmicro"
			(at -0.95 -4.169 180)
			(layer "B.Fab")
			(effects
				(font
					(size 0.7 0.7)
					(thickness 0.15)
				)
				(justify left bottom mirror)
			)
		)
		(pad "1" smd roundrect
			(at -0.48 0)
			(size 0.59 0.64)
			(layers "B.Cu" "B.Mask" "B.Paste")
			(roundrect_rratio 0.25)
			(net 243 "/FPGA MSSIO/EMMC.DAT1")
			(pintype "passive")
		)
		(pad "2" smd roundrect
			(at 0.48 0)
			(size 0.59 0.64)
			(layers "B.Cu" "B.Mask" "B.Paste")
			(roundrect_rratio 0.25)
			(net 137 "SD_VDD")
			(pintype "passive")
		)
	)
	(footprint "antmicro-footprints:C_0402_1005Metric"
		(layer "B.Cu")
		(at 216.14 152.97 180)
		(descr "Capacitor SMD 0402")
		(tags "capacitor SMD 0402")
		(property "Reference" "C176"
			(at -3.74 -0.6 0)
			(layer "B.SilkS")
			(effects
				(font
					(size 0.7 0.7)
					(thickness 0.15)
				)
				(justify left bottom mirror)
			)
		)
		(property "Value" "C_100n_0402"
			(at -1.022927 -2.155213 0)
			(layer "B.Fab")
			(hide yes)
			(effects
				(font
					(size 0.7 0.7)
					(thickness 0.15)
				)
				(justify left bottom mirror)
			)
		)
		(property "Datasheet" "https://www.murata.com/products/productdetail?partno=GRM155R61H104KE14%23"
			(at 0 0 180)
			(layer "F.Fab")
			(hide yes)
			(effects
				(font
					(size 1.27 1.27)
					(thickness 0.15)
				)
			)
		)
		(property "Description" "SMD Multilayer Ceramic Capacitor, 0.1 µF, 50 V, 0402 [1005 Metric], ± 10%, X5R, GRM Series"
			(at 0 0 180)
			(layer "F.Fab")
			(hide yes)
			(effects
				(font
					(size 1.27 1.27)
					(thickness 0.15)
				)
			)
		)
		(property "Author" "Antmicro"
			(at 432.28 305.94 0)
			(layer "B.Fab")
			(hide yes)
			(effects
				(font
					(size 1 1)
					(thickness 0.15)
				)
				(justify mirror)
			)
		)
		(property "Dielectric" "X5R"
			(at 432.28 305.94 0)
			(layer "B.Fab")
			(hide yes)
			(effects
				(font
					(size 1 1)
					(thickness 0.15)
				)
				(justify mirror)
			)
		)
		(property "License" "Apache-2.0"
			(at 432.28 305.94 0)
			(layer "B.Fab")
			(hide yes)
			(effects
				(font
					(size 1 1)
					(thickness 0.15)
				)
				(justify mirror)
			)
		)
		(property "MPN" "GRM155R61H104KE14D"
			(at 432.28 305.94 0)
			(layer "B.Fab")
			(hide yes)
			(effects
				(font
					(size 1 1)
					(thickness 0.15)
				)
				(justify mirror)
			)
		)
		(property "Manufacturer" "Murata"
			(at 432.28 305.94 0)
			(layer "B.Fab")
			(hide yes)
			(effects
				(font
					(size 1 1)
					(thickness 0.15)
				)
				(justify mirror)
			)
		)
		(property "Public" ""
			(at 432.28 305.94 0)
			(layer "B.Fab")
			(hide yes)
			(effects
				(font
					(size 1 1)
					(thickness 0.15)
				)
				(justify mirror)
			)
		)
		(property "Val" "100n"
			(at 432.28 305.94 0)
			(layer "B.Fab")
			(hide yes)
			(effects
				(font
					(size 1 1)
					(thickness 0.15)
				)
				(justify mirror)
			)
		)
		(property "Voltage" "50V"
			(at 432.28 305.94 0)
			(layer "B.Fab")
			(hide yes)
			(effects
				(font
					(size 1 1)
					(thickness 0.15)
				)
				(justify mirror)
			)
		)
		(sheetname "/USB/")
		(sheetfile "usb.kicad_sch")
		(attr smd)
		(fp_rect
			(start -0.925 0.47)
			(end 0.925 -0.47)
			(stroke
				(width 0.05)
				(type default)
			)
			(fill no)
			(layer "B.CrtYd")
		)
		(fp_line
			(start 0.504 0.25)
			(end 0.504 -0.248)
			(stroke
				(width 0.15)
				(type solid)
			)
			(layer "B.Fab")
		)
		(fp_line
			(start 0.504 -0.248)
			(end -0.494 -0.248)
			(stroke
				(width 0.15)
				(type solid)
			)
			(layer "B.Fab")
		)
		(fp_line
			(start -0.494 0.25)
			(end 0.504 0.25)
			(stroke
				(width 0.15)
				(type solid)
			)
			(layer "B.Fab")
		)
		(fp_line
			(start -0.494 -0.248)
			(end -0.494 0.25)
			(stroke
				(width 0.15)
				(type solid)
			)
			(layer "B.Fab")
		)
		(fp_text user "License: Apache-2.0"
			(at -0.939 -5.799 0)
			(layer "B.Fab")
			(effects
				(font
					(size 0.7 0.7)
					(thickness 0.15)
				)
				(justify left bottom mirror)
			)
		)
		(fp_text user "Author: Antmicro"
			(at -0.939 -3.399 0)
			(layer "B.Fab")
			(effects
				(font
					(size 0.7 0.7)
					(thickness 0.15)
				)
				(justify left bottom mirror)
			)
		)
		(fp_text user "${REFERENCE}"
			(at -0.939 -4.599 0)
			(layer "B.Fab")
			(effects
				(font
					(size 0.7 0.7)
					(thickness 0.15)
				)
				(justify left bottom mirror)
			)
		)
		(pad "1" smd roundrect
			(at -0.48 0 180)
			(size 0.59 0.64)
			(layers "B.Cu" "B.Mask" "B.Paste")
			(roundrect_rratio 0.25)
			(net 417 "GND")
			(pintype "passive")
		)
		(pad "2" smd roundrect
			(at 0.48 0 180)
			(size 0.59 0.64)
			(layers "B.Cu" "B.Mask" "B.Paste")
			(roundrect_rratio 0.25)
			(net 50 "+3V3")
			(pintype "passive")
		)
	)
	(footprint "antmicro-footprints:C_0402_1005Metric"
		(layer "B.Cu")
		(at 184.4 130.25)
		(descr "Capacitor SMD 0402")
		(tags "capacitor SMD 0402")
		(property "Reference" "C155"
			(at -3.75 0.3 0)
			(layer "B.SilkS")
			(effects
				(font
					(size 0.7 0.7)
					(thickness 0.15)
				)
				(justify right bottom mirror)
			)
		)
		(property "Value" "C_1u_0402"
			(at -1.022927 -2.155213 0)
			(layer "B.Fab")
			(hide yes)
			(effects
				(font
					(size 0.7 0.7)
					(thickness 0.15)
				)
				(justify right bottom mirror)
			)
		)
		(property "Datasheet" "https://product.tdk.com/en/search/capacitor/ceramic/mlcc/info?part_no=C1005X6S1A105K050BC"
			(at 0 0 0)
			(layer "F.Fab")
			(hide yes)
			(effects
				(font
					(size 1.27 1.27)
					(thickness 0.15)
				)
			)
		)
		(property "Description" "SMD Multilayer Ceramic Capacitor, 1 µF, 10 V, 0402 [1005 Metric], ± 10%, X6S, C"
			(at 0 0 0)
			(layer "F.Fab")
			(hide yes)
			(effects
				(font
					(size 1.27 1.27)
					(thickness 0.15)
				)
			)
		)
		(property "Author" "Antmicro"
			(at 0 0 0)
			(layer "B.Fab")
			(hide yes)
			(effects
				(font
					(size 1 1)
					(thickness 0.15)
				)
				(justify mirror)
			)
		)
		(property "Dielectric" "X5R"
			(at 0 0 0)
			(layer "B.Fab")
			(hide yes)
			(effects
				(font
					(size 1 1)
					(thickness 0.15)
				)
				(justify mirror)
			)
		)
		(property "License" "Apache-2.0"
			(at 0 0 0)
			(layer "B.Fab")
			(hide yes)
			(effects
				(font
					(size 1 1)
					(thickness 0.15)
				)
				(justify mirror)
			)
		)
		(property "MPN" "C1005X6S1A105K050BC"
			(at 0 0 0)
			(layer "B.Fab")
			(hide yes)
			(effects
				(font
					(size 1 1)
					(thickness 0.15)
				)
				(justify mirror)
			)
		)
		(property "Manufacturer" "TDK"
			(at 0 0 0)
			(layer "B.Fab")
			(hide yes)
			(effects
				(font
					(size 1 1)
					(thickness 0.15)
				)
				(justify mirror)
			)
		)
		(property "Public" ""
			(at 0 0 0)
			(layer "B.Fab")
			(hide yes)
			(effects
				(font
					(size 1 1)
					(thickness 0.15)
				)
				(justify mirror)
			)
		)
		(property "Val" "1u"
			(at 0 0 0)
			(layer "B.Fab")
			(hide yes)
			(effects
				(font
					(size 1 1)
					(thickness 0.15)
				)
				(justify mirror)
			)
		)
		(property "Voltage" "16V"
			(at 0 0 0)
			(layer "B.Fab")
			(hide yes)
			(effects
				(font
					(size 1 1)
					(thickness 0.15)
				)
				(justify mirror)
			)
		)
		(sheetname "/LPDDR4/")
		(sheetfile "lpddr.kicad_sch")
		(attr smd)
		(fp_rect
			(start -0.925 0.47)
			(end 0.925 -0.47)
			(stroke
				(width 0.05)
				(type default)
			)
			(fill no)
			(layer "B.CrtYd")
		)
		(fp_line
			(start -0.494 -0.248)
			(end -0.494 0.25)
			(stroke
				(width 0.15)
				(type solid)
			)
			(layer "B.Fab")
		)
		(fp_line
			(start -0.494 0.25)
			(end 0.504 0.25)
			(stroke
				(width 0.15)
				(type solid)
			)
			(layer "B.Fab")
		)
		(fp_line
			(start 0.504 -0.248)
			(end -0.494 -0.248)
			(stroke
				(width 0.15)
				(type solid)
			)
			(layer "B.Fab")
		)
		(fp_line
			(start 0.504 0.25)
			(end 0.504 -0.248)
			(stroke
				(width 0.15)
				(type solid)
			)
			(layer "B.Fab")
		)
		(fp_text user "${REFERENCE}"
			(at -0.939 -4.599 180)
			(layer "B.Fab")
			(effects
				(font
					(size 0.7 0.7)
					(thickness 0.15)
				)
				(justify left bottom mirror)
			)
		)
		(fp_text user "Author: Antmicro"
			(at -0.939 -3.399 180)
			(layer "B.Fab")
			(effects
				(font
					(size 0.7 0.7)
					(thickness 0.15)
				)
				(justify left bottom mirror)
			)
		)
		(fp_text user "License: Apache-2.0"
			(at -0.939 -5.799 180)
			(layer "B.Fab")
			(effects
				(font
					(size 0.7 0.7)
					(thickness 0.15)
				)
				(justify left bottom mirror)
			)
		)
		(pad "1" smd roundrect
			(at -0.48 0)
			(size 0.59 0.64)
			(layers "B.Cu" "B.Mask" "B.Paste")
			(roundrect_rratio 0.25)
			(net 417 "GND")
			(pintype "passive")
		)
		(pad "2" smd roundrect
			(at 0.48 0)
			(size 0.59 0.64)
			(layers "B.Cu" "B.Mask" "B.Paste")
			(roundrect_rratio 0.25)
			(net 2 "+1V1")
			(pintype "passive")
		)
	)
	(footprint "antmicro-footprints:C_0402_1005Metric"
		(layer "B.Cu")
		(at 208.11 144.54 180)
		(descr "Capacitor SMD 0402")
		(tags "capacitor SMD 0402")
		(property "Reference" "C202"
			(at 5.63 18.4 0)
			(layer "B.SilkS")
			(effects
				(font
					(size 0.7 0.7)
					(thickness 0.15)
				)
				(justify left bottom mirror)
			)
		)
		(property "Value" "C_10u_10V_0402"
			(at -1.022927 -2.155213 0)
			(layer "B.Fab")
			(hide yes)
			(effects
				(font
					(size 0.7 0.7)
					(thickness 0.15)
				)
				(justify left bottom mirror)
			)
		)
		(property "Datasheet" "https://www.murata.com/products/productdetail?partno=GRM155R61A106ME11%23"
			(at 0 0 180)
			(layer "F.Fab")
			(hide yes)
			(effects
				(font
					(size 1.27 1.27)
					(thickness 0.15)
				)
			)
		)
		(property "Description" "Multilayer Ceramic Capacitors MLCC - SMD/SMT 10 uF 10 VDC 20% 0402 X5R"
			(at 0 0 180)
			(layer "F.Fab")
			(hide yes)
			(effects
				(font
					(size 1.27 1.27)
					(thickness 0.15)
				)
			)
		)
		(property "Author" "Antmicro"
			(at 416.22 289.08 0)
			(layer "B.Fab")
			(hide yes)
			(effects
				(font
					(size 1 1)
					(thickness 0.15)
				)
				(justify mirror)
			)
		)
		(property "Dielectric" "X5R"
			(at 416.22 289.08 0)
			(layer "B.Fab")
			(hide yes)
			(effects
				(font
					(size 1 1)
					(thickness 0.15)
				)
				(justify mirror)
			)
		)
		(property "License" "Apache-2.0"
			(at 416.22 289.08 0)
			(layer "B.Fab")
			(hide yes)
			(effects
				(font
					(size 1 1)
					(thickness 0.15)
				)
				(justify mirror)
			)
		)
		(property "MPN" "GRM155R61A106ME11D"
			(at 416.22 289.08 0)
			(layer "B.Fab")
			(hide yes)
			(effects
				(font
					(size 1 1)
					(thickness 0.15)
				)
				(justify mirror)
			)
		)
		(property "Manufacturer" "Murata"
			(at 416.22 289.08 0)
			(layer "B.Fab")
			(hide yes)
			(effects
				(font
					(size 1 1)
					(thickness 0.15)
				)
				(justify mirror)
			)
		)
		(property "Public" ""
			(at 416.22 289.08 0)
			(layer "B.Fab")
			(hide yes)
			(effects
				(font
					(size 1 1)
					(thickness 0.15)
				)
				(justify mirror)
			)
		)
		(property "Val" "10u"
			(at 416.22 289.08 0)
			(layer "B.Fab")
			(hide yes)
			(effects
				(font
					(size 1 1)
					(thickness 0.15)
				)
				(justify mirror)
			)
		)
		(property "Voltage" "10V"
			(at 416.22 289.08 0)
			(layer "B.Fab")
			(hide yes)
			(effects
				(font
					(size 1 1)
					(thickness 0.15)
				)
				(justify mirror)
			)
		)
		(sheetname "/MIPI CrossLink/")
		(sheetfile "crosslink.kicad_sch")
		(attr smd)
		(fp_rect
			(start -0.925 0.47)
			(end 0.925 -0.47)
			(stroke
				(width 0.05)
				(type default)
			)
			(fill no)
			(layer "B.CrtYd")
		)
		(fp_line
			(start 0.504 0.25)
			(end 0.504 -0.248)
			(stroke
				(width 0.15)
				(type solid)
			)
			(layer "B.Fab")
		)
		(fp_line
			(start 0.504 -0.248)
			(end -0.494 -0.248)
			(stroke
				(width 0.15)
				(type solid)
			)
			(layer "B.Fab")
		)
		(fp_line
			(start -0.494 0.25)
			(end 0.504 0.25)
			(stroke
				(width 0.15)
				(type solid)
			)
			(layer "B.Fab")
		)
		(fp_line
			(start -0.494 -0.248)
			(end -0.494 0.25)
			(stroke
				(width 0.15)
				(type solid)
			)
			(layer "B.Fab")
		)
		(fp_text user "${REFERENCE}"
			(at -0.939 -4.599 0)
			(layer "B.Fab")
			(effects
				(font
					(size 0.7 0.7)
					(thickness 0.15)
				)
				(justify left bottom mirror)
			)
		)
		(fp_text user "Author: Antmicro"
			(at -0.939 -3.399 0)
			(layer "B.Fab")
			(effects
				(font
					(size 0.7 0.7)
					(thickness 0.15)
				)
				(justify left bottom mirror)
			)
		)
		(fp_text user "License: Apache-2.0"
			(at -0.939 -5.799 0)
			(layer "B.Fab")
			(effects
				(font
					(size 0.7 0.7)
					(thickness 0.15)
				)
				(justify left bottom mirror)
			)
		)
		(pad "1" smd roundrect
			(at -0.48 0 180)
			(size 0.59 0.64)
			(layers "B.Cu" "B.Mask" "B.Paste")
			(roundrect_rratio 0.25)
			(net 417 "GND")
			(pintype "passive")
		)
		(pad "2" smd roundrect
			(at 0.48 0 180)
			(size 0.59 0.64)
			(layers "B.Cu" "B.Mask" "B.Paste")
			(roundrect_rratio 0.25)
			(net 185 "/MIPI CrossLink/CL_VCCIO1")
			(pintype "passive")
		)
	)
	(footprint "antmicro-footprints:R_0402_1005Metric"
		(layer "B.Cu")
		(at 218.975 138.775 180)
		(descr "Resistor SMD 0402")
		(tags "resistor SMD 0402")
		(property "Reference" "R51"
			(at 0.75 -0.475 0)
			(layer "B.SilkS")
			(effects
				(font
					(size 0.7 0.7)
					(thickness 0.15)
				)
				(justify left bottom mirror)
			)
		)
		(property "Value" "R_10k_0402"
			(at -1.011843 -1.772047 0)
			(layer "B.Fab")
			(hide yes)
			(effects
				(font
					(size 0.7 0.7)
					(thickness 0.15)
				)
				(justify left bottom mirror)
			)
		)
		(property "Datasheet" "https://www.bourns.com/docs/product-datasheets/cr.pdf"
			(at 0 0 180)
			(layer "F.Fab")
			(hide yes)
			(effects
				(font
					(size 1.27 1.27)
					(thickness 0.15)
				)
			)
		)
		(property "Description" "SMD Chip Resistor, 10 kohm, ± 1%, 62.5 mW, 0402 [1005 Metric], Thick Film, General Purpose"
			(at 0 0 180)
			(layer "F.Fab")
			(hide yes)
			(effects
				(font
					(size 1.27 1.27)
					(thickness 0.15)
				)
			)
		)
		(property "Author" "Antmicro"
			(at 437.95 277.55 0)
			(layer "B.Fab")
			(hide yes)
			(effects
				(font
					(size 1 1)
					(thickness 0.15)
				)
				(justify mirror)
			)
		)
		(property "License" "Apache-2.0"
			(at 437.95 277.55 0)
			(layer "B.Fab")
			(hide yes)
			(effects
				(font
					(size 1 1)
					(thickness 0.15)
				)
				(justify mirror)
			)
		)
		(property "MPN" "CR0402-FX-1002GLF"
			(at 437.95 277.55 0)
			(layer "B.Fab")
			(hide yes)
			(effects
				(font
					(size 1 1)
					(thickness 0.15)
				)
				(justify mirror)
			)
		)
		(property "Manufacturer" "Bourns"
			(at 437.95 277.55 0)
			(layer "B.Fab")
			(hide yes)
			(effects
				(font
					(size 1 1)
					(thickness 0.15)
				)
				(justify mirror)
			)
		)
		(property "Public" ""
			(at 437.95 277.55 0)
			(layer "B.Fab")
			(hide yes)
			(effects
				(font
					(size 1 1)
					(thickness 0.15)
				)
				(justify mirror)
			)
		)
		(property "Tolerance" "1%"
			(at 437.95 277.55 0)
			(layer "B.Fab")
			(hide yes)
			(effects
				(font
					(size 1 1)
					(thickness 0.15)
				)
				(justify mirror)
			)
		)
		(property "Val" "10k"
			(at 437.95 277.55 0)
			(layer "B.Fab")
			(hide yes)
			(effects
				(font
					(size 1 1)
					(thickness 0.15)
				)
				(justify mirror)
			)
		)
		(sheetname "/Memory/")
		(sheetfile "memory.kicad_sch")
		(attr smd)
		(fp_rect
			(start -0.925 0.47)
			(end 0.925 -0.47)
			(stroke
				(width 0.05)
				(type default)
			)
			(fill no)
			(layer "B.CrtYd")
		)
		(fp_rect
			(start -0.5 0.25)
			(end 0.5 -0.25)
			(stroke
				(width 0.15)
				(type solid)
			)
			(fill no)
			(layer "B.Fab")
		)
		(fp_text user "${REFERENCE}"
			(at -0.95 -3.168 0)
			(layer "B.Fab")
			(effects
				(font
					(size 0.7 0.7)
					(thickness 0.15)
				)
				(justify left bottom mirror)
			)
		)
		(fp_text user "License: Apache-2.0"
			(at -0.95 -5.169 0)
			(layer "B.Fab")
			(effects
				(font
					(size 0.7 0.7)
					(thickness 0.15)
				)
				(justify left bottom mirror)
			)
		)
		(fp_text user "Author: Antmicro"
			(at -0.95 -4.169 0)
			(layer "B.Fab")
			(effects
				(font
					(size 0.7 0.7)
					(thickness 0.15)
				)
				(justify left bottom mirror)
			)
		)
		(pad "1" smd roundrect
			(at -0.48 0 180)
			(size 0.59 0.64)
			(layers "B.Cu" "B.Mask" "B.Paste")
			(roundrect_rratio 0.25)
			(net 517 "SD_VDD_FLAG")
			(pintype "passive")
		)
		(pad "2" smd roundrect
			(at 0.48 0 180)
			(size 0.59 0.64)
			(layers "B.Cu" "B.Mask" "B.Paste")
			(roundrect_rratio 0.25)
			(net 649 "VDD")
			(pintype "passive")
		)
	)
	(footprint "antmicro-footprints:C_0402_1005Metric"
		(layer "B.Cu")
		(at 180.05 134.45 -90)
		(descr "Capacitor SMD 0402")
		(tags "capacitor SMD 0402")
		(property "Reference" "C263"
			(at -1.975 -1.47 90)
			(layer "B.SilkS")
			(effects
				(font
					(size 0.7 0.7)
					(thickness 0.15)
				)
				(justify left bottom mirror)
			)
		)
		(property "Value" "C_10u_0402"
			(at -1.022927 -2.155213 90)
			(layer "B.Fab")
			(hide yes)
			(effects
				(font
					(size 0.7 0.7)
					(thickness 0.15)
				)
				(justify left bottom mirror)
			)
		)
		(property "Datasheet" "https://www.yageo.com/en/Chart/Download/pdf/CC0402MRX5R5BB106"
			(at 0 0 270)
			(layer "F.Fab")
			(hide yes)
			(effects
				(font
					(size 1.27 1.27)
					(thickness 0.15)
				)
			)
		)
		(property "Description" "SMD Multilayer Ceramic Capacitor, 10 µF, 6.3 V, 0402 [1005 Metric], ± 20%, X5R, CC Series"
			(at 0 0 270)
			(layer "F.Fab")
			(hide yes)
			(effects
				(font
					(size 1.27 1.27)
					(thickness 0.15)
				)
			)
		)
		(property "Author" "Antmicro"
			(at 45.6 314.5 0)
			(layer "B.Fab")
			(hide yes)
			(effects
				(font
					(size 1 1)
					(thickness 0.15)
				)
				(justify mirror)
			)
		)
		(property "Dielectric" ""
			(at 45.6 314.5 0)
			(layer "B.Fab")
			(hide yes)
			(effects
				(font
					(size 1 1)
					(thickness 0.15)
				)
				(justify mirror)
			)
		)
		(property "License" "Apache-2.0"
			(at 45.6 314.5 0)
			(layer "B.Fab")
			(hide yes)
			(effects
				(font
					(size 1 1)
					(thickness 0.15)
				)
				(justify mirror)
			)
		)
		(property "MPN" "CC0402MRX5R5BB106"
			(at 45.6 314.5 0)
			(layer "B.Fab")
			(hide yes)
			(effects
				(font
					(size 1 1)
					(thickness 0.15)
				)
				(justify mirror)
			)
		)
		(property "Manufacturer" "YAGEO"
			(at 45.6 314.5 0)
			(layer "B.Fab")
			(hide yes)
			(effects
				(font
					(size 1 1)
					(thickness 0.15)
				)
				(justify mirror)
			)
		)
		(property "Public" ""
			(at 45.6 314.5 0)
			(layer "B.Fab")
			(hide yes)
			(effects
				(font
					(size 1 1)
					(thickness 0.15)
				)
				(justify mirror)
			)
		)
		(property "Val" "10u"
			(at 45.6 314.5 0)
			(layer "B.Fab")
			(hide yes)
			(effects
				(font
					(size 1 1)
					(thickness 0.15)
				)
				(justify mirror)
			)
		)
		(property "Voltage" ""
			(at 45.6 314.5 0)
			(layer "B.Fab")
			(hide yes)
			(effects
				(font
					(size 1 1)
					(thickness 0.15)
				)
				(justify mirror)
			)
		)
		(sheetname "/LPDDR4/")
		(sheetfile "lpddr.kicad_sch")
		(attr smd)
		(fp_rect
			(start -0.925 0.47)
			(end 0.925 -0.47)
			(stroke
				(width 0.05)
				(type default)
			)
			(fill no)
			(layer "B.CrtYd")
		)
		(fp_line
			(start -0.494 0.25)
			(end 0.504 0.25)
			(stroke
				(width 0.15)
				(type solid)
			)
			(layer "B.Fab")
		)
		(fp_line
			(start 0.504 0.25)
			(end 0.504 -0.248)
			(stroke
				(width 0.15)
				(type solid)
			)
			(layer "B.Fab")
		)
		(fp_line
			(start -0.494 -0.248)
			(end -0.494 0.25)
			(stroke
				(width 0.15)
				(type solid)
			)
			(layer "B.Fab")
		)
		(fp_line
			(start 0.504 -0.248)
			(end -0.494 -0.248)
			(stroke
				(width 0.15)
				(type solid)
			)
			(layer "B.Fab")
		)
		(fp_text user "Author: Antmicro"
			(at -0.939 -3.399 90)
			(layer "B.Fab")
			(effects
				(font
					(size 0.7 0.7)
					(thickness 0.15)
				)
				(justify left bottom mirror)
			)
		)
		(fp_text user "License: Apache-2.0"
			(at -0.939 -5.799 90)
			(layer "B.Fab")
			(effects
				(font
					(size 0.7 0.7)
					(thickness 0.15)
				)
				(justify left bottom mirror)
			)
		)
		(fp_text user "${REFERENCE}"
			(at -0.939 -4.599 90)
			(layer "B.Fab")
			(effects
				(font
					(size 0.7 0.7)
					(thickness 0.15)
				)
				(justify left bottom mirror)
			)
		)
		(pad "1" smd roundrect
			(at -0.48 0 270)
			(size 0.59 0.64)
			(layers "B.Cu" "B.Mask" "B.Paste")
			(roundrect_rratio 0.25)
			(net 417 "GND")
			(pintype "passive")
		)
		(pad "2" smd roundrect
			(at 0.48 0 270)
			(size 0.59 0.64)
			(layers "B.Cu" "B.Mask" "B.Paste")
			(roundrect_rratio 0.25)
			(net 2 "+1V1")
			(pintype "passive")
		)
	)
	(footprint "antmicro-footprints:R_0402_1005Metric"
		(layer "B.Cu")
		(at 215.061 124.754 180)
		(descr "Resistor SMD 0402")
		(tags "resistor SMD 0402")
		(property "Reference" "R96"
			(at -2.964 -0.296 0)
			(layer "B.SilkS")
			(effects
				(font
					(size 0.7 0.7)
					(thickness 0.15)
				)
				(justify left bottom mirror)
			)
		)
		(property "Value" "R_2k2_0402"
			(at -1.011843 -1.772047 0)
			(layer "B.Fab")
			(hide yes)
			(effects
				(font
					(size 0.7 0.7)
					(thickness 0.15)
				)
				(justify left bottom mirror)
			)
		)
		(property "Datasheet" "https://www.bourns.com/docs/product-datasheets/cr.pdf"
			(at 0 0 180)
			(layer "F.Fab")
			(hide yes)
			(effects
				(font
					(size 1.27 1.27)
					(thickness 0.15)
				)
			)
		)
		(property "Description" "SMD Chip Resistor, 2.2 kohm, ± 1%, 62.5 mW, 0402 [1005 Metric], Thick Film, General Purpose"
			(at 0 0 180)
			(layer "F.Fab")
			(hide yes)
			(effects
				(font
					(size 1.27 1.27)
					(thickness 0.15)
				)
			)
		)
		(property "Author" "Antmicro"
			(at 430.122 249.508 0)
			(layer "B.Fab")
			(hide yes)
			(effects
				(font
					(size 1 1)
					(thickness 0.15)
				)
				(justify mirror)
			)
		)
		(property "License" "Apache-2.0"
			(at 430.122 249.508 0)
			(layer "B.Fab")
			(hide yes)
			(effects
				(font
					(size 1 1)
					(thickness 0.15)
				)
				(justify mirror)
			)
		)
		(property "MPN" "CR0402-FX-2201GLF"
			(at 430.122 249.508 0)
			(layer "B.Fab")
			(hide yes)
			(effects
				(font
					(size 1 1)
					(thickness 0.15)
				)
				(justify mirror)
			)
		)
		(property "Manufacturer" "Bourns"
			(at 430.122 249.508 0)
			(layer "B.Fab")
			(hide yes)
			(effects
				(font
					(size 1 1)
					(thickness 0.15)
				)
				(justify mirror)
			)
		)
		(property "Public" ""
			(at 430.122 249.508 0)
			(layer "B.Fab")
			(hide yes)
			(effects
				(font
					(size 1 1)
					(thickness 0.15)
				)
				(justify mirror)
			)
		)
		(property "Tolerance" "1%"
			(at 430.122 249.508 0)
			(layer "B.Fab")
			(hide yes)
			(effects
				(font
					(size 1 1)
					(thickness 0.15)
				)
				(justify mirror)
			)
		)
		(property "Val" "2k2"
			(at 430.122 249.508 0)
			(layer "B.Fab")
			(hide yes)
			(effects
				(font
					(size 1 1)
					(thickness 0.15)
				)
				(justify mirror)
			)
		)
		(sheetname "/Ethernet/")
		(sheetfile "ethernet.kicad_sch")
		(attr smd)
		(fp_rect
			(start -0.925 0.47)
			(end 0.925 -0.47)
			(stroke
				(width 0.05)
				(type default)
			)
			(fill no)
			(layer "B.CrtYd")
		)
		(fp_rect
			(start -0.5 0.25)
			(end 0.5 -0.25)
			(stroke
				(width 0.15)
				(type solid)
			)
			(fill no)
			(layer "B.Fab")
		)
		(fp_text user "Author: Antmicro"
			(at -0.95 -4.169 0)
			(layer "B.Fab")
			(effects
				(font
					(size 0.7 0.7)
					(thickness 0.15)
				)
				(justify left bottom mirror)
			)
		)
		(fp_text user "${REFERENCE}"
			(at -0.95 -3.168 0)
			(layer "B.Fab")
			(effects
				(font
					(size 0.7 0.7)
					(thickness 0.15)
				)
				(justify left bottom mirror)
			)
		)
		(fp_text user "License: Apache-2.0"
			(at -0.95 -5.169 0)
			(layer "B.Fab")
			(effects
				(font
					(size 0.7 0.7)
					(thickness 0.15)
				)
				(justify left bottom mirror)
			)
		)
		(pad "1" smd roundrect
			(at -0.48 0 180)
			(size 0.59 0.64)
			(layers "B.Cu" "B.Mask" "B.Paste")
			(roundrect_rratio 0.25)
			(net 417 "GND")
			(pintype "passive")
		)
		(pad "2" smd roundrect
			(at 0.48 0 180)
			(size 0.59 0.64)
			(layers "B.Cu" "B.Mask" "B.Paste")
			(roundrect_rratio 0.25)
			(net 282 "/Ethernet/ETH_RXCTRL")
			(pintype "passive")
		)
	)
	(footprint "antmicro-footprints:C_0402_1005Metric"
		(layer "B.Cu")
		(at 222.35 125.955 90)
		(descr "Capacitor SMD 0402")
		(tags "capacitor SMD 0402")
		(property "Reference" "C82"
			(at -0.795 2.525 90)
			(layer "B.SilkS")
			(effects
				(font
					(size 0.7 0.7)
					(thickness 0.15)
				)
				(justify right bottom mirror)
			)
		)
		(property "Value" "C_100n_0402"
			(at -1.022927 -2.155213 90)
			(layer "B.Fab")
			(hide yes)
			(effects
				(font
					(size 0.7 0.7)
					(thickness 0.15)
				)
				(justify right bottom mirror)
			)
		)
		(property "Datasheet" "https://www.murata.com/products/productdetail?partno=GRM155R61H104KE14%23"
			(at 0 0 90)
			(layer "F.Fab")
			(hide yes)
			(effects
				(font
					(size 1.27 1.27)
					(thickness 0.15)
				)
			)
		)
		(property "Description" "SMD Multilayer Ceramic Capacitor, 0.1 µF, 50 V, 0402 [1005 Metric], ± 10%, X5R, GRM Series"
			(at 0 0 90)
			(layer "F.Fab")
			(hide yes)
			(effects
				(font
					(size 1.27 1.27)
					(thickness 0.15)
				)
			)
		)
		(property "Author" "Antmicro"
			(at 348.305 -96.395 0)
			(layer "B.Fab")
			(hide yes)
			(effects
				(font
					(size 1 1)
					(thickness 0.15)
				)
				(justify mirror)
			)
		)
		(property "Dielectric" "X5R"
			(at 348.305 -96.395 0)
			(layer "B.Fab")
			(hide yes)
			(effects
				(font
					(size 1 1)
					(thickness 0.15)
				)
				(justify mirror)
			)
		)
		(property "License" "Apache-2.0"
			(at 348.305 -96.395 0)
			(layer "B.Fab")
			(hide yes)
			(effects
				(font
					(size 1 1)
					(thickness 0.15)
				)
				(justify mirror)
			)
		)
		(property "MPN" "GRM155R61H104KE14D"
			(at 348.305 -96.395 0)
			(layer "B.Fab")
			(hide yes)
			(effects
				(font
					(size 1 1)
					(thickness 0.15)
				)
				(justify mirror)
			)
		)
		(property "Manufacturer" "Murata"
			(at 348.305 -96.395 0)
			(layer "B.Fab")
			(hide yes)
			(effects
				(font
					(size 1 1)
					(thickness 0.15)
				)
				(justify mirror)
			)
		)
		(property "Public" ""
			(at 348.305 -96.395 0)
			(layer "B.Fab")
			(hide yes)
			(effects
				(font
					(size 1 1)
					(thickness 0.15)
				)
				(justify mirror)
			)
		)
		(property "Val" "100n"
			(at 348.305 -96.395 0)
			(layer "B.Fab")
			(hide yes)
			(effects
				(font
					(size 1 1)
					(thickness 0.15)
				)
				(justify mirror)
			)
		)
		(property "Voltage" "50V"
			(at 348.305 -96.395 0)
			(layer "B.Fab")
			(hide yes)
			(effects
				(font
					(size 1 1)
					(thickness 0.15)
				)
				(justify mirror)
			)
		)
		(sheetname "/FPGA Config/")
		(sheetfile "fpga-config.kicad_sch")
		(attr smd)
		(fp_rect
			(start -0.925 0.47)
			(end 0.925 -0.47)
			(stroke
				(width 0.05)
				(type default)
			)
			(fill no)
			(layer "B.CrtYd")
		)
		(fp_line
			(start 0.504 -0.248)
			(end -0.494 -0.248)
			(stroke
				(width 0.15)
				(type solid)
			)
			(layer "B.Fab")
		)
		(fp_line
			(start -0.494 -0.248)
			(end -0.494 0.25)
			(stroke
				(width 0.15)
				(type solid)
			)
			(layer "B.Fab")
		)
		(fp_line
			(start 0.504 0.25)
			(end 0.504 -0.248)
			(stroke
				(width 0.15)
				(type solid)
			)
			(layer "B.Fab")
		)
		(fp_line
			(start -0.494 0.25)
			(end 0.504 0.25)
			(stroke
				(width 0.15)
				(type solid)
			)
			(layer "B.Fab")
		)
		(fp_text user "${REFERENCE}"
			(at -0.939 -4.599 270)
			(layer "B.Fab")
			(effects
				(font
					(size 0.7 0.7)
					(thickness 0.15)
				)
				(justify left bottom mirror)
			)
		)
		(fp_text user "Author: Antmicro"
			(at -0.939 -3.399 270)
			(layer "B.Fab")
			(effects
				(font
					(size 0.7 0.7)
					(thickness 0.15)
				)
				(justify left bottom mirror)
			)
		)
		(fp_text user "License: Apache-2.0"
			(at -0.939 -5.799 270)
			(layer "B.Fab")
			(effects
				(font
					(size 0.7 0.7)
					(thickness 0.15)
				)
				(justify left bottom mirror)
			)
		)
		(pad "1" smd roundrect
			(at -0.48 0 90)
			(size 0.59 0.64)
			(layers "B.Cu" "B.Mask" "B.Paste")
			(roundrect_rratio 0.25)
			(net 417 "GND")
			(pintype "passive")
		)
		(pad "2" smd roundrect
			(at 0.48 0 90)
			(size 0.59 0.64)
			(layers "B.Cu" "B.Mask" "B.Paste")
			(roundrect_rratio 0.25)
			(net 50 "+3V3")
			(pintype "passive")
		)
	)
	(footprint "antmicro-footprints:R_0603_1608Metric"
		(layer "B.Cu")
		(at 186.4 147.7 90)
		(descr "Resistor SMD 0603")
		(tags "resistor SMD 0603")
		(property "Reference" "R20"
			(at 0 1.6 270)
			(layer "B.SilkS")
			(effects
				(font
					(size 0.7 0.7)
					(thickness 0.15)
				)
				(justify left bottom mirror)
			)
		)
		(property "Value" "R_0R_22.4A_0603"
			(at 0 -1.6 270)
			(layer "B.Fab")
			(hide yes)
			(effects
				(font
					(size 0.7 0.7)
					(thickness 0.15)
				)
				(justify left bottom mirror)
			)
		)
		(property "Datasheet" "https://fscdn.rohm.com/en/products/databook/datasheet/passive/resistor/chip_resistor/pmr-jpw-e.pdf"
			(at 0 0 90)
			(layer "F.Fab")
			(hide yes)
			(effects
				(font
					(size 1.27 1.27)
					(thickness 0.15)
				)
			)
		)
		(property "Description" "SMD Chip Resistor"
			(at 0 0 90)
			(layer "F.Fab")
			(hide yes)
			(effects
				(font
					(size 1.27 1.27)
					(thickness 0.15)
				)
			)
		)
		(property "Author" "Antmicro"
			(at 334.1 -38.7 0)
			(layer "B.Fab")
			(hide yes)
			(effects
				(font
					(size 1 1)
					(thickness 0.15)
				)
				(justify mirror)
			)
		)
		(property "License" "Apache-2.0"
			(at 334.1 -38.7 0)
			(layer "B.Fab")
			(hide yes)
			(effects
				(font
					(size 1 1)
					(thickness 0.15)
				)
				(justify mirror)
			)
		)
		(property "MPN" "PMR03EZPJ000"
			(at 334.1 -38.7 0)
			(layer "B.Fab")
			(hide yes)
			(effects
				(font
					(size 1 1)
					(thickness 0.15)
				)
				(justify mirror)
			)
		)
		(property "Manufacturer" "ROHM Semiconductor"
			(at 334.1 -38.7 0)
			(layer "B.Fab")
			(hide yes)
			(effects
				(font
					(size 1 1)
					(thickness 0.15)
				)
				(justify mirror)
			)
		)
		(property "Max. Curr." "22.4A"
			(at 334.1 -38.7 0)
			(layer "B.Fab")
			(hide yes)
			(effects
				(font
					(size 1 1)
					(thickness 0.15)
				)
				(justify mirror)
			)
		)
		(property "Public" ""
			(at 334.1 -38.7 0)
			(layer "B.Fab")
			(hide yes)
			(effects
				(font
					(size 1 1)
					(thickness 0.15)
				)
				(justify mirror)
			)
		)
		(property "Tolerance" "template_tolerance"
			(at 334.1 -38.7 0)
			(layer "B.Fab")
			(hide yes)
			(effects
				(font
					(size 1 1)
					(thickness 0.15)
				)
				(justify mirror)
			)
		)
		(property "Val" "0R"
			(at 334.1 -38.7 0)
			(layer "B.Fab")
			(hide yes)
			(effects
				(font
					(size 1 1)
					(thickness 0.15)
				)
				(justify mirror)
			)
		)
		(sheetname "/Supply/")
		(sheetfile "supply.kicad_sch")
		(attr smd)
		(fp_line
			(start -0.15 -0.4)
			(end 0.15 -0.4)
			(stroke
				(width 0.15)
				(type solid)
			)
			(layer "B.SilkS")
		)
		(fp_line
			(start -0.15 0.4)
			(end 0.15 0.4)
			(stroke
				(width 0.15)
				(type solid)
			)
			(layer "B.SilkS")
		)
		(fp_rect
			(start -1.25 0.65)
			(end 1.25 -0.65)
			(stroke
				(width 0.05)
				(type solid)
			)
			(fill no)
			(layer "B.CrtYd")
		)
		(fp_rect
			(start -0.8 0.4)
			(end 0.8 -0.4)
			(stroke
				(width 0.15)
				(type solid)
			)
			(fill no)
			(layer "B.Fab")
		)
		(fp_text user "Author: Antmicro"
			(at -1.25 -4.9 270)
			(layer "B.Fab")
			(effects
				(font
					(size 0.7 0.7)
					(thickness 0.15)
				)
				(justify left bottom mirror)
			)
		)
		(fp_text user "License: Apache-2.0"
			(at -1.25 -5.9 270)
			(layer "B.Fab")
			(effects
				(font
					(size 0.7 0.7)
					(thickness 0.15)
				)
				(justify left bottom mirror)
			)
		)
		(fp_text user "${REFERENCE}"
			(at -1.25 -3.898 270)
			(layer "B.Fab")
			(effects
				(font
					(size 0.7 0.7)
					(thickness 0.15)
				)
				(justify left bottom mirror)
			)
		)
		(pad "1" smd roundrect
			(at -0.7 0 90)
			(size 0.8 1)
			(layers "B.Cu" "B.Mask" "B.Paste")
			(roundrect_rratio 0.2)
			(net 522 "/Supply/1V05_REG")
			(pintype "passive")
		)
		(pad "2" smd roundrect
			(at 0.7 0 90)
			(size 0.8 1)
			(layers "B.Cu" "B.Mask" "B.Paste")
			(roundrect_rratio 0.2)
			(net 47 "+1V05")
			(pintype "passive")
		)
	)
	(footprint "antmicro-footprints:C_0402_1005Metric"
		(layer "B.Cu")
		(at 175.248 132.7165 90)
		(descr "Capacitor SMD 0402")
		(tags "capacitor SMD 0402")
		(property "Reference" "C129"
			(at -0.9235 2.312 315)
			(layer "B.SilkS")
			(effects
				(font
					(size 0.7 0.7)
					(thickness 0.15)
				)
				(justify left bottom mirror)
			)
		)
		(property "Value" "C_1u_0402"
			(at -1.022927 -2.155213 270)
			(layer "B.Fab")
			(hide yes)
			(effects
				(font
					(size 0.7 0.7)
					(thickness 0.15)
				)
				(justify left bottom mirror)
			)
		)
		(property "Datasheet" "https://product.tdk.com/en/search/capacitor/ceramic/mlcc/info?part_no=C1005X6S1A105K050BC"
			(at 0 0 90)
			(layer "F.Fab")
			(hide yes)
			(effects
				(font
					(size 1.27 1.27)
					(thickness 0.15)
				)
			)
		)
		(property "Description" "SMD Multilayer Ceramic Capacitor, 1 µF, 10 V, 0402 [1005 Metric], ± 10%, X6S, C"
			(at 0 0 90)
			(layer "F.Fab")
			(hide yes)
			(effects
				(font
					(size 1.27 1.27)
					(thickness 0.15)
				)
			)
		)
		(property "Author" "Antmicro"
			(at 307.9645 -42.5315 0)
			(layer "B.Fab")
			(hide yes)
			(effects
				(font
					(size 1 1)
					(thickness 0.15)
				)
				(justify mirror)
			)
		)
		(property "Dielectric" "X5R"
			(at 307.9645 -42.5315 0)
			(layer "B.Fab")
			(hide yes)
			(effects
				(font
					(size 1 1)
					(thickness 0.15)
				)
				(justify mirror)
			)
		)
		(property "License" "Apache-2.0"
			(at 307.9645 -42.5315 0)
			(layer "B.Fab")
			(hide yes)
			(effects
				(font
					(size 1 1)
					(thickness 0.15)
				)
				(justify mirror)
			)
		)
		(property "MPN" "C1005X6S1A105K050BC"
			(at 307.9645 -42.5315 0)
			(layer "B.Fab")
			(hide yes)
			(effects
				(font
					(size 1 1)
					(thickness 0.15)
				)
				(justify mirror)
			)
		)
		(property "Manufacturer" "TDK"
			(at 307.9645 -42.5315 0)
			(layer "B.Fab")
			(hide yes)
			(effects
				(font
					(size 1 1)
					(thickness 0.15)
				)
				(justify mirror)
			)
		)
		(property "Public" ""
			(at 307.9645 -42.5315 0)
			(layer "B.Fab")
			(hide yes)
			(effects
				(font
					(size 1 1)
					(thickness 0.15)
				)
				(justify mirror)
			)
		)
		(property "Val" "1u"
			(at 307.9645 -42.5315 0)
			(layer "B.Fab")
			(hide yes)
			(effects
				(font
					(size 1 1)
					(thickness 0.15)
				)
				(justify mirror)
			)
		)
		(property "Voltage" "16V"
			(at 307.9645 -42.5315 0)
			(layer "B.Fab")
			(hide yes)
			(effects
				(font
					(size 1 1)
					(thickness 0.15)
				)
				(justify mirror)
			)
		)
		(sheetname "/LPDDR4/")
		(sheetfile "lpddr.kicad_sch")
		(attr smd)
		(fp_rect
			(start -0.925 0.47)
			(end 0.925 -0.47)
			(stroke
				(width 0.05)
				(type default)
			)
			(fill no)
			(layer "B.CrtYd")
		)
		(fp_line
			(start 0.504 -0.248)
			(end -0.494 -0.248)
			(stroke
				(width 0.15)
				(type solid)
			)
			(layer "B.Fab")
		)
		(fp_line
			(start -0.494 -0.248)
			(end -0.494 0.25)
			(stroke
				(width 0.15)
				(type solid)
			)
			(layer "B.Fab")
		)
		(fp_line
			(start 0.504 0.25)
			(end 0.504 -0.248)
			(stroke
				(width 0.15)
				(type solid)
			)
			(layer "B.Fab")
		)
		(fp_line
			(start -0.494 0.25)
			(end 0.504 0.25)
			(stroke
				(width 0.15)
				(type solid)
			)
			(layer "B.Fab")
		)
		(fp_text user "License: Apache-2.0"
			(at -0.939 -5.799 270)
			(layer "B.Fab")
			(effects
				(font
					(size 0.7 0.7)
					(thickness 0.15)
				)
				(justify left bottom mirror)
			)
		)
		(fp_text user "Author: Antmicro"
			(at -0.939 -3.399 270)
			(layer "B.Fab")
			(effects
				(font
					(size 0.7 0.7)
					(thickness 0.15)
				)
				(justify left bottom mirror)
			)
		)
		(fp_text user "${REFERENCE}"
			(at -0.939 -4.599 270)
			(layer "B.Fab")
			(effects
				(font
					(size 0.7 0.7)
					(thickness 0.15)
				)
				(justify left bottom mirror)
			)
		)
		(pad "1" smd roundrect
			(at -0.48 0 90)
			(size 0.59 0.64)
			(layers "B.Cu" "B.Mask" "B.Paste")
			(roundrect_rratio 0.25)
			(net 417 "GND")
			(pintype "passive")
		)
		(pad "2" smd roundrect
			(at 0.48 0 90)
			(size 0.59 0.64)
			(layers "B.Cu" "B.Mask" "B.Paste")
			(roundrect_rratio 0.25)
			(net 2 "+1V1")
			(pintype "passive")
		)
	)
	(footprint "antmicro-footprints:R_0402_1005Metric"
		(layer "B.Cu")
		(at 186.475 154.425 90)
		(descr "Resistor SMD 0402")
		(tags "resistor SMD 0402")
		(property "Reference" "R63"
			(at 1.225 -5.125 270)
			(layer "B.SilkS")
			(effects
				(font
					(size 0.7 0.7)
					(thickness 0.15)
				)
				(justify left bottom mirror)
			)
		)
		(property "Value" "R_100k_0402"
			(at -1.011843 -1.772047 270)
			(layer "B.Fab")
			(hide yes)
			(effects
				(font
					(size 0.7 0.7)
					(thickness 0.15)
				)
				(justify left bottom mirror)
			)
		)
		(property "Datasheet" "https://www.bourns.com/docs/product-datasheets/cr.pdf"
			(at 0 0 90)
			(layer "F.Fab")
			(hide yes)
			(effects
				(font
					(size 1.27 1.27)
					(thickness 0.15)
				)
			)
		)
		(property "Description" "SMD Chip Resistor, 100 kohm, ± 1%, 62.5 mW, 0402 [1005 Metric], Thick Film, General Purpose"
			(at 0 0 90)
			(layer "F.Fab")
			(hide yes)
			(effects
				(font
					(size 1.27 1.27)
					(thickness 0.15)
				)
			)
		)
		(property "Author" "Antmicro"
			(at 340.9 -32.05 0)
			(layer "B.Fab")
			(hide yes)
			(effects
				(font
					(size 1 1)
					(thickness 0.15)
				)
				(justify mirror)
			)
		)
		(property "License" "Apache-2.0"
			(at 340.9 -32.05 0)
			(layer "B.Fab")
			(hide yes)
			(effects
				(font
					(size 1 1)
					(thickness 0.15)
				)
				(justify mirror)
			)
		)
		(property "MPN" "CR0402-FX-1003GLF"
			(at 340.9 -32.05 0)
			(layer "B.Fab")
			(hide yes)
			(effects
				(font
					(size 1 1)
					(thickness 0.15)
				)
				(justify mirror)
			)
		)
		(property "Manufacturer" "Bourns"
			(at 340.9 -32.05 0)
			(layer "B.Fab")
			(hide yes)
			(effects
				(font
					(size 1 1)
					(thickness 0.15)
				)
				(justify mirror)
			)
		)
		(property "Public" ""
			(at 340.9 -32.05 0)
			(layer "B.Fab")
			(hide yes)
			(effects
				(font
					(size 1 1)
					(thickness 0.15)
				)
				(justify mirror)
			)
		)
		(property "Tolerance" "1%"
			(at 340.9 -32.05 0)
			(layer "B.Fab")
			(hide yes)
			(effects
				(font
					(size 1 1)
					(thickness 0.15)
				)
				(justify mirror)
			)
		)
		(property "Val" "100k"
			(at 340.9 -32.05 0)
			(layer "B.Fab")
			(hide yes)
			(effects
				(font
					(size 1 1)
					(thickness 0.15)
				)
				(justify mirror)
			)
		)
		(sheetname "/Bottom Connector/")
		(sheetfile "bottom-connector.kicad_sch")
		(attr smd)
		(fp_rect
			(start -0.925 0.47)
			(end 0.925 -0.47)
			(stroke
				(width 0.05)
				(type default)
			)
			(fill no)
			(layer "B.CrtYd")
		)
		(fp_rect
			(start -0.5 0.25)
			(end 0.5 -0.25)
			(stroke
				(width 0.15)
				(type solid)
			)
			(fill no)
			(layer "B.Fab")
		)
		(fp_text user "License: Apache-2.0"
			(at -0.95 -5.169 270)
			(layer "B.Fab")
			(effects
				(font
					(size 0.7 0.7)
					(thickness 0.15)
				)
				(justify left bottom mirror)
			)
		)
		(fp_text user "Author: Antmicro"
			(at -0.95 -4.169 270)
			(layer "B.Fab")
			(effects
				(font
					(size 0.7 0.7)
					(thickness 0.15)
				)
				(justify left bottom mirror)
			)
		)
		(fp_text user "${REFERENCE}"
			(at -0.95 -3.168 270)
			(layer "B.Fab")
			(effects
				(font
					(size 0.7 0.7)
					(thickness 0.15)
				)
				(justify left bottom mirror)
			)
		)
		(pad "1" smd roundrect
			(at -0.48 0 90)
			(size 0.59 0.64)
			(layers "B.Cu" "B.Mask" "B.Paste")
			(roundrect_rratio 0.25)
			(net 417 "GND")
			(pintype "passive")
		)
		(pad "2" smd roundrect
			(at 0.48 0 90)
			(size 0.59 0.64)
			(layers "B.Cu" "B.Mask" "B.Paste")
			(roundrect_rratio 0.25)
			(net 275 "Net-(Q3-REF)")
			(pintype "passive")
		)
	)
	(footprint "antmicro-footprints:C_0402_1005Metric"
		(layer "B.Cu")
		(at 184.85 133.366 90)
		(descr "Capacitor SMD 0402")
		(tags "capacitor SMD 0402")
		(property "Reference" "C124"
			(at -2.014 -0.37 270)
			(layer "B.SilkS")
			(effects
				(font
					(size 0.7 0.7)
					(thickness 0.15)
				)
				(justify right bottom mirror)
			)
		)
		(property "Value" "C_1u_0402"
			(at -1.022927 -2.155213 90)
			(layer "B.Fab")
			(hide yes)
			(effects
				(font
					(size 0.7 0.7)
					(thickness 0.15)
				)
				(justify right bottom mirror)
			)
		)
		(property "Datasheet" "https://product.tdk.com/en/search/capacitor/ceramic/mlcc/info?part_no=C1005X6S1A105K050BC"
			(at 0 0 90)
			(layer "F.Fab")
			(hide yes)
			(effects
				(font
					(size 1.27 1.27)
					(thickness 0.15)
				)
			)
		)
		(property "Description" "SMD Multilayer Ceramic Capacitor, 1 µF, 10 V, 0402 [1005 Metric], ± 10%, X6S, C"
			(at 0 0 90)
			(layer "F.Fab")
			(hide yes)
			(effects
				(font
					(size 1.27 1.27)
					(thickness 0.15)
				)
			)
		)
		(property "Author" "Antmicro"
			(at 318.216 -51.484 0)
			(layer "B.Fab")
			(hide yes)
			(effects
				(font
					(size 1 1)
					(thickness 0.15)
				)
				(justify mirror)
			)
		)
		(property "Dielectric" "X5R"
			(at 318.216 -51.484 0)
			(layer "B.Fab")
			(hide yes)
			(effects
				(font
					(size 1 1)
					(thickness 0.15)
				)
				(justify mirror)
			)
		)
		(property "License" "Apache-2.0"
			(at 318.216 -51.484 0)
			(layer "B.Fab")
			(hide yes)
			(effects
				(font
					(size 1 1)
					(thickness 0.15)
				)
				(justify mirror)
			)
		)
		(property "MPN" "C1005X6S1A105K050BC"
			(at 318.216 -51.484 0)
			(layer "B.Fab")
			(hide yes)
			(effects
				(font
					(size 1 1)
					(thickness 0.15)
				)
				(justify mirror)
			)
		)
		(property "Manufacturer" "TDK"
			(at 318.216 -51.484 0)
			(layer "B.Fab")
			(hide yes)
			(effects
				(font
					(size 1 1)
					(thickness 0.15)
				)
				(justify mirror)
			)
		)
		(property "Public" ""
			(at 318.216 -51.484 0)
			(layer "B.Fab")
			(hide yes)
			(effects
				(font
					(size 1 1)
					(thickness 0.15)
				)
				(justify mirror)
			)
		)
		(property "Val" "1u"
			(at 318.216 -51.484 0)
			(layer "B.Fab")
			(hide yes)
			(effects
				(font
					(size 1 1)
					(thickness 0.15)
				)
				(justify mirror)
			)
		)
		(property "Voltage" "16V"
			(at 318.216 -51.484 0)
			(layer "B.Fab")
			(hide yes)
			(effects
				(font
					(size 1 1)
					(thickness 0.15)
				)
				(justify mirror)
			)
		)
		(sheetname "/LPDDR4/")
		(sheetfile "lpddr.kicad_sch")
		(attr smd)
		(fp_rect
			(start -0.925 0.47)
			(end 0.925 -0.47)
			(stroke
				(width 0.05)
				(type default)
			)
			(fill no)
			(layer "B.CrtYd")
		)
		(fp_line
			(start 0.504 -0.248)
			(end -0.494 -0.248)
			(stroke
				(width 0.15)
				(type solid)
			)
			(layer "B.Fab")
		)
		(fp_line
			(start -0.494 -0.248)
			(end -0.494 0.25)
			(stroke
				(width 0.15)
				(type solid)
			)
			(layer "B.Fab")
		)
		(fp_line
			(start 0.504 0.25)
			(end 0.504 -0.248)
			(stroke
				(width 0.15)
				(type solid)
			)
			(layer "B.Fab")
		)
		(fp_line
			(start -0.494 0.25)
			(end 0.504 0.25)
			(stroke
				(width 0.15)
				(type solid)
			)
			(layer "B.Fab")
		)
		(fp_text user "${REFERENCE}"
			(at -0.939 -4.599 270)
			(layer "B.Fab")
			(effects
				(font
					(size 0.7 0.7)
					(thickness 0.15)
				)
				(justify left bottom mirror)
			)
		)
		(fp_text user "Author: Antmicro"
			(at -0.939 -3.399 270)
			(layer "B.Fab")
			(effects
				(font
					(size 0.7 0.7)
					(thickness 0.15)
				)
				(justify left bottom mirror)
			)
		)
		(fp_text user "License: Apache-2.0"
			(at -0.939 -5.799 270)
			(layer "B.Fab")
			(effects
				(font
					(size 0.7 0.7)
					(thickness 0.15)
				)
				(justify left bottom mirror)
			)
		)
		(pad "1" smd roundrect
			(at -0.48 0 90)
			(size 0.59 0.64)
			(layers "B.Cu" "B.Mask" "B.Paste")
			(roundrect_rratio 0.25)
			(net 417 "GND")
			(pintype "passive")
		)
		(pad "2" smd roundrect
			(at 0.48 0 90)
			(size 0.59 0.64)
			(layers "B.Cu" "B.Mask" "B.Paste")
			(roundrect_rratio 0.25)
			(net 48 "+1V8")
			(pintype "passive")
		)
	)
	(footprint "antmicro-footprints:C_0402_1005Metric"
		(layer "B.Cu")
		(at 194.7 140.564 90)
		(descr "Capacitor SMD 0402")
		(tags "capacitor SMD 0402")
		(property "Reference" "C31"
			(at 1.454 -1.56 270)
			(layer "B.SilkS")
			(effects
				(font
					(size 0.7 0.7)
					(thickness 0.15)
				)
				(justify left bottom mirror)
			)
		)
		(property "Value" "C_100n_0402"
			(at -1.022927 -2.155213 270)
			(layer "B.Fab")
			(hide yes)
			(effects
				(font
					(size 0.7 0.7)
					(thickness 0.15)
				)
				(justify left bottom mirror)
			)
		)
		(property "Datasheet" "https://www.murata.com/products/productdetail?partno=GRM155R61H104KE14%23"
			(at 0 0 90)
			(layer "F.Fab")
			(hide yes)
			(effects
				(font
					(size 1.27 1.27)
					(thickness 0.15)
				)
			)
		)
		(property "Description" "SMD Multilayer Ceramic Capacitor, 0.1 µF, 50 V, 0402 [1005 Metric], ± 10%, X5R, GRM Series"
			(at 0 0 90)
			(layer "F.Fab")
			(hide yes)
			(effects
				(font
					(size 1.27 1.27)
					(thickness 0.15)
				)
			)
		)
		(property "Author" "Antmicro"
			(at 335.264 -54.136 0)
			(layer "B.Fab")
			(hide yes)
			(effects
				(font
					(size 1 1)
					(thickness 0.15)
				)
				(justify mirror)
			)
		)
		(property "Dielectric" "X5R"
			(at 335.264 -54.136 0)
			(layer "B.Fab")
			(hide yes)
			(effects
				(font
					(size 1 1)
					(thickness 0.15)
				)
				(justify mirror)
			)
		)
		(property "License" "Apache-2.0"
			(at 335.264 -54.136 0)
			(layer "B.Fab")
			(hide yes)
			(effects
				(font
					(size 1 1)
					(thickness 0.15)
				)
				(justify mirror)
			)
		)
		(property "MPN" "GRM155R61H104KE14D"
			(at 335.264 -54.136 0)
			(layer "B.Fab")
			(hide yes)
			(effects
				(font
					(size 1 1)
					(thickness 0.15)
				)
				(justify mirror)
			)
		)
		(property "Manufacturer" "Murata"
			(at 335.264 -54.136 0)
			(layer "B.Fab")
			(hide yes)
			(effects
				(font
					(size 1 1)
					(thickness 0.15)
				)
				(justify mirror)
			)
		)
		(property "Public" ""
			(at 335.264 -54.136 0)
			(layer "B.Fab")
			(hide yes)
			(effects
				(font
					(size 1 1)
					(thickness 0.15)
				)
				(justify mirror)
			)
		)
		(property "Val" "100n"
			(at 335.264 -54.136 0)
			(layer "B.Fab")
			(hide yes)
			(effects
				(font
					(size 1 1)
					(thickness 0.15)
				)
				(justify mirror)
			)
		)
		(property "Voltage" "50V"
			(at 335.264 -54.136 0)
			(layer "B.Fab")
			(hide yes)
			(effects
				(font
					(size 1 1)
					(thickness 0.15)
				)
				(justify mirror)
			)
		)
		(sheetname "/FPGA Supply/")
		(sheetfile "fpga-supply.kicad_sch")
		(attr smd)
		(fp_rect
			(start -0.925 0.47)
			(end 0.925 -0.47)
			(stroke
				(width 0.05)
				(type default)
			)
			(fill no)
			(layer "B.CrtYd")
		)
		(fp_line
			(start 0.504 -0.248)
			(end -0.494 -0.248)
			(stroke
				(width 0.15)
				(type solid)
			)
			(layer "B.Fab")
		)
		(fp_line
			(start -0.494 -0.248)
			(end -0.494 0.25)
			(stroke
				(width 0.15)
				(type solid)
			)
			(layer "B.Fab")
		)
		(fp_line
			(start 0.504 0.25)
			(end 0.504 -0.248)
			(stroke
				(width 0.15)
				(type solid)
			)
			(layer "B.Fab")
		)
		(fp_line
			(start -0.494 0.25)
			(end 0.504 0.25)
			(stroke
				(width 0.15)
				(type solid)
			)
			(layer "B.Fab")
		)
		(fp_text user "Author: Antmicro"
			(at -0.939 -3.399 270)
			(layer "B.Fab")
			(effects
				(font
					(size 0.7 0.7)
					(thickness 0.15)
				)
				(justify left bottom mirror)
			)
		)
		(fp_text user "License: Apache-2.0"
			(at -0.939 -5.799 270)
			(layer "B.Fab")
			(effects
				(font
					(size 0.7 0.7)
					(thickness 0.15)
				)
				(justify left bottom mirror)
			)
		)
		(fp_text user "${REFERENCE}"
			(at -0.939 -4.599 270)
			(layer "B.Fab")
			(effects
				(font
					(size 0.7 0.7)
					(thickness 0.15)
				)
				(justify left bottom mirror)
			)
		)
		(pad "1" smd roundrect
			(at -0.48 0 90)
			(size 0.59 0.64)
			(layers "B.Cu" "B.Mask" "B.Paste")
			(roundrect_rratio 0.25)
			(net 417 "GND")
			(pintype "passive")
		)
		(pad "2" smd roundrect
			(at 0.48 0 90)
			(size 0.59 0.64)
			(layers "B.Cu" "B.Mask" "B.Paste")
			(roundrect_rratio 0.25)
			(net 47 "+1V05")
			(pintype "passive")
		)
	)
	(footprint "antmicro-footprints:D_0402_1005Metric"
		(layer "B.Cu")
		(at 185.75 118.95 -90)
		(property "Reference" "D1"
			(at -2.4 -0.375 90)
			(layer "B.SilkS")
			(effects
				(font
					(size 0.7 0.7)
					(thickness 0.15)
				)
				(justify left bottom mirror)
			)
		)
		(property "Value" "AXGD10402KR"
			(at -2.54 -2.54 90)
			(layer "B.Fab")
			(hide yes)
			(effects
				(font
					(size 0.7 0.7)
					(thickness 0.15)
				)
				(justify left bottom mirror)
			)
		)
		(property "Datasheet" "https://www.littelfuse.com/media?resourcetype=datasheets&itemid=020b2bf2-064c-4ff1-a898-b4ec805b2fea&filename=littelfuse-xtremeguard-axgd-datasheet"
			(at 0 0 270)
			(layer "F.Fab")
			(hide yes)
			(effects
				(font
					(size 1.27 1.27)
					(thickness 0.15)
				)
			)
		)
		(property "Description" "Bidirectional TVS, 30 kV,  0402, 24 V, 0.04 pF"
			(at 0 0 270)
			(layer "F.Fab")
			(hide yes)
			(effects
				(font
					(size 1.27 1.27)
					(thickness 0.15)
				)
			)
		)
		(property "Author" "Antmicro"
			(at 66.8 304.7 0)
			(layer "B.Fab")
			(hide yes)
			(effects
				(font
					(size 1 1)
					(thickness 0.15)
				)
				(justify mirror)
			)
		)
		(property "License" "Apache-2.0"
			(at 66.8 304.7 0)
			(layer "B.Fab")
			(hide yes)
			(effects
				(font
					(size 1 1)
					(thickness 0.15)
				)
				(justify mirror)
			)
		)
		(property "MPN" "AXGD10402KR"
			(at 66.8 304.7 0)
			(layer "B.Fab")
			(hide yes)
			(effects
				(font
					(size 1 1)
					(thickness 0.15)
				)
				(justify mirror)
			)
		)
		(property "Manufacturer" "Littelfuse"
			(at 66.8 304.7 0)
			(layer "B.Fab")
			(hide yes)
			(effects
				(font
					(size 1 1)
					(thickness 0.15)
				)
				(justify mirror)
			)
		)
		(property "Public" ""
			(at 66.8 304.7 0)
			(layer "B.Fab")
			(hide yes)
			(effects
				(font
					(size 1 1)
					(thickness 0.15)
				)
				(justify mirror)
			)
		)
		(sheetname "/Supply/")
		(sheetfile "supply.kicad_sch")
		(attr smd)
		(fp_line
			(start 0.1 0.255)
			(end -0.1 0.255)
			(stroke
				(width 0.15)
				(type solid)
			)
			(layer "B.SilkS")
		)
		(fp_line
			(start -0.875 0.25)
			(end -0.875 -0.25)
			(stroke
				(width 0.15)
				(type solid)
			)
			(layer "B.SilkS")
		)
		(fp_line
			(start -0.1 -0.255)
			(end 0.1 -0.255)
			(stroke
				(width 0.15)
				(type solid)
			)
			(layer "B.SilkS")
		)
		(fp_rect
			(start -0.925 0.47)
			(end 0.925 -0.47)
			(stroke
				(width 0.05)
				(type default)
			)
			(fill no)
			(layer "B.CrtYd")
		)
		(fp_line
			(start -0.51 0.255)
			(end 0.51 0.255)
			(stroke
				(width 0.15)
				(type solid)
			)
			(layer "B.Fab")
		)
		(fp_line
			(start 0.51 0.255)
			(end 0.51 -0.255)
			(stroke
				(width 0.15)
				(type solid)
			)
			(layer "B.Fab")
		)
		(fp_line
			(start -0.2 0.25)
			(end -0.5 -0.05)
			(stroke
				(width 0.15)
				(type solid)
			)
			(layer "B.Fab")
		)
		(fp_line
			(start -0.51 -0.255)
			(end -0.51 0.255)
			(stroke
				(width 0.15)
				(type solid)
			)
			(layer "B.Fab")
		)
		(fp_line
			(start 0.51 -0.255)
			(end -0.51 -0.255)
			(stroke
				(width 0.15)
				(type solid)
			)
			(layer "B.Fab")
		)
		(fp_text user "License: Apache-2.0"
			(at -2.54 -5.74 90)
			(layer "B.Fab")
			(effects
				(font
					(size 0.7 0.7)
					(thickness 0.15)
				)
				(justify left bottom mirror)
			)
		)
		(fp_text user "Author: Antmicro"
			(at -2.54 -6.94 90)
			(layer "B.Fab")
			(effects
				(font
					(size 0.7 0.7)
					(thickness 0.15)
				)
				(justify left bottom mirror)
			)
		)
		(fp_text user "${REFERENCE}"
			(at -2.54 -4.54 90)
			(layer "B.Fab")
			(effects
				(font
					(size 0.7 0.7)
					(thickness 0.15)
				)
				(justify left bottom mirror)
			)
		)
		(pad "1" smd roundrect
			(at -0.48 0 270)
			(size 0.59 0.64)
			(layers "B.Cu" "B.Mask" "B.Paste")
			(roundrect_rratio 0.25)
			(net 417 "GND")
			(pinfunction "C")
			(pintype "passive")
		)
		(pad "2" smd roundrect
			(at 0.48 0 270)
			(size 0.59 0.64)
			(layers "B.Cu" "B.Mask" "B.Paste")
			(roundrect_rratio 0.25)
			(net 212 "GLOBAL_EN")
			(pinfunction "A")
			(pintype "passive")
		)
	)
	(footprint "antmicro-footprints:R_0402_1005Metric"
		(layer "B.Cu")
		(at 218.41 117.55 90)
		(descr "Resistor SMD 0402")
		(tags "resistor SMD 0402")
		(property "Reference" "R137"
			(at -0.9 0.39 270)
			(layer "B.SilkS")
			(effects
				(font
					(size 0.7 0.7)
					(thickness 0.15)
				)
				(justify left bottom mirror)
			)
		)
		(property "Value" "R_1k5_0402"
			(at -1.011843 -1.772047 270)
			(layer "B.Fab")
			(hide yes)
			(effects
				(font
					(size 0.7 0.7)
					(thickness 0.15)
				)
				(justify left bottom mirror)
			)
		)
		(property "Datasheet" "https://www.bourns.com/docs/product-datasheets/cr.pdf"
			(at 0 0 90)
			(layer "F.Fab")
			(hide yes)
			(effects
				(font
					(size 1.27 1.27)
					(thickness 0.15)
				)
			)
		)
		(property "Description" "SMD Chip Resistor, 1.5 kohm, ± 1%, 62.5 mW, 0402 [1005 Metric], Thick Film, General Purpose"
			(at 0 0 90)
			(layer "F.Fab")
			(hide yes)
			(effects
				(font
					(size 1.27 1.27)
					(thickness 0.15)
				)
			)
		)
		(property "Author" "Antmicro"
			(at 335.96 -100.86 0)
			(layer "B.Fab")
			(hide yes)
			(effects
				(font
					(size 1 1)
					(thickness 0.15)
				)
				(justify mirror)
			)
		)
		(property "License" "Apache-2.0"
			(at 335.96 -100.86 0)
			(layer "B.Fab")
			(hide yes)
			(effects
				(font
					(size 1 1)
					(thickness 0.15)
				)
				(justify mirror)
			)
		)
		(property "MPN" "CR0402-FX-1501GLF"
			(at 335.96 -100.86 0)
			(layer "B.Fab")
			(hide yes)
			(effects
				(font
					(size 1 1)
					(thickness 0.15)
				)
				(justify mirror)
			)
		)
		(property "Manufacturer" "Bourns"
			(at 335.96 -100.86 0)
			(layer "B.Fab")
			(hide yes)
			(effects
				(font
					(size 1 1)
					(thickness 0.15)
				)
				(justify mirror)
			)
		)
		(property "Public" ""
			(at 335.96 -100.86 0)
			(layer "B.Fab")
			(hide yes)
			(effects
				(font
					(size 1 1)
					(thickness 0.15)
				)
				(justify mirror)
			)
		)
		(property "Tolerance" "1%"
			(at 335.96 -100.86 0)
			(layer "B.Fab")
			(hide yes)
			(effects
				(font
					(size 1 1)
					(thickness 0.15)
				)
				(justify mirror)
			)
		)
		(property "Val" "1k5"
			(at 335.96 -100.86 0)
			(layer "B.Fab")
			(hide yes)
			(effects
				(font
					(size 1 1)
					(thickness 0.15)
				)
				(justify mirror)
			)
		)
		(sheetname "/Ethernet/")
		(sheetfile "ethernet.kicad_sch")
		(attr smd)
		(fp_rect
			(start -0.925 0.47)
			(end 0.925 -0.47)
			(stroke
				(width 0.05)
				(type default)
			)
			(fill no)
			(layer "B.CrtYd")
		)
		(fp_rect
			(start -0.5 0.25)
			(end 0.5 -0.25)
			(stroke
				(width 0.15)
				(type solid)
			)
			(fill no)
			(layer "B.Fab")
		)
		(fp_text user "Author: Antmicro"
			(at -0.95 -4.169 270)
			(layer "B.Fab")
			(effects
				(font
					(size 0.7 0.7)
					(thickness 0.15)
				)
				(justify left bottom mirror)
			)
		)
		(fp_text user "License: Apache-2.0"
			(at -0.95 -5.169 270)
			(layer "B.Fab")
			(effects
				(font
					(size 0.7 0.7)
					(thickness 0.15)
				)
				(justify left bottom mirror)
			)
		)
		(fp_text user "${REFERENCE}"
			(at -0.95 -3.168 270)
			(layer "B.Fab")
			(effects
				(font
					(size 0.7 0.7)
					(thickness 0.15)
				)
				(justify left bottom mirror)
			)
		)
		(pad "1" smd roundrect
			(at -0.48 0 90)
			(size 0.59 0.64)
			(layers "B.Cu" "B.Mask" "B.Paste")
			(roundrect_rratio 0.25)
			(net 50 "+3V3")
			(pintype "passive")
		)
		(pad "2" smd roundrect
			(at 0.48 0 90)
			(size 0.59 0.64)
			(layers "B.Cu" "B.Mask" "B.Paste")
			(roundrect_rratio 0.25)
			(net 343 "/Ethernet/ETH.MDIO")
			(pintype "passive")
		)
	)
	(footprint "antmicro-footprints:C_0402_1005Metric"
		(layer "B.Cu")
		(at 219.911 118.704)
		(descr "Capacitor SMD 0402")
		(tags "capacitor SMD 0402")
		(property "Reference" "C214"
			(at 6.539 4.346 0)
			(layer "B.SilkS")
			(effects
				(font
					(size 0.7 0.7)
					(thickness 0.15)
				)
				(justify right bottom mirror)
			)
		)
		(property "Value" "C_100n_0402"
			(at -1.022927 -2.155213 0)
			(layer "B.Fab")
			(hide yes)
			(effects
				(font
					(size 0.7 0.7)
					(thickness 0.15)
				)
				(justify right bottom mirror)
			)
		)
		(property "Datasheet" "https://www.murata.com/products/productdetail?partno=GRM155R61H104KE14%23"
			(at 0 0 0)
			(layer "F.Fab")
			(hide yes)
			(effects
				(font
					(size 1.27 1.27)
					(thickness 0.15)
				)
			)
		)
		(property "Description" "SMD Multilayer Ceramic Capacitor, 0.1 µF, 50 V, 0402 [1005 Metric], ± 10%, X5R, GRM Series"
			(at 0 0 0)
			(layer "F.Fab")
			(hide yes)
			(effects
				(font
					(size 1.27 1.27)
					(thickness 0.15)
				)
			)
		)
		(property "Author" "Antmicro"
			(at 0 0 0)
			(layer "B.Fab")
			(hide yes)
			(effects
				(font
					(size 1 1)
					(thickness 0.15)
				)
				(justify mirror)
			)
		)
		(property "Dielectric" "X5R"
			(at 0 0 0)
			(layer "B.Fab")
			(hide yes)
			(effects
				(font
					(size 1 1)
					(thickness 0.15)
				)
				(justify mirror)
			)
		)
		(property "License" "Apache-2.0"
			(at 0 0 0)
			(layer "B.Fab")
			(hide yes)
			(effects
				(font
					(size 1 1)
					(thickness 0.15)
				)
				(justify mirror)
			)
		)
		(property "MPN" "GRM155R61H104KE14D"
			(at 0 0 0)
			(layer "B.Fab")
			(hide yes)
			(effects
				(font
					(size 1 1)
					(thickness 0.15)
				)
				(justify mirror)
			)
		)
		(property "Manufacturer" "Murata"
			(at 0 0 0)
			(layer "B.Fab")
			(hide yes)
			(effects
				(font
					(size 1 1)
					(thickness 0.15)
				)
				(justify mirror)
			)
		)
		(property "Public" ""
			(at 0 0 0)
			(layer "B.Fab")
			(hide yes)
			(effects
				(font
					(size 1 1)
					(thickness 0.15)
				)
				(justify mirror)
			)
		)
		(property "Val" "100n"
			(at 0 0 0)
			(layer "B.Fab")
			(hide yes)
			(effects
				(font
					(size 1 1)
					(thickness 0.15)
				)
				(justify mirror)
			)
		)
		(property "Voltage" "50V"
			(at 0 0 0)
			(layer "B.Fab")
			(hide yes)
			(effects
				(font
					(size 1 1)
					(thickness 0.15)
				)
				(justify mirror)
			)
		)
		(sheetname "/Ethernet/")
		(sheetfile "ethernet.kicad_sch")
		(attr smd)
		(fp_rect
			(start -0.925 0.47)
			(end 0.925 -0.47)
			(stroke
				(width 0.05)
				(type default)
			)
			(fill no)
			(layer "B.CrtYd")
		)
		(fp_line
			(start -0.494 -0.248)
			(end -0.494 0.25)
			(stroke
				(width 0.15)
				(type solid)
			)
			(layer "B.Fab")
		)
		(fp_line
			(start -0.494 0.25)
			(end 0.504 0.25)
			(stroke
				(width 0.15)
				(type solid)
			)
			(layer "B.Fab")
		)
		(fp_line
			(start 0.504 -0.248)
			(end -0.494 -0.248)
			(stroke
				(width 0.15)
				(type solid)
			)
			(layer "B.Fab")
		)
		(fp_line
			(start 0.504 0.25)
			(end 0.504 -0.248)
			(stroke
				(width 0.15)
				(type solid)
			)
			(layer "B.Fab")
		)
		(fp_text user "Author: Antmicro"
			(at -0.939 -3.399 180)
			(layer "B.Fab")
			(effects
				(font
					(size 0.7 0.7)
					(thickness 0.15)
				)
				(justify left bottom mirror)
			)
		)
		(fp_text user "License: Apache-2.0"
			(at -0.939 -5.799 180)
			(layer "B.Fab")
			(effects
				(font
					(size 0.7 0.7)
					(thickness 0.15)
				)
				(justify left bottom mirror)
			)
		)
		(fp_text user "${REFERENCE}"
			(at -0.939 -4.599 180)
			(layer "B.Fab")
			(effects
				(font
					(size 0.7 0.7)
					(thickness 0.15)
				)
				(justify left bottom mirror)
			)
		)
		(pad "1" smd roundrect
			(at -0.48 0)
			(size 0.59 0.64)
			(layers "B.Cu" "B.Mask" "B.Paste")
			(roundrect_rratio 0.25)
			(net 417 "GND")
			(pintype "passive")
		)
		(pad "2" smd roundrect
			(at 0.48 0)
			(size 0.59 0.64)
			(layers "B.Cu" "B.Mask" "B.Paste")
			(roundrect_rratio 0.25)
			(net 418 "+2V5")
			(pintype "passive")
		)
	)
	(footprint "antmicro-footprints:C_0402_1005Metric"
		(layer "B.Cu")
		(at 213.95 141.3 90)
		(descr "Capacitor SMD 0402")
		(tags "capacitor SMD 0402")
		(property "Reference" "C185"
			(at 0.85 0.11 90)
			(layer "B.SilkS")
			(effects
				(font
					(size 0.7 0.7)
					(thickness 0.15)
				)
				(justify right bottom mirror)
			)
		)
		(property "Value" "C_100n_0402"
			(at -1.022927 -2.155213 90)
			(layer "B.Fab")
			(hide yes)
			(effects
				(font
					(size 0.7 0.7)
					(thickness 0.15)
				)
				(justify right bottom mirror)
			)
		)
		(property "Datasheet" "https://www.murata.com/products/productdetail?partno=GRM155R61H104KE14%23"
			(at 0 0 90)
			(layer "F.Fab")
			(hide yes)
			(effects
				(font
					(size 1.27 1.27)
					(thickness 0.15)
				)
			)
		)
		(property "Description" "SMD Multilayer Ceramic Capacitor, 0.1 µF, 50 V, 0402 [1005 Metric], ± 10%, X5R, GRM Series"
			(at 0 0 90)
			(layer "F.Fab")
			(hide yes)
			(effects
				(font
					(size 1.27 1.27)
					(thickness 0.15)
				)
			)
		)
		(property "Author" "Antmicro"
			(at 355.25 -72.65 0)
			(layer "B.Fab")
			(hide yes)
			(effects
				(font
					(size 1 1)
					(thickness 0.15)
				)
				(justify mirror)
			)
		)
		(property "Dielectric" "X5R"
			(at 355.25 -72.65 0)
			(layer "B.Fab")
			(hide yes)
			(effects
				(font
					(size 1 1)
					(thickness 0.15)
				)
				(justify mirror)
			)
		)
		(property "License" "Apache-2.0"
			(at 355.25 -72.65 0)
			(layer "B.Fab")
			(hide yes)
			(effects
				(font
					(size 1 1)
					(thickness 0.15)
				)
				(justify mirror)
			)
		)
		(property "MPN" "GRM155R61H104KE14D"
			(at 355.25 -72.65 0)
			(layer "B.Fab")
			(hide yes)
			(effects
				(font
					(size 1 1)
					(thickness 0.15)
				)
				(justify mirror)
			)
		)
		(property "Manufacturer" "Murata"
			(at 355.25 -72.65 0)
			(layer "B.Fab")
			(hide yes)
			(effects
				(font
					(size 1 1)
					(thickness 0.15)
				)
				(justify mirror)
			)
		)
		(property "Public" ""
			(at 355.25 -72.65 0)
			(layer "B.Fab")
			(hide yes)
			(effects
				(font
					(size 1 1)
					(thickness 0.15)
				)
				(justify mirror)
			)
		)
		(property "Val" "100n"
			(at 355.25 -72.65 0)
			(layer "B.Fab")
			(hide yes)
			(effects
				(font
					(size 1 1)
					(thickness 0.15)
				)
				(justify mirror)
			)
		)
		(property "Voltage" "50V"
			(at 355.25 -72.65 0)
			(layer "B.Fab")
			(hide yes)
			(effects
				(font
					(size 1 1)
					(thickness 0.15)
				)
				(justify mirror)
			)
		)
		(sheetname "/USB/")
		(sheetfile "usb.kicad_sch")
		(attr smd)
		(fp_rect
			(start -0.925 0.47)
			(end 0.925 -0.47)
			(stroke
				(width 0.05)
				(type default)
			)
			(fill no)
			(layer "B.CrtYd")
		)
		(fp_line
			(start 0.504 -0.248)
			(end -0.494 -0.248)
			(stroke
				(width 0.15)
				(type solid)
			)
			(layer "B.Fab")
		)
		(fp_line
			(start -0.494 -0.248)
			(end -0.494 0.25)
			(stroke
				(width 0.15)
				(type solid)
			)
			(layer "B.Fab")
		)
		(fp_line
			(start 0.504 0.25)
			(end 0.504 -0.248)
			(stroke
				(width 0.15)
				(type solid)
			)
			(layer "B.Fab")
		)
		(fp_line
			(start -0.494 0.25)
			(end 0.504 0.25)
			(stroke
				(width 0.15)
				(type solid)
			)
			(layer "B.Fab")
		)
		(fp_text user "${REFERENCE}"
			(at -0.939 -4.599 270)
			(layer "B.Fab")
			(effects
				(font
					(size 0.7 0.7)
					(thickness 0.15)
				)
				(justify left bottom mirror)
			)
		)
		(fp_text user "Author: Antmicro"
			(at -0.939 -3.399 270)
			(layer "B.Fab")
			(effects
				(font
					(size 0.7 0.7)
					(thickness 0.15)
				)
				(justify left bottom mirror)
			)
		)
		(fp_text user "License: Apache-2.0"
			(at -0.939 -5.799 270)
			(layer "B.Fab")
			(effects
				(font
					(size 0.7 0.7)
					(thickness 0.15)
				)
				(justify left bottom mirror)
			)
		)
		(pad "1" smd roundrect
			(at -0.48 0 90)
			(size 0.59 0.64)
			(layers "B.Cu" "B.Mask" "B.Paste")
			(roundrect_rratio 0.25)
			(net 417 "GND")
			(pintype "passive")
		)
		(pad "2" smd roundrect
			(at 0.48 0 90)
			(size 0.59 0.64)
			(layers "B.Cu" "B.Mask" "B.Paste")
			(roundrect_rratio 0.25)
			(net 152 "/USB/VDDIO")
			(pintype "passive")
		)
	)
	(footprint "antmicro-footprints:C_0402_1005Metric"
		(layer "B.Cu")
		(at 214.361 123.254 -90)
		(descr "Capacitor SMD 0402")
		(tags "capacitor SMD 0402")
		(property "Reference" "C116"
			(at 1.886 -0.589 90)
			(layer "B.SilkS")
			(effects
				(font
					(size 0.7 0.7)
					(thickness 0.15)
				)
				(justify left bottom mirror)
			)
		)
		(property "Value" "C_1u_0402"
			(at -1.022927 -2.155213 90)
			(layer "B.Fab")
			(hide yes)
			(effects
				(font
					(size 0.7 0.7)
					(thickness 0.15)
				)
				(justify left bottom mirror)
			)
		)
		(property "Datasheet" "https://product.tdk.com/en/search/capacitor/ceramic/mlcc/info?part_no=C1005X6S1A105K050BC"
			(at 0 0 270)
			(layer "F.Fab")
			(hide yes)
			(effects
				(font
					(size 1.27 1.27)
					(thickness 0.15)
				)
			)
		)
		(property "Description" "SMD Multilayer Ceramic Capacitor, 1 µF, 10 V, 0402 [1005 Metric], ± 10%, X6S, C"
			(at 0 0 270)
			(layer "F.Fab")
			(hide yes)
			(effects
				(font
					(size 1.27 1.27)
					(thickness 0.15)
				)
			)
		)
		(property "Author" "Antmicro"
			(at 91.107 337.615 0)
			(layer "B.Fab")
			(hide yes)
			(effects
				(font
					(size 1 1)
					(thickness 0.15)
				)
				(justify mirror)
			)
		)
		(property "Dielectric" ""
			(at 91.107 337.615 0)
			(layer "B.Fab")
			(hide yes)
			(effects
				(font
					(size 1 1)
					(thickness 0.15)
				)
				(justify mirror)
			)
		)
		(property "License" "Apache-2.0"
			(at 91.107 337.615 0)
			(layer "B.Fab")
			(hide yes)
			(effects
				(font
					(size 1 1)
					(thickness 0.15)
				)
				(justify mirror)
			)
		)
		(property "MPN" "C1005X6S1A105K050BC"
			(at 91.107 337.615 0)
			(layer "B.Fab")
			(hide yes)
			(effects
				(font
					(size 1 1)
					(thickness 0.15)
				)
				(justify mirror)
			)
		)
		(property "Manufacturer" "TDK"
			(at 91.107 337.615 0)
			(layer "B.Fab")
			(hide yes)
			(effects
				(font
					(size 1 1)
					(thickness 0.15)
				)
				(justify mirror)
			)
		)
		(property "Public" ""
			(at 91.107 337.615 0)
			(layer "B.Fab")
			(hide yes)
			(effects
				(font
					(size 1 1)
					(thickness 0.15)
				)
				(justify mirror)
			)
		)
		(property "Val" "1u"
			(at 91.107 337.615 0)
			(layer "B.Fab")
			(hide yes)
			(effects
				(font
					(size 1 1)
					(thickness 0.15)
				)
				(justify mirror)
			)
		)
		(property "Voltage" ""
			(at 91.107 337.615 0)
			(layer "B.Fab")
			(hide yes)
			(effects
				(font
					(size 1 1)
					(thickness 0.15)
				)
				(justify mirror)
			)
		)
		(sheetname "/Ethernet/")
		(sheetfile "ethernet.kicad_sch")
		(attr smd)
		(fp_rect
			(start -0.925 0.47)
			(end 0.925 -0.47)
			(stroke
				(width 0.05)
				(type default)
			)
			(fill no)
			(layer "B.CrtYd")
		)
		(fp_line
			(start -0.494 0.25)
			(end 0.504 0.25)
			(stroke
				(width 0.15)
				(type solid)
			)
			(layer "B.Fab")
		)
		(fp_line
			(start 0.504 0.25)
			(end 0.504 -0.248)
			(stroke
				(width 0.15)
				(type solid)
			)
			(layer "B.Fab")
		)
		(fp_line
			(start -0.494 -0.248)
			(end -0.494 0.25)
			(stroke
				(width 0.15)
				(type solid)
			)
			(layer "B.Fab")
		)
		(fp_line
			(start 0.504 -0.248)
			(end -0.494 -0.248)
			(stroke
				(width 0.15)
				(type solid)
			)
			(layer "B.Fab")
		)
		(fp_text user "License: Apache-2.0"
			(at -0.939 -5.799 90)
			(layer "B.Fab")
			(effects
				(font
					(size 0.7 0.7)
					(thickness 0.15)
				)
				(justify left bottom mirror)
			)
		)
		(fp_text user "Author: Antmicro"
			(at -0.939 -3.399 90)
			(layer "B.Fab")
			(effects
				(font
					(size 0.7 0.7)
					(thickness 0.15)
				)
				(justify left bottom mirror)
			)
		)
		(fp_text user "${REFERENCE}"
			(at -0.939 -4.599 90)
			(layer "B.Fab")
			(effects
				(font
					(size 0.7 0.7)
					(thickness 0.15)
				)
				(justify left bottom mirror)
			)
		)
		(pad "1" smd roundrect
			(at -0.48 0 270)
			(size 0.59 0.64)
			(layers "B.Cu" "B.Mask" "B.Paste")
			(roundrect_rratio 0.25)
			(net 417 "GND")
			(pintype "passive")
		)
		(pad "2" smd roundrect
			(at 0.48 0 270)
			(size 0.59 0.64)
			(layers "B.Cu" "B.Mask" "B.Paste")
			(roundrect_rratio 0.25)
			(net 50 "+3V3")
			(pintype "passive")
		)
	)
	(footprint "antmicro-footprints:C_0402_1005Metric"
		(layer "B.Cu")
		(at 201.23 148.68)
		(descr "Capacitor SMD 0402")
		(tags "capacitor SMD 0402")
		(property "Reference" "C280"
			(at -1.236 2.275 0)
			(layer "B.SilkS")
			(effects
				(font
					(size 0.7 0.7)
					(thickness 0.15)
				)
				(justify right bottom mirror)
			)
		)
		(property "Value" "C_100n_0402"
			(at -1.022927 -2.155213 0)
			(layer "B.Fab")
			(hide yes)
			(effects
				(font
					(size 0.7 0.7)
					(thickness 0.15)
				)
				(justify right bottom mirror)
			)
		)
		(property "Datasheet" "https://www.murata.com/products/productdetail?partno=GRM155R61H104KE14%23"
			(at 0 0 0)
			(layer "F.Fab")
			(hide yes)
			(effects
				(font
					(size 1.27 1.27)
					(thickness 0.15)
				)
			)
		)
		(property "Description" "SMD Multilayer Ceramic Capacitor, 0.1 µF, 50 V, 0402 [1005 Metric], ± 10%, X5R, GRM Series"
			(at 0 0 0)
			(layer "F.Fab")
			(hide yes)
			(effects
				(font
					(size 1.27 1.27)
					(thickness 0.15)
				)
			)
		)
		(property "Author" "Antmicro"
			(at 0 0 0)
			(layer "B.Fab")
			(hide yes)
			(effects
				(font
					(size 1 1)
					(thickness 0.15)
				)
				(justify mirror)
			)
		)
		(property "Dielectric" "X5R"
			(at 0 0 0)
			(layer "B.Fab")
			(hide yes)
			(effects
				(font
					(size 1 1)
					(thickness 0.15)
				)
				(justify mirror)
			)
		)
		(property "License" "Apache-2.0"
			(at 0 0 0)
			(layer "B.Fab")
			(hide yes)
			(effects
				(font
					(size 1 1)
					(thickness 0.15)
				)
				(justify mirror)
			)
		)
		(property "MPN" "GRM155R61H104KE14D"
			(at 0 0 0)
			(layer "B.Fab")
			(hide yes)
			(effects
				(font
					(size 1 1)
					(thickness 0.15)
				)
				(justify mirror)
			)
		)
		(property "Manufacturer" "Murata"
			(at 0 0 0)
			(layer "B.Fab")
			(hide yes)
			(effects
				(font
					(size 1 1)
					(thickness 0.15)
				)
				(justify mirror)
			)
		)
		(property "Public" ""
			(at 0 0 0)
			(layer "B.Fab")
			(hide yes)
			(effects
				(font
					(size 1 1)
					(thickness 0.15)
				)
				(justify mirror)
			)
		)
		(property "Val" "100n"
			(at 0 0 0)
			(layer "B.Fab")
			(hide yes)
			(effects
				(font
					(size 1 1)
					(thickness 0.15)
				)
				(justify mirror)
			)
		)
		(property "Voltage" "50V"
			(at 0 0 0)
			(layer "B.Fab")
			(hide yes)
			(effects
				(font
					(size 1 1)
					(thickness 0.15)
				)
				(justify mirror)
			)
		)
		(sheetname "/MIPI CrossLink/")
		(sheetfile "crosslink.kicad_sch")
		(attr smd)
		(fp_rect
			(start -0.925 0.47)
			(end 0.925 -0.47)
			(stroke
				(width 0.05)
				(type default)
			)
			(fill no)
			(layer "B.CrtYd")
		)
		(fp_line
			(start -0.494 -0.248)
			(end -0.494 0.25)
			(stroke
				(width 0.15)
				(type solid)
			)
			(layer "B.Fab")
		)
		(fp_line
			(start -0.494 0.25)
			(end 0.504 0.25)
			(stroke
				(width 0.15)
				(type solid)
			)
			(layer "B.Fab")
		)
		(fp_line
			(start 0.504 -0.248)
			(end -0.494 -0.248)
			(stroke
				(width 0.15)
				(type solid)
			)
			(layer "B.Fab")
		)
		(fp_line
			(start 0.504 0.25)
			(end 0.504 -0.248)
			(stroke
				(width 0.15)
				(type solid)
			)
			(layer "B.Fab")
		)
		(fp_text user "Author: Antmicro"
			(at -0.939 -3.399 180)
			(layer "B.Fab")
			(effects
				(font
					(size 0.7 0.7)
					(thickness 0.15)
				)
				(justify left bottom mirror)
			)
		)
		(fp_text user "License: Apache-2.0"
			(at -0.939 -5.799 180)
			(layer "B.Fab")
			(effects
				(font
					(size 0.7 0.7)
					(thickness 0.15)
				)
				(justify left bottom mirror)
			)
		)
		(fp_text user "${REFERENCE}"
			(at -0.939 -4.599 180)
			(layer "B.Fab")
			(effects
				(font
					(size 0.7 0.7)
					(thickness 0.15)
				)
				(justify left bottom mirror)
			)
		)
		(pad "1" smd roundrect
			(at -0.48 0)
			(size 0.59 0.64)
			(layers "B.Cu" "B.Mask" "B.Paste")
			(roundrect_rratio 0.25)
			(net 417 "GND")
			(pintype "passive")
		)
		(pad "2" smd roundrect
			(at 0.48 0)
			(size 0.59 0.64)
			(layers "B.Cu" "B.Mask" "B.Paste")
			(roundrect_rratio 0.25)
			(net 204 "/MIPI CrossLink/CL_VCCPLL_DPHY0")
			(pintype "passive")
		)
	)
	(footprint "antmicro-footprints:R_0402_1005Metric"
		(layer "B.Cu")
		(at 222.13 128.2 180)
		(descr "Resistor SMD 0402")
		(tags "resistor SMD 0402")
		(property "Reference" "R72"
			(at -1.82 0.45 0)
			(layer "B.SilkS")
			(effects
				(font
					(size 0.7 0.7)
					(thickness 0.15)
				)
				(justify left bottom mirror)
			)
		)
		(property "Value" "R_470R_0402"
			(at -1.011843 -1.772047 0)
			(layer "B.Fab")
			(hide yes)
			(effects
				(font
					(size 0.7 0.7)
					(thickness 0.15)
				)
				(justify left bottom mirror)
			)
		)
		(property "Datasheet" "https://www.bourns.com/docs/product-datasheets/cr.pdf"
			(at 0 0 180)
			(layer "F.Fab")
			(hide yes)
			(effects
				(font
					(size 1.27 1.27)
					(thickness 0.15)
				)
			)
		)
		(property "Description" "SMD Chip Resistor, 470 ohm, ± 1%, 62.5 mW, 0402 [1005 Metric], Thick Film, General Purpose"
			(at 0 0 180)
			(layer "F.Fab")
			(hide yes)
			(effects
				(font
					(size 1.27 1.27)
					(thickness 0.15)
				)
			)
		)
		(property "Author" "Antmicro"
			(at 444.26 256.4 0)
			(layer "B.Fab")
			(hide yes)
			(effects
				(font
					(size 1 1)
					(thickness 0.15)
				)
				(justify mirror)
			)
		)
		(property "License" "Apache-2.0"
			(at 444.26 256.4 0)
			(layer "B.Fab")
			(hide yes)
			(effects
				(font
					(size 1 1)
					(thickness 0.15)
				)
				(justify mirror)
			)
		)
		(property "MPN" "CR0402-FX-4700GLF"
			(at 444.26 256.4 0)
			(layer "B.Fab")
			(hide yes)
			(effects
				(font
					(size 1 1)
					(thickness 0.15)
				)
				(justify mirror)
			)
		)
		(property "Manufacturer" "Bourns"
			(at 444.26 256.4 0)
			(layer "B.Fab")
			(hide yes)
			(effects
				(font
					(size 1 1)
					(thickness 0.15)
				)
				(justify mirror)
			)
		)
		(property "Public" ""
			(at 444.26 256.4 0)
			(layer "B.Fab")
			(hide yes)
			(effects
				(font
					(size 1 1)
					(thickness 0.15)
				)
				(justify mirror)
			)
		)
		(property "Tolerance" "1%"
			(at 444.26 256.4 0)
			(layer "B.Fab")
			(hide yes)
			(effects
				(font
					(size 1 1)
					(thickness 0.15)
				)
				(justify mirror)
			)
		)
		(property "Val" "470R"
			(at 444.26 256.4 0)
			(layer "B.Fab")
			(hide yes)
			(effects
				(font
					(size 1 1)
					(thickness 0.15)
				)
				(justify mirror)
			)
		)
		(sheetname "/FPGA GPIO/")
		(sheetfile "fpga-gpio.kicad_sch")
		(attr smd)
		(fp_rect
			(start -0.925 0.47)
			(end 0.925 -0.47)
			(stroke
				(width 0.05)
				(type default)
			)
			(fill no)
			(layer "B.CrtYd")
		)
		(fp_rect
			(start -0.5 0.25)
			(end 0.5 -0.25)
			(stroke
				(width 0.15)
				(type solid)
			)
			(fill no)
			(layer "B.Fab")
		)
		(fp_text user "Author: Antmicro"
			(at -0.95 -4.169 0)
			(layer "B.Fab")
			(effects
				(font
					(size 0.7 0.7)
					(thickness 0.15)
				)
				(justify left bottom mirror)
			)
		)
		(fp_text user "License: Apache-2.0"
			(at -0.95 -5.169 0)
			(layer "B.Fab")
			(effects
				(font
					(size 0.7 0.7)
					(thickness 0.15)
				)
				(justify left bottom mirror)
			)
		)
		(fp_text user "${REFERENCE}"
			(at -0.95 -3.168 0)
			(layer "B.Fab")
			(effects
				(font
					(size 0.7 0.7)
					(thickness 0.15)
				)
				(justify left bottom mirror)
			)
		)
		(pad "1" smd roundrect
			(at -0.48 0 180)
			(size 0.59 0.64)
			(layers "B.Cu" "B.Mask" "B.Paste")
			(roundrect_rratio 0.25)
			(net 540 "Net-(Q5-D)")
			(pintype "passive")
		)
		(pad "2" smd roundrect
			(at 0.48 0 180)
			(size 0.59 0.64)
			(layers "B.Cu" "B.Mask" "B.Paste")
			(roundrect_rratio 0.25)
			(net 539 "Net-(D6-C_{B})")
			(pintype "passive")
		)
	)
	(footprint "antmicro-footprints:R_0402_1005Metric"
		(layer "B.Cu")
		(at 218.975 136.775 180)
		(descr "Resistor SMD 0402")
		(tags "resistor SMD 0402")
		(property "Reference" "R56"
			(at 0.75 -0.475 0)
			(layer "B.SilkS")
			(effects
				(font
					(size 0.7 0.7)
					(thickness 0.15)
				)
				(justify left bottom mirror)
			)
		)
		(property "Value" "R_0R_0402"
			(at -1.011843 -1.772047 0)
			(layer "B.Fab")
			(hide yes)
			(effects
				(font
					(size 0.7 0.7)
					(thickness 0.15)
				)
				(justify left bottom mirror)
			)
		)
		(property "Datasheet" "https://industrial.panasonic.com/cdbs/www-data/pdf/RDA0000/AOA0000C301.pdf"
			(at 0 0 180)
			(layer "F.Fab")
			(hide yes)
			(effects
				(font
					(size 1.27 1.27)
					(thickness 0.15)
				)
			)
		)
		(property "Description" "SMD Chip Resistor, Jumper, 0 ohm, 100 mW, 0402 [1005 Metric], Thick Film, General Purpose"
			(at 0 0 180)
			(layer "F.Fab")
			(hide yes)
			(effects
				(font
					(size 1.27 1.27)
					(thickness 0.15)
				)
			)
		)
		(property "Author" "Antmicro"
			(at 437.95 273.55 0)
			(layer "B.Fab")
			(hide yes)
			(effects
				(font
					(size 1 1)
					(thickness 0.15)
				)
				(justify mirror)
			)
		)
		(property "Current" "1A"
			(at 437.95 273.55 0)
			(layer "B.Fab")
			(hide yes)
			(effects
				(font
					(size 1 1)
					(thickness 0.15)
				)
				(justify mirror)
			)
		)
		(property "License" "Apache-2.0"
			(at 437.95 273.55 0)
			(layer "B.Fab")
			(hide yes)
			(effects
				(font
					(size 1 1)
					(thickness 0.15)
				)
				(justify mirror)
			)
		)
		(property "MPN" "ERJ2GE0R00X"
			(at 437.95 273.55 0)
			(layer "B.Fab")
			(hide yes)
			(effects
				(font
					(size 1 1)
					(thickness 0.15)
				)
				(justify mirror)
			)
		)
		(property "Manufacturer" "Panasonic"
			(at 437.95 273.55 0)
			(layer "B.Fab")
			(hide yes)
			(effects
				(font
					(size 1 1)
					(thickness 0.15)
				)
				(justify mirror)
			)
		)
		(property "Public" ""
			(at 437.95 273.55 0)
			(layer "B.Fab")
			(hide yes)
			(effects
				(font
					(size 1 1)
					(thickness 0.15)
				)
				(justify mirror)
			)
		)
		(property "Tolerance" "~"
			(at 437.95 273.55 0)
			(layer "B.Fab")
			(hide yes)
			(effects
				(font
					(size 1 1)
					(thickness 0.15)
				)
				(justify mirror)
			)
		)
		(property "Val" "0R"
			(at 437.95 273.55 0)
			(layer "B.Fab")
			(hide yes)
			(effects
				(font
					(size 1 1)
					(thickness 0.15)
				)
				(justify mirror)
			)
		)
		(sheetname "/Memory/")
		(sheetfile "memory.kicad_sch")
		(attr smd)
		(fp_rect
			(start -0.925 0.47)
			(end 0.925 -0.47)
			(stroke
				(width 0.05)
				(type default)
			)
			(fill no)
			(layer "B.CrtYd")
		)
		(fp_rect
			(start -0.5 0.25)
			(end 0.5 -0.25)
			(stroke
				(width 0.15)
				(type solid)
			)
			(fill no)
			(layer "B.Fab")
		)
		(fp_text user "Author: Antmicro"
			(at -0.95 -4.169 0)
			(layer "B.Fab")
			(effects
				(font
					(size 0.7 0.7)
					(thickness 0.15)
				)
				(justify left bottom mirror)
			)
		)
		(fp_text user "${REFERENCE}"
			(at -0.95 -3.168 0)
			(layer "B.Fab")
			(effects
				(font
					(size 0.7 0.7)
					(thickness 0.15)
				)
				(justify left bottom mirror)
			)
		)
		(fp_text user "License: Apache-2.0"
			(at -0.95 -5.169 0)
			(layer "B.Fab")
			(effects
				(font
					(size 0.7 0.7)
					(thickness 0.15)
				)
				(justify left bottom mirror)
			)
		)
		(pad "1" smd roundrect
			(at -0.48 0 180)
			(size 0.59 0.64)
			(layers "B.Cu" "B.Mask" "B.Paste")
			(roundrect_rratio 0.25)
			(net 518 "Net-(R56-Pad1)")
			(pintype "passive")
		)
		(pad "2" smd roundrect
			(at 0.48 0 180)
			(size 0.59 0.64)
			(layers "B.Cu" "B.Mask" "B.Paste")
			(roundrect_rratio 0.25)
			(net 519 "SD_VDD_AUX")
			(pintype "passive")
		)
	)
	(footprint "antmicro-footprints:C_0402_1005Metric"
		(layer "B.Cu")
		(at 222.35 120.03 180)
		(descr "Capacitor SMD 0402")
		(tags "capacitor SMD 0402")
		(property "Reference" "C45"
			(at -1.05 1.33 0)
			(layer "B.SilkS")
			(effects
				(font
					(size 0.7 0.7)
					(thickness 0.15)
				)
				(justify left bottom mirror)
			)
		)
		(property "Value" "C_100n_0402"
			(at -1.022927 -2.155213 0)
			(layer "B.Fab")
			(hide yes)
			(effects
				(font
					(size 0.7 0.7)
					(thickness 0.15)
				)
				(justify left bottom mirror)
			)
		)
		(property "Datasheet" "https://www.murata.com/products/productdetail?partno=GRM155R61H104KE14%23"
			(at 0 0 180)
			(layer "F.Fab")
			(hide yes)
			(effects
				(font
					(size 1.27 1.27)
					(thickness 0.15)
				)
			)
		)
		(property "Description" "SMD Multilayer Ceramic Capacitor, 0.1 µF, 50 V, 0402 [1005 Metric], ± 10%, X5R, GRM Series"
			(at 0 0 180)
			(layer "F.Fab")
			(hide yes)
			(effects
				(font
					(size 1.27 1.27)
					(thickness 0.15)
				)
			)
		)
		(property "Author" "Antmicro"
			(at 444.7 240.06 0)
			(layer "B.Fab")
			(hide yes)
			(effects
				(font
					(size 1 1)
					(thickness 0.15)
				)
				(justify mirror)
			)
		)
		(property "Dielectric" "X5R"
			(at 444.7 240.06 0)
			(layer "B.Fab")
			(hide yes)
			(effects
				(font
					(size 1 1)
					(thickness 0.15)
				)
				(justify mirror)
			)
		)
		(property "License" "Apache-2.0"
			(at 444.7 240.06 0)
			(layer "B.Fab")
			(hide yes)
			(effects
				(font
					(size 1 1)
					(thickness 0.15)
				)
				(justify mirror)
			)
		)
		(property "MPN" "GRM155R61H104KE14D"
			(at 444.7 240.06 0)
			(layer "B.Fab")
			(hide yes)
			(effects
				(font
					(size 1 1)
					(thickness 0.15)
				)
				(justify mirror)
			)
		)
		(property "Manufacturer" "Murata"
			(at 444.7 240.06 0)
			(layer "B.Fab")
			(hide yes)
			(effects
				(font
					(size 1 1)
					(thickness 0.15)
				)
				(justify mirror)
			)
		)
		(property "Public" ""
			(at 444.7 240.06 0)
			(layer "B.Fab")
			(hide yes)
			(effects
				(font
					(size 1 1)
					(thickness 0.15)
				)
				(justify mirror)
			)
		)
		(property "Val" "100n"
			(at 444.7 240.06 0)
			(layer "B.Fab")
			(hide yes)
			(effects
				(font
					(size 1 1)
					(thickness 0.15)
				)
				(justify mirror)
			)
		)
		(property "Voltage" "50V"
			(at 444.7 240.06 0)
			(layer "B.Fab")
			(hide yes)
			(effects
				(font
					(size 1 1)
					(thickness 0.15)
				)
				(justify mirror)
			)
		)
		(sheetname "/FPGA GPIO/")
		(sheetfile "fpga-gpio.kicad_sch")
		(attr smd)
		(fp_rect
			(start -0.925 0.47)
			(end 0.925 -0.47)
			(stroke
				(width 0.05)
				(type default)
			)
			(fill no)
			(layer "B.CrtYd")
		)
		(fp_line
			(start 0.504 0.25)
			(end 0.504 -0.248)
			(stroke
				(width 0.15)
				(type solid)
			)
			(layer "B.Fab")
		)
		(fp_line
			(start 0.504 -0.248)
			(end -0.494 -0.248)
			(stroke
				(width 0.15)
				(type solid)
			)
			(layer "B.Fab")
		)
		(fp_line
			(start -0.494 0.25)
			(end 0.504 0.25)
			(stroke
				(width 0.15)
				(type solid)
			)
			(layer "B.Fab")
		)
		(fp_line
			(start -0.494 -0.248)
			(end -0.494 0.25)
			(stroke
				(width 0.15)
				(type solid)
			)
			(layer "B.Fab")
		)
		(fp_text user "License: Apache-2.0"
			(at -0.939 -5.799 0)
			(layer "B.Fab")
			(effects
				(font
					(size 0.7 0.7)
					(thickness 0.15)
				)
				(justify left bottom mirror)
			)
		)
		(fp_text user "${REFERENCE}"
			(at -0.939 -4.599 0)
			(layer "B.Fab")
			(effects
				(font
					(size 0.7 0.7)
					(thickness 0.15)
				)
				(justify left bottom mirror)
			)
		)
		(fp_text user "Author: Antmicro"
			(at -0.939 -3.399 0)
			(layer "B.Fab")
			(effects
				(font
					(size 0.7 0.7)
					(thickness 0.15)
				)
				(justify left bottom mirror)
			)
		)
		(pad "1" smd roundrect
			(at -0.48 0 180)
			(size 0.59 0.64)
			(layers "B.Cu" "B.Mask" "B.Paste")
			(roundrect_rratio 0.25)
			(net 50 "+3V3")
			(pintype "passive")
		)
		(pad "2" smd roundrect
			(at 0.48 0 180)
			(size 0.59 0.64)
			(layers "B.Cu" "B.Mask" "B.Paste")
			(roundrect_rratio 0.25)
			(net 417 "GND")
			(pintype "passive")
		)
	)
	(footprint "antmicro-footprints:R_0402_1005Metric"
		(layer "B.Cu")
		(at 219.92 124.82 180)
		(descr "Resistor SMD 0402")
		(tags "resistor SMD 0402")
		(property "Reference" "R103"
			(at -3.75 -0.34 0)
			(layer "B.SilkS")
			(effects
				(font
					(size 0.7 0.7)
					(thickness 0.15)
				)
				(justify left bottom mirror)
			)
		)
		(property "Value" "R_2k2_0402"
			(at -1.011843 -1.772047 0)
			(layer "B.Fab")
			(hide yes)
			(effects
				(font
					(size 0.7 0.7)
					(thickness 0.15)
				)
				(justify left bottom mirror)
			)
		)
		(property "Datasheet" "https://www.bourns.com/docs/product-datasheets/cr.pdf"
			(at 0 0 180)
			(layer "F.Fab")
			(hide yes)
			(effects
				(font
					(size 1.27 1.27)
					(thickness 0.15)
				)
			)
		)
		(property "Description" "SMD Chip Resistor, 2.2 kohm, ± 1%, 62.5 mW, 0402 [1005 Metric], Thick Film, General Purpose"
			(at 0 0 180)
			(layer "F.Fab")
			(hide yes)
			(effects
				(font
					(size 1.27 1.27)
					(thickness 0.15)
				)
			)
		)
		(property "Author" "Antmicro"
			(at 439.84 249.64 0)
			(layer "B.Fab")
			(hide yes)
			(effects
				(font
					(size 1 1)
					(thickness 0.15)
				)
				(justify mirror)
			)
		)
		(property "License" "Apache-2.0"
			(at 439.84 249.64 0)
			(layer "B.Fab")
			(hide yes)
			(effects
				(font
					(size 1 1)
					(thickness 0.15)
				)
				(justify mirror)
			)
		)
		(property "MPN" "CR0402-FX-2201GLF"
			(at 439.84 249.64 0)
			(layer "B.Fab")
			(hide yes)
			(effects
				(font
					(size 1 1)
					(thickness 0.15)
				)
				(justify mirror)
			)
		)
		(property "Manufacturer" "Bourns"
			(at 439.84 249.64 0)
			(layer "B.Fab")
			(hide yes)
			(effects
				(font
					(size 1 1)
					(thickness 0.15)
				)
				(justify mirror)
			)
		)
		(property "Public" ""
			(at 439.84 249.64 0)
			(layer "B.Fab")
			(hide yes)
			(effects
				(font
					(size 1 1)
					(thickness 0.15)
				)
				(justify mirror)
			)
		)
		(property "Tolerance" "1%"
			(at 439.84 249.64 0)
			(layer "B.Fab")
			(hide yes)
			(effects
				(font
					(size 1 1)
					(thickness 0.15)
				)
				(justify mirror)
			)
		)
		(property "Val" "2k2"
			(at 439.84 249.64 0)
			(layer "B.Fab")
			(hide yes)
			(effects
				(font
					(size 1 1)
					(thickness 0.15)
				)
				(justify mirror)
			)
		)
		(sheetname "/Ethernet/")
		(sheetfile "ethernet.kicad_sch")
		(attr smd)
		(fp_rect
			(start -0.925 0.47)
			(end 0.925 -0.47)
			(stroke
				(width 0.05)
				(type default)
			)
			(fill no)
			(layer "B.CrtYd")
		)
		(fp_rect
			(start -0.5 0.25)
			(end 0.5 -0.25)
			(stroke
				(width 0.15)
				(type solid)
			)
			(fill no)
			(layer "B.Fab")
		)
		(fp_text user "Author: Antmicro"
			(at -0.95 -4.169 0)
			(layer "B.Fab")
			(effects
				(font
					(size 0.7 0.7)
					(thickness 0.15)
				)
				(justify left bottom mirror)
			)
		)
		(fp_text user "${REFERENCE}"
			(at -0.95 -3.168 0)
			(layer "B.Fab")
			(effects
				(font
					(size 0.7 0.7)
					(thickness 0.15)
				)
				(justify left bottom mirror)
			)
		)
		(fp_text user "License: Apache-2.0"
			(at -0.95 -5.169 0)
			(layer "B.Fab")
			(effects
				(font
					(size 0.7 0.7)
					(thickness 0.15)
				)
				(justify left bottom mirror)
			)
		)
		(pad "1" smd roundrect
			(at -0.48 0 180)
			(size 0.59 0.64)
			(layers "B.Cu" "B.Mask" "B.Paste")
			(roundrect_rratio 0.25)
			(net 417 "GND")
			(pintype "passive")
		)
		(pad "2" smd roundrect
			(at 0.48 0 180)
			(size 0.59 0.64)
			(layers "B.Cu" "B.Mask" "B.Paste")
			(roundrect_rratio 0.25)
			(net 617 "/Ethernet/LED0")
			(pintype "passive")
		)
	)
	(footprint "antmicro-footprints:C_0402_1005Metric"
		(layer "B.Cu")
		(at 193.3 134.27)
		(descr "Capacitor SMD 0402")
		(tags "capacitor SMD 0402")
		(property "Reference" "C51"
			(at -2.85 -0.495 0)
			(layer "B.SilkS")
			(effects
				(font
					(size 0.7 0.7)
					(thickness 0.15)
				)
				(justify right bottom mirror)
			)
		)
		(property "Value" "C_1n_0402"
			(at -1.022927 -2.155213 0)
			(layer "B.Fab")
			(hide yes)
			(effects
				(font
					(size 0.7 0.7)
					(thickness 0.15)
				)
				(justify right bottom mirror)
			)
		)
		(property "Datasheet" "https://www.murata.com/products/productdetail?partno=GRM1555C1H102JA01%23"
			(at 0 0 0)
			(layer "F.Fab")
			(hide yes)
			(effects
				(font
					(size 1.27 1.27)
					(thickness 0.15)
				)
			)
		)
		(property "Description" "SMD Multilayer Ceramic Capacitor, 1000 pF, 50 V, 0402 [1005 Metric], ± 5%, C0G / NP0, GRM Series"
			(at 0 0 0)
			(layer "F.Fab")
			(hide yes)
			(effects
				(font
					(size 1.27 1.27)
					(thickness 0.15)
				)
			)
		)
		(property "Author" "Antmicro"
			(at 0 0 0)
			(layer "B.Fab")
			(hide yes)
			(effects
				(font
					(size 1 1)
					(thickness 0.15)
				)
				(justify mirror)
			)
		)
		(property "Dielectric" "C0G"
			(at 0 0 0)
			(layer "B.Fab")
			(hide yes)
			(effects
				(font
					(size 1 1)
					(thickness 0.15)
				)
				(justify mirror)
			)
		)
		(property "License" "Apache-2.0"
			(at 0 0 0)
			(layer "B.Fab")
			(hide yes)
			(effects
				(font
					(size 1 1)
					(thickness 0.15)
				)
				(justify mirror)
			)
		)
		(property "MPN" "GRM1555C1H102JA01D"
			(at 0 0 0)
			(layer "B.Fab")
			(hide yes)
			(effects
				(font
					(size 1 1)
					(thickness 0.15)
				)
				(justify mirror)
			)
		)
		(property "Manufacturer" "Murata"
			(at 0 0 0)
			(layer "B.Fab")
			(hide yes)
			(effects
				(font
					(size 1 1)
					(thickness 0.15)
				)
				(justify mirror)
			)
		)
		(property "Public" ""
			(at 0 0 0)
			(layer "B.Fab")
			(hide yes)
			(effects
				(font
					(size 1 1)
					(thickness 0.15)
				)
				(justify mirror)
			)
		)
		(property "Val" "1n"
			(at 0 0 0)
			(layer "B.Fab")
			(hide yes)
			(effects
				(font
					(size 1 1)
					(thickness 0.15)
				)
				(justify mirror)
			)
		)
		(property "Voltage" "50V"
			(at 0 0 0)
			(layer "B.Fab")
			(hide yes)
			(effects
				(font
					(size 1 1)
					(thickness 0.15)
				)
				(justify mirror)
			)
		)
		(sheetname "/FPGA Supply/")
		(sheetfile "fpga-supply.kicad_sch")
		(attr smd)
		(fp_rect
			(start -0.925 0.47)
			(end 0.925 -0.47)
			(stroke
				(width 0.05)
				(type default)
			)
			(fill no)
			(layer "B.CrtYd")
		)
		(fp_line
			(start -0.494 -0.248)
			(end -0.494 0.25)
			(stroke
				(width 0.15)
				(type solid)
			)
			(layer "B.Fab")
		)
		(fp_line
			(start -0.494 0.25)
			(end 0.504 0.25)
			(stroke
				(width 0.15)
				(type solid)
			)
			(layer "B.Fab")
		)
		(fp_line
			(start 0.504 -0.248)
			(end -0.494 -0.248)
			(stroke
				(width 0.15)
				(type solid)
			)
			(layer "B.Fab")
		)
		(fp_line
			(start 0.504 0.25)
			(end 0.504 -0.248)
			(stroke
				(width 0.15)
				(type solid)
			)
			(layer "B.Fab")
		)
		(fp_text user "Author: Antmicro"
			(at -0.939 -3.399 180)
			(layer "B.Fab")
			(effects
				(font
					(size 0.7 0.7)
					(thickness 0.15)
				)
				(justify left bottom mirror)
			)
		)
		(fp_text user "${REFERENCE}"
			(at -0.939 -4.599 180)
			(layer "B.Fab")
			(effects
				(font
					(size 0.7 0.7)
					(thickness 0.15)
				)
				(justify left bottom mirror)
			)
		)
		(fp_text user "License: Apache-2.0"
			(at -0.939 -5.799 180)
			(layer "B.Fab")
			(effects
				(font
					(size 0.7 0.7)
					(thickness 0.15)
				)
				(justify left bottom mirror)
			)
		)
		(pad "1" smd roundrect
			(at -0.48 0)
			(size 0.59 0.64)
			(layers "B.Cu" "B.Mask" "B.Paste")
			(roundrect_rratio 0.25)
			(net 417 "GND")
			(pintype "passive")
		)
		(pad "2" smd roundrect
			(at 0.48 0)
			(size 0.59 0.64)
			(layers "B.Cu" "B.Mask" "B.Paste")
			(roundrect_rratio 0.25)
			(net 48 "+1V8")
			(pintype "passive")
		)
	)
	(footprint "antmicro-footprints:C_0402_1005Metric"
		(layer "B.Cu")
		(at 206.14 149.61 180)
		(descr "Capacitor SMD 0402")
		(tags "capacitor SMD 0402")
		(property "Reference" "C212"
			(at 0.8 -0.4 0)
			(layer "B.SilkS")
			(effects
				(font
					(size 0.7 0.7)
					(thickness 0.15)
				)
				(justify left bottom mirror)
			)
		)
		(property "Value" "C_100n_0402"
			(at -1.022927 -2.155213 0)
			(layer "B.Fab")
			(hide yes)
			(effects
				(font
					(size 0.7 0.7)
					(thickness 0.15)
				)
				(justify left bottom mirror)
			)
		)
		(property "Datasheet" "https://www.murata.com/products/productdetail?partno=GRM155R61H104KE14%23"
			(at 0 0 180)
			(layer "F.Fab")
			(hide yes)
			(effects
				(font
					(size 1.27 1.27)
					(thickness 0.15)
				)
			)
		)
		(property "Description" "SMD Multilayer Ceramic Capacitor, 0.1 µF, 50 V, 0402 [1005 Metric], ± 10%, X5R, GRM Series"
			(at 0 0 180)
			(layer "F.Fab")
			(hide yes)
			(effects
				(font
					(size 1.27 1.27)
					(thickness 0.15)
				)
			)
		)
		(property "Author" "Antmicro"
			(at 412.28 299.22 0)
			(layer "B.Fab")
			(hide yes)
			(effects
				(font
					(size 1 1)
					(thickness 0.15)
				)
				(justify mirror)
			)
		)
		(property "Dielectric" "X5R"
			(at 412.28 299.22 0)
			(layer "B.Fab")
			(hide yes)
			(effects
				(font
					(size 1 1)
					(thickness 0.15)
				)
				(justify mirror)
			)
		)
		(property "License" "Apache-2.0"
			(at 412.28 299.22 0)
			(layer "B.Fab")
			(hide yes)
			(effects
				(font
					(size 1 1)
					(thickness 0.15)
				)
				(justify mirror)
			)
		)
		(property "MPN" "GRM155R61H104KE14D"
			(at 412.28 299.22 0)
			(layer "B.Fab")
			(hide yes)
			(effects
				(font
					(size 1 1)
					(thickness 0.15)
				)
				(justify mirror)
			)
		)
		(property "Manufacturer" "Murata"
			(at 412.28 299.22 0)
			(layer "B.Fab")
			(hide yes)
			(effects
				(font
					(size 1 1)
					(thickness 0.15)
				)
				(justify mirror)
			)
		)
		(property "Public" ""
			(at 412.28 299.22 0)
			(layer "B.Fab")
			(hide yes)
			(effects
				(font
					(size 1 1)
					(thickness 0.15)
				)
				(justify mirror)
			)
		)
		(property "Val" "100n"
			(at 412.28 299.22 0)
			(layer "B.Fab")
			(hide yes)
			(effects
				(font
					(size 1 1)
					(thickness 0.15)
				)
				(justify mirror)
			)
		)
		(property "Voltage" "50V"
			(at 412.28 299.22 0)
			(layer "B.Fab")
			(hide yes)
			(effects
				(font
					(size 1 1)
					(thickness 0.15)
				)
				(justify mirror)
			)
		)
		(sheetname "/MIPI CrossLink/")
		(sheetfile "crosslink.kicad_sch")
		(attr smd)
		(fp_rect
			(start -0.925 0.47)
			(end 0.925 -0.47)
			(stroke
				(width 0.05)
				(type default)
			)
			(fill no)
			(layer "B.CrtYd")
		)
		(fp_line
			(start 0.504 0.25)
			(end 0.504 -0.248)
			(stroke
				(width 0.15)
				(type solid)
			)
			(layer "B.Fab")
		)
		(fp_line
			(start 0.504 -0.248)
			(end -0.494 -0.248)
			(stroke
				(width 0.15)
				(type solid)
			)
			(layer "B.Fab")
		)
		(fp_line
			(start -0.494 0.25)
			(end 0.504 0.25)
			(stroke
				(width 0.15)
				(type solid)
			)
			(layer "B.Fab")
		)
		(fp_line
			(start -0.494 -0.248)
			(end -0.494 0.25)
			(stroke
				(width 0.15)
				(type solid)
			)
			(layer "B.Fab")
		)
		(fp_text user "Author: Antmicro"
			(at -0.939 -3.399 0)
			(layer "B.Fab")
			(effects
				(font
					(size 0.7 0.7)
					(thickness 0.15)
				)
				(justify left bottom mirror)
			)
		)
		(fp_text user "License: Apache-2.0"
			(at -0.939 -5.799 0)
			(layer "B.Fab")
			(effects
				(font
					(size 0.7 0.7)
					(thickness 0.15)
				)
				(justify left bottom mirror)
			)
		)
		(fp_text user "${REFERENCE}"
			(at -0.939 -4.599 0)
			(layer "B.Fab")
			(effects
				(font
					(size 0.7 0.7)
					(thickness 0.15)
				)
				(justify left bottom mirror)
			)
		)
		(pad "1" smd roundrect
			(at -0.48 0 180)
			(size 0.59 0.64)
			(layers "B.Cu" "B.Mask" "B.Paste")
			(roundrect_rratio 0.25)
			(net 417 "GND")
			(pintype "passive")
		)
		(pad "2" smd roundrect
			(at 0.48 0 180)
			(size 0.59 0.64)
			(layers "B.Cu" "B.Mask" "B.Paste")
			(roundrect_rratio 0.25)
			(net 205 "/MIPI CrossLink/CL_VCCA_DPHY1")
			(pintype "passive")
		)
	)
	(footprint "antmicro-footprints:R_0402_1005Metric"
		(layer "B.Cu")
		(at 182.41 139.3 -90)
		(descr "Resistor SMD 0402")
		(tags "resistor SMD 0402")
		(property "Reference" "R97"
			(at -2.14 -1.94 225)
			(layer "B.SilkS")
			(effects
				(font
					(size 0.7 0.7)
					(thickness 0.15)
				)
				(justify left bottom mirror)
			)
		)
		(property "Value" "R_0R_0402"
			(at -1.011843 -1.772047 90)
			(layer "B.Fab")
			(hide yes)
			(effects
				(font
					(size 0.7 0.7)
					(thickness 0.15)
				)
				(justify left bottom mirror)
			)
		)
		(property "Datasheet" "https://industrial.panasonic.com/cdbs/www-data/pdf/RDA0000/AOA0000C301.pdf"
			(at 0 0 270)
			(layer "F.Fab")
			(hide yes)
			(effects
				(font
					(size 1.27 1.27)
					(thickness 0.15)
				)
			)
		)
		(property "Description" "SMD Chip Resistor, Jumper, 0 ohm, 100 mW, 0402 [1005 Metric], Thick Film, General Purpose"
			(at 0 0 270)
			(layer "F.Fab")
			(hide yes)
			(effects
				(font
					(size 1.27 1.27)
					(thickness 0.15)
				)
			)
		)
		(property "Author" "Antmicro"
			(at 43.11 321.71 0)
			(layer "B.Fab")
			(hide yes)
			(effects
				(font
					(size 1 1)
					(thickness 0.15)
				)
				(justify mirror)
			)
		)
		(property "Current" "1A"
			(at 43.11 321.71 0)
			(layer "B.Fab")
			(hide yes)
			(effects
				(font
					(size 1 1)
					(thickness 0.15)
				)
				(justify mirror)
			)
		)
		(property "License" "Apache-2.0"
			(at 43.11 321.71 0)
			(layer "B.Fab")
			(hide yes)
			(effects
				(font
					(size 1 1)
					(thickness 0.15)
				)
				(justify mirror)
			)
		)
		(property "MPN" "ERJ2GE0R00X"
			(at 43.11 321.71 0)
			(layer "B.Fab")
			(hide yes)
			(effects
				(font
					(size 1 1)
					(thickness 0.15)
				)
				(justify mirror)
			)
		)
		(property "Manufacturer" "Panasonic"
			(at 43.11 321.71 0)
			(layer "B.Fab")
			(hide yes)
			(effects
				(font
					(size 1 1)
					(thickness 0.15)
				)
				(justify mirror)
			)
		)
		(property "Public" ""
			(at 43.11 321.71 0)
			(layer "B.Fab")
			(hide yes)
			(effects
				(font
					(size 1 1)
					(thickness 0.15)
				)
				(justify mirror)
			)
		)
		(property "Tolerance" "~"
			(at 43.11 321.71 0)
			(layer "B.Fab")
			(hide yes)
			(effects
				(font
					(size 1 1)
					(thickness 0.15)
				)
				(justify mirror)
			)
		)
		(property "Val" "0R"
			(at 43.11 321.71 0)
			(layer "B.Fab")
			(hide yes)
			(effects
				(font
					(size 1 1)
					(thickness 0.15)
				)
				(justify mirror)
			)
		)
		(sheetname "/Supply/")
		(sheetfile "supply.kicad_sch")
		(attr smd)
		(fp_rect
			(start -0.925 0.47)
			(end 0.925 -0.47)
			(stroke
				(width 0.05)
				(type default)
			)
			(fill no)
			(layer "B.CrtYd")
		)
		(fp_rect
			(start -0.5 0.25)
			(end 0.5 -0.25)
			(stroke
				(width 0.15)
				(type solid)
			)
			(fill no)
			(layer "B.Fab")
		)
		(fp_text user "${REFERENCE}"
			(at -0.95 -3.168 90)
			(layer "B.Fab")
			(effects
				(font
					(size 0.7 0.7)
					(thickness 0.15)
				)
				(justify left bottom mirror)
			)
		)
		(fp_text user "Author: Antmicro"
			(at -0.95 -4.169 90)
			(layer "B.Fab")
			(effects
				(font
					(size 0.7 0.7)
					(thickness 0.15)
				)
				(justify left bottom mirror)
			)
		)
		(fp_text user "License: Apache-2.0"
			(at -0.95 -5.169 90)
			(layer "B.Fab")
			(effects
				(font
					(size 0.7 0.7)
					(thickness 0.15)
				)
				(justify left bottom mirror)
			)
		)
		(pad "1" smd roundrect
			(at -0.48 0 270)
			(size 0.59 0.64)
			(layers "B.Cu" "B.Mask" "B.Paste")
			(roundrect_rratio 0.25)
			(net 272 "/Supply/SENSE3_P")
			(pintype "passive")
		)
		(pad "2" smd roundrect
			(at 0.48 0 270)
			(size 0.59 0.64)
			(layers "B.Cu" "B.Mask" "B.Paste")
			(roundrect_rratio 0.25)
			(net 578 "Net-(U6-SENSE3+)")
			(pintype "passive")
		)
	)
	(footprint "antmicro-footprints:C_0402_1005Metric"
		(layer "B.Cu")
		(at 180.025 136.45 90)
		(descr "Capacitor SMD 0402")
		(tags "capacitor SMD 0402")
		(property "Reference" "C76"
			(at -0.975 1.435 90)
			(layer "B.SilkS")
			(effects
				(font
					(size 0.7 0.7)
					(thickness 0.15)
				)
				(justify right bottom mirror)
			)
		)
		(property "Value" "C_10u_0402"
			(at -1.022927 -2.155213 90)
			(layer "B.Fab")
			(hide yes)
			(effects
				(font
					(size 0.7 0.7)
					(thickness 0.15)
				)
				(justify right bottom mirror)
			)
		)
		(property "Datasheet" "https://www.yageo.com/en/Chart/Download/pdf/CC0402MRX5R5BB106"
			(at 0 0 90)
			(layer "F.Fab")
			(hide yes)
			(effects
				(font
					(size 1.27 1.27)
					(thickness 0.15)
				)
			)
		)
		(property "Description" "SMD Multilayer Ceramic Capacitor, 10 µF, 6.3 V, 0402 [1005 Metric], ± 20%, X5R, CC Series"
			(at 0 0 90)
			(layer "F.Fab")
			(hide yes)
			(effects
				(font
					(size 1.27 1.27)
					(thickness 0.15)
				)
			)
		)
		(property "Author" "Antmicro"
			(at 316.475 -43.575 0)
			(layer "B.Fab")
			(hide yes)
			(effects
				(font
					(size 1 1)
					(thickness 0.15)
				)
				(justify mirror)
			)
		)
		(property "Dielectric" ""
			(at 316.475 -43.575 0)
			(layer "B.Fab")
			(hide yes)
			(effects
				(font
					(size 1 1)
					(thickness 0.15)
				)
				(justify mirror)
			)
		)
		(property "License" "Apache-2.0"
			(at 316.475 -43.575 0)
			(layer "B.Fab")
			(hide yes)
			(effects
				(font
					(size 1 1)
					(thickness 0.15)
				)
				(justify mirror)
			)
		)
		(property "MPN" "CC0402MRX5R5BB106"
			(at 316.475 -43.575 0)
			(layer "B.Fab")
			(hide yes)
			(effects
				(font
					(size 1 1)
					(thickness 0.15)
				)
				(justify mirror)
			)
		)
		(property "Manufacturer" "YAGEO"
			(at 316.475 -43.575 0)
			(layer "B.Fab")
			(hide yes)
			(effects
				(font
					(size 1 1)
					(thickness 0.15)
				)
				(justify mirror)
			)
		)
		(property "Public" ""
			(at 316.475 -43.575 0)
			(layer "B.Fab")
			(hide yes)
			(effects
				(font
					(size 1 1)
					(thickness 0.15)
				)
				(justify mirror)
			)
		)
		(property "Val" "10u"
			(at 316.475 -43.575 0)
			(layer "B.Fab")
			(hide yes)
			(effects
				(font
					(size 1 1)
					(thickness 0.15)
				)
				(justify mirror)
			)
		)
		(property "Voltage" ""
			(at 316.475 -43.575 0)
			(layer "B.Fab")
			(hide yes)
			(effects
				(font
					(size 1 1)
					(thickness 0.15)
				)
				(justify mirror)
			)
		)
		(sheetname "/LPDDR4/")
		(sheetfile "lpddr.kicad_sch")
		(attr smd)
		(fp_rect
			(start -0.925 0.47)
			(end 0.925 -0.47)
			(stroke
				(width 0.05)
				(type default)
			)
			(fill no)
			(layer "B.CrtYd")
		)
		(fp_line
			(start 0.504 -0.248)
			(end -0.494 -0.248)
			(stroke
				(width 0.15)
				(type solid)
			)
			(layer "B.Fab")
		)
		(fp_line
			(start -0.494 -0.248)
			(end -0.494 0.25)
			(stroke
				(width 0.15)
				(type solid)
			)
			(layer "B.Fab")
		)
		(fp_line
			(start 0.504 0.25)
			(end 0.504 -0.248)
			(stroke
				(width 0.15)
				(type solid)
			)
			(layer "B.Fab")
		)
		(fp_line
			(start -0.494 0.25)
			(end 0.504 0.25)
			(stroke
				(width 0.15)
				(type solid)
			)
			(layer "B.Fab")
		)
		(fp_text user "License: Apache-2.0"
			(at -0.939 -5.799 270)
			(layer "B.Fab")
			(effects
				(font
					(size 0.7 0.7)
					(thickness 0.15)
				)
				(justify left bottom mirror)
			)
		)
		(fp_text user "${REFERENCE}"
			(at -0.939 -4.599 270)
			(layer "B.Fab")
			(effects
				(font
					(size 0.7 0.7)
					(thickness 0.15)
				)
				(justify left bottom mirror)
			)
		)
		(fp_text user "Author: Antmicro"
			(at -0.939 -3.399 270)
			(layer "B.Fab")
			(effects
				(font
					(size 0.7 0.7)
					(thickness 0.15)
				)
				(justify left bottom mirror)
			)
		)
		(pad "1" smd roundrect
			(at -0.48 0 90)
			(size 0.59 0.64)
			(layers "B.Cu" "B.Mask" "B.Paste")
			(roundrect_rratio 0.25)
			(net 417 "GND")
			(pintype "passive")
		)
		(pad "2" smd roundrect
			(at 0.48 0 90)
			(size 0.59 0.64)
			(layers "B.Cu" "B.Mask" "B.Paste")
			(roundrect_rratio 0.25)
			(net 2 "+1V1")
			(pintype "passive")
		)
	)
	(footprint "antmicro-footprints:R_0402_1005Metric"
		(layer "B.Cu")
		(at 201.5 123.6 180)
		(descr "Resistor SMD 0402")
		(tags "resistor SMD 0402")
		(property "Reference" "R106"
			(at -4.73 -0.9 0)
			(layer "B.SilkS")
			(effects
				(font
					(size 0.7 0.7)
					(thickness 0.15)
				)
				(justify left bottom mirror)
			)
		)
		(property "Value" "R_4k7_0402"
			(at -1.011843 -1.772047 0)
			(layer "B.Fab")
			(hide yes)
			(effects
				(font
					(size 0.7 0.7)
					(thickness 0.15)
				)
				(justify left bottom mirror)
			)
		)
		(property "Datasheet" "https://www.bourns.com/docs/product-datasheets/cr.pdf"
			(at 0 0 180)
			(layer "F.Fab")
			(hide yes)
			(effects
				(font
					(size 1.27 1.27)
					(thickness 0.15)
				)
			)
		)
		(property "Description" "SMD Chip Resistor, 4.7 kohm, ± 1%, 62.5 mW, 0402 [1005 Metric], Thick Film, General Purpose"
			(at 0 0 180)
			(layer "F.Fab")
			(hide yes)
			(effects
				(font
					(size 1.27 1.27)
					(thickness 0.15)
				)
			)
		)
		(property "Author" "Antmicro"
			(at 403 247.2 0)
			(layer "B.Fab")
			(hide yes)
			(effects
				(font
					(size 1 1)
					(thickness 0.15)
				)
				(justify mirror)
			)
		)
		(property "License" "Apache-2.0"
			(at 403 247.2 0)
			(layer "B.Fab")
			(hide yes)
			(effects
				(font
					(size 1 1)
					(thickness 0.15)
				)
				(justify mirror)
			)
		)
		(property "MPN" "CR0402-FX-4701GLF"
			(at 403 247.2 0)
			(layer "B.Fab")
			(hide yes)
			(effects
				(font
					(size 1 1)
					(thickness 0.15)
				)
				(justify mirror)
			)
		)
		(property "Manufacturer" "Bourns"
			(at 403 247.2 0)
			(layer "B.Fab")
			(hide yes)
			(effects
				(font
					(size 1 1)
					(thickness 0.15)
				)
				(justify mirror)
			)
		)
		(property "Public" ""
			(at 403 247.2 0)
			(layer "B.Fab")
			(hide yes)
			(effects
				(font
					(size 1 1)
					(thickness 0.15)
				)
				(justify mirror)
			)
		)
		(property "Tolerance" "1%"
			(at 403 247.2 0)
			(layer "B.Fab")
			(hide yes)
			(effects
				(font
					(size 1 1)
					(thickness 0.15)
				)
				(justify mirror)
			)
		)
		(property "Val" "4k7"
			(at 403 247.2 0)
			(layer "B.Fab")
			(hide yes)
			(effects
				(font
					(size 1 1)
					(thickness 0.15)
				)
				(justify mirror)
			)
		)
		(sheetname "/FPGA MSSIO/")
		(sheetfile "fpga-mssio.kicad_sch")
		(attr smd)
		(fp_rect
			(start -0.925 0.47)
			(end 0.925 -0.47)
			(stroke
				(width 0.05)
				(type default)
			)
			(fill no)
			(layer "B.CrtYd")
		)
		(fp_rect
			(start -0.5 0.25)
			(end 0.5 -0.25)
			(stroke
				(width 0.15)
				(type solid)
			)
			(fill no)
			(layer "B.Fab")
		)
		(fp_text user "License: Apache-2.0"
			(at -0.95 -5.169 0)
			(layer "B.Fab")
			(effects
				(font
					(size 0.7 0.7)
					(thickness 0.15)
				)
				(justify left bottom mirror)
			)
		)
		(fp_text user "${REFERENCE}"
			(at -0.95 -3.168 0)
			(layer "B.Fab")
			(effects
				(font
					(size 0.7 0.7)
					(thickness 0.15)
				)
				(justify left bottom mirror)
			)
		)
		(fp_text user "Author: Antmicro"
			(at -0.95 -4.169 0)
			(layer "B.Fab")
			(effects
				(font
					(size 0.7 0.7)
					(thickness 0.15)
				)
				(justify left bottom mirror)
			)
		)
		(pad "1" smd roundrect
			(at -0.48 0 180)
			(size 0.59 0.64)
			(layers "B.Cu" "B.Mask" "B.Paste")
			(roundrect_rratio 0.25)
			(net 100 "/FPGA MSSIO/SUPPLY.SDA")
			(pintype "passive")
		)
		(pad "2" smd roundrect
			(at 0.48 0 180)
			(size 0.59 0.64)
			(layers "B.Cu" "B.Mask" "B.Paste")
			(roundrect_rratio 0.25)
			(net 649 "VDD")
			(pintype "passive")
		)
	)
	(footprint "antmicro-footprints:R_0603_1608Metric"
		(layer "B.Cu")
		(at 180.5 139 180)
		(descr "Resistor SMD 0603")
		(tags "resistor SMD 0603")
		(property "Reference" "R53"
			(at -1.3 -1.45 0)
			(layer "B.SilkS")
			(effects
				(font
					(size 0.7 0.7)
					(thickness 0.15)
				)
				(justify left bottom mirror)
			)
		)
		(property "Value" "R_0R_22.4A_0603"
			(at 0 -1.6 0)
			(layer "B.Fab")
			(hide yes)
			(effects
				(font
					(size 0.7 0.7)
					(thickness 0.15)
				)
				(justify left bottom mirror)
			)
		)
		(property "Datasheet" "https://fscdn.rohm.com/en/products/databook/datasheet/passive/resistor/chip_resistor/pmr-jpw-e.pdf"
			(at 0 0 180)
			(layer "F.Fab")
			(hide yes)
			(effects
				(font
					(size 1.27 1.27)
					(thickness 0.15)
				)
			)
		)
		(property "Description" "SMD Chip Resistor"
			(at 0 0 180)
			(layer "F.Fab")
			(hide yes)
			(effects
				(font
					(size 1.27 1.27)
					(thickness 0.15)
				)
			)
		)
		(property "Author" "Antmicro"
			(at 361 278 0)
			(layer "B.Fab")
			(hide yes)
			(effects
				(font
					(size 1 1)
					(thickness 0.15)
				)
				(justify mirror)
			)
		)
		(property "License" "Apache-2.0"
			(at 361 278 0)
			(layer "B.Fab")
			(hide yes)
			(effects
				(font
					(size 1 1)
					(thickness 0.15)
				)
				(justify mirror)
			)
		)
		(property "MPN" "PMR03EZPJ000"
			(at 361 278 0)
			(layer "B.Fab")
			(hide yes)
			(effects
				(font
					(size 1 1)
					(thickness 0.15)
				)
				(justify mirror)
			)
		)
		(property "Manufacturer" "ROHM Semiconductor"
			(at 361 278 0)
			(layer "B.Fab")
			(hide yes)
			(effects
				(font
					(size 1 1)
					(thickness 0.15)
				)
				(justify mirror)
			)
		)
		(property "Max. Curr." "22.4A"
			(at 361 278 0)
			(layer "B.Fab")
			(hide yes)
			(effects
				(font
					(size 1 1)
					(thickness 0.15)
				)
				(justify mirror)
			)
		)
		(property "Public" ""
			(at 361 278 0)
			(layer "B.Fab")
			(hide yes)
			(effects
				(font
					(size 1 1)
					(thickness 0.15)
				)
				(justify mirror)
			)
		)
		(property "Tolerance" "template_tolerance"
			(at 361 278 0)
			(layer "B.Fab")
			(hide yes)
			(effects
				(font
					(size 1 1)
					(thickness 0.15)
				)
				(justify mirror)
			)
		)
		(property "Val" "0R"
			(at 361 278 0)
			(layer "B.Fab")
			(hide yes)
			(effects
				(font
					(size 1 1)
					(thickness 0.15)
				)
				(justify mirror)
			)
		)
		(sheetname "/Supply/")
		(sheetfile "supply.kicad_sch")
		(attr smd)
		(fp_line
			(start -0.15 0.4)
			(end 0.15 0.4)
			(stroke
				(width 0.15)
				(type solid)
			)
			(layer "B.SilkS")
		)
		(fp_line
			(start -0.15 -0.4)
			(end 0.15 -0.4)
			(stroke
				(width 0.15)
				(type solid)
			)
			(layer "B.SilkS")
		)
		(fp_rect
			(start -1.25 0.65)
			(end 1.25 -0.65)
			(stroke
				(width 0.05)
				(type solid)
			)
			(fill no)
			(layer "B.CrtYd")
		)
		(fp_rect
			(start -0.8 0.4)
			(end 0.8 -0.4)
			(stroke
				(width 0.15)
				(type solid)
			)
			(fill no)
			(layer "B.Fab")
		)
		(fp_text user "Author: Antmicro"
			(at -1.25 -4.9 0)
			(layer "B.Fab")
			(effects
				(font
					(size 0.7 0.7)
					(thickness 0.15)
				)
				(justify left bottom mirror)
			)
		)
		(fp_text user "${REFERENCE}"
			(at -1.25 -3.898 0)
			(layer "B.Fab")
			(effects
				(font
					(size 0.7 0.7)
					(thickness 0.15)
				)
				(justify left bottom mirror)
			)
		)
		(fp_text user "License: Apache-2.0"
			(at -1.25 -5.9 0)
			(layer "B.Fab")
			(effects
				(font
					(size 0.7 0.7)
					(thickness 0.15)
				)
				(justify left bottom mirror)
			)
		)
		(pad "1" smd roundrect
			(at -0.7 0 180)
			(size 0.8 1)
			(layers "B.Cu" "B.Mask" "B.Paste")
			(roundrect_rratio 0.2)
			(net 632 "Net-(U7-OUT2)")
			(pintype "passive")
		)
		(pad "2" smd roundrect
			(at 0.7 0 180)
			(size 0.8 1)
			(layers "B.Cu" "B.Mask" "B.Paste")
			(roundrect_rratio 0.2)
			(net 418 "+2V5")
			(pintype "passive")
		)
	)
	(footprint "antmicro-footprints:C_0402_1005Metric"
		(layer "B.Cu")
		(at 198.48 138.1)
		(descr "Capacitor SMD 0402")
		(tags "capacitor SMD 0402")
		(property "Reference" "C20"
			(at -11.23 -4.95 0)
			(layer "B.SilkS")
			(effects
				(font
					(size 0.7 0.7)
					(thickness 0.15)
				)
				(justify right bottom mirror)
			)
		)
		(property "Value" "C_10u_0402"
			(at -1.022927 -2.155213 0)
			(layer "B.Fab")
			(hide yes)
			(effects
				(font
					(size 0.7 0.7)
					(thickness 0.15)
				)
				(justify right bottom mirror)
			)
		)
		(property "Datasheet" "https://www.yageo.com/en/Chart/Download/pdf/CC0402MRX5R5BB106"
			(at 0 0 0)
			(layer "F.Fab")
			(hide yes)
			(effects
				(font
					(size 1.27 1.27)
					(thickness 0.15)
				)
			)
		)
		(property "Description" "SMD Multilayer Ceramic Capacitor, 10 µF, 6.3 V, 0402 [1005 Metric], ± 20%, X5R, CC Series"
			(at 0 0 0)
			(layer "F.Fab")
			(hide yes)
			(effects
				(font
					(size 1.27 1.27)
					(thickness 0.15)
				)
			)
		)
		(property "Author" "Antmicro"
			(at 0 0 0)
			(layer "B.Fab")
			(hide yes)
			(effects
				(font
					(size 1 1)
					(thickness 0.15)
				)
				(justify mirror)
			)
		)
		(property "Dielectric" ""
			(at 0 0 0)
			(layer "B.Fab")
			(hide yes)
			(effects
				(font
					(size 1 1)
					(thickness 0.15)
				)
				(justify mirror)
			)
		)
		(property "License" "Apache-2.0"
			(at 0 0 0)
			(layer "B.Fab")
			(hide yes)
			(effects
				(font
					(size 1 1)
					(thickness 0.15)
				)
				(justify mirror)
			)
		)
		(property "MPN" "CC0402MRX5R5BB106"
			(at 0 0 0)
			(layer "B.Fab")
			(hide yes)
			(effects
				(font
					(size 1 1)
					(thickness 0.15)
				)
				(justify mirror)
			)
		)
		(property "Manufacturer" "YAGEO"
			(at 0 0 0)
			(layer "B.Fab")
			(hide yes)
			(effects
				(font
					(size 1 1)
					(thickness 0.15)
				)
				(justify mirror)
			)
		)
		(property "Public" ""
			(at 0 0 0)
			(layer "B.Fab")
			(hide yes)
			(effects
				(font
					(size 1 1)
					(thickness 0.15)
				)
				(justify mirror)
			)
		)
		(property "Val" "10u"
			(at 0 0 0)
			(layer "B.Fab")
			(hide yes)
			(effects
				(font
					(size 1 1)
					(thickness 0.15)
				)
				(justify mirror)
			)
		)
		(property "Voltage" ""
			(at 0 0 0)
			(layer "B.Fab")
			(hide yes)
			(effects
				(font
					(size 1 1)
					(thickness 0.15)
				)
				(justify mirror)
			)
		)
		(sheetname "/FPGA Supply/")
		(sheetfile "fpga-supply.kicad_sch")
		(attr smd)
		(fp_rect
			(start -0.925 0.47)
			(end 0.925 -0.47)
			(stroke
				(width 0.05)
				(type default)
			)
			(fill no)
			(layer "B.CrtYd")
		)
		(fp_line
			(start -0.494 -0.248)
			(end -0.494 0.25)
			(stroke
				(width 0.15)
				(type solid)
			)
			(layer "B.Fab")
		)
		(fp_line
			(start -0.494 0.25)
			(end 0.504 0.25)
			(stroke
				(width 0.15)
				(type solid)
			)
			(layer "B.Fab")
		)
		(fp_line
			(start 0.504 -0.248)
			(end -0.494 -0.248)
			(stroke
				(width 0.15)
				(type solid)
			)
			(layer "B.Fab")
		)
		(fp_line
			(start 0.504 0.25)
			(end 0.504 -0.248)
			(stroke
				(width 0.15)
				(type solid)
			)
			(layer "B.Fab")
		)
		(fp_text user "License: Apache-2.0"
			(at -0.939 -5.799 180)
			(layer "B.Fab")
			(effects
				(font
					(size 0.7 0.7)
					(thickness 0.15)
				)
				(justify left bottom mirror)
			)
		)
		(fp_text user "${REFERENCE}"
			(at -0.939 -4.599 180)
			(layer "B.Fab")
			(effects
				(font
					(size 0.7 0.7)
					(thickness 0.15)
				)
				(justify left bottom mirror)
			)
		)
		(fp_text user "Author: Antmicro"
			(at -0.939 -3.399 180)
			(layer "B.Fab")
			(effects
				(font
					(size 0.7 0.7)
					(thickness 0.15)
				)
				(justify left bottom mirror)
			)
		)
		(pad "1" smd roundrect
			(at -0.48 0)
			(size 0.59 0.64)
			(layers "B.Cu" "B.Mask" "B.Paste")
			(roundrect_rratio 0.25)
			(net 417 "GND")
			(pintype "passive")
		)
		(pad "2" smd roundrect
			(at 0.48 0)
			(size 0.59 0.64)
			(layers "B.Cu" "B.Mask" "B.Paste")
			(roundrect_rratio 0.25)
			(net 418 "+2V5")
			(pintype "passive")
		)
	)
	(footprint "antmicro-footprints:C_0402_1005Metric"
		(layer "B.Cu")
		(at 182.884 125.8)
		(descr "Capacitor SMD 0402")
		(tags "capacitor SMD 0402")
		(property "Reference" "C143"
			(at -0.766 1.708 0)
			(layer "B.SilkS")
			(effects
				(font
					(size 0.7 0.7)
					(thickness 0.15)
				)
				(justify right bottom mirror)
			)
		)
		(property "Value" "C_1u_0402"
			(at -1.022927 -2.155213 0)
			(layer "B.Fab")
			(hide yes)
			(effects
				(font
					(size 0.7 0.7)
					(thickness 0.15)
				)
				(justify right bottom mirror)
			)
		)
		(property "Datasheet" "https://product.tdk.com/en/search/capacitor/ceramic/mlcc/info?part_no=C1005X6S1A105K050BC"
			(at 0 0 0)
			(layer "F.Fab")
			(hide yes)
			(effects
				(font
					(size 1.27 1.27)
					(thickness 0.15)
				)
			)
		)
		(property "Description" "SMD Multilayer Ceramic Capacitor, 1 µF, 10 V, 0402 [1005 Metric], ± 10%, X6S, C"
			(at 0 0 0)
			(layer "F.Fab")
			(hide yes)
			(effects
				(font
					(size 1.27 1.27)
					(thickness 0.15)
				)
			)
		)
		(property "Author" "Antmicro"
			(at 0 0 0)
			(layer "B.Fab")
			(hide yes)
			(effects
				(font
					(size 1 1)
					(thickness 0.15)
				)
				(justify mirror)
			)
		)
		(property "Dielectric" "X5R"
			(at 0 0 0)
			(layer "B.Fab")
			(hide yes)
			(effects
				(font
					(size 1 1)
					(thickness 0.15)
				)
				(justify mirror)
			)
		)
		(property "License" "Apache-2.0"
			(at 0 0 0)
			(layer "B.Fab")
			(hide yes)
			(effects
				(font
					(size 1 1)
					(thickness 0.15)
				)
				(justify mirror)
			)
		)
		(property "MPN" "C1005X6S1A105K050BC"
			(at 0 0 0)
			(layer "B.Fab")
			(hide yes)
			(effects
				(font
					(size 1 1)
					(thickness 0.15)
				)
				(justify mirror)
			)
		)
		(property "Manufacturer" "TDK"
			(at 0 0 0)
			(layer "B.Fab")
			(hide yes)
			(effects
				(font
					(size 1 1)
					(thickness 0.15)
				)
				(justify mirror)
			)
		)
		(property "Public" ""
			(at 0 0 0)
			(layer "B.Fab")
			(hide yes)
			(effects
				(font
					(size 1 1)
					(thickness 0.15)
				)
				(justify mirror)
			)
		)
		(property "Val" "1u"
			(at 0 0 0)
			(layer "B.Fab")
			(hide yes)
			(effects
				(font
					(size 1 1)
					(thickness 0.15)
				)
				(justify mirror)
			)
		)
		(property "Voltage" "16V"
			(at 0 0 0)
			(layer "B.Fab")
			(hide yes)
			(effects
				(font
					(size 1 1)
					(thickness 0.15)
				)
				(justify mirror)
			)
		)
		(sheetname "/LPDDR4/")
		(sheetfile "lpddr.kicad_sch")
		(attr smd)
		(fp_rect
			(start -0.925 0.47)
			(end 0.925 -0.47)
			(stroke
				(width 0.05)
				(type default)
			)
			(fill no)
			(layer "B.CrtYd")
		)
		(fp_line
			(start -0.494 -0.248)
			(end -0.494 0.25)
			(stroke
				(width 0.15)
				(type solid)
			)
			(layer "B.Fab")
		)
		(fp_line
			(start -0.494 0.25)
			(end 0.504 0.25)
			(stroke
				(width 0.15)
				(type solid)
			)
			(layer "B.Fab")
		)
		(fp_line
			(start 0.504 -0.248)
			(end -0.494 -0.248)
			(stroke
				(width 0.15)
				(type solid)
			)
			(layer "B.Fab")
		)
		(fp_line
			(start 0.504 0.25)
			(end 0.504 -0.248)
			(stroke
				(width 0.15)
				(type solid)
			)
			(layer "B.Fab")
		)
		(fp_text user "License: Apache-2.0"
			(at -0.939 -5.799 180)
			(layer "B.Fab")
			(effects
				(font
					(size 0.7 0.7)
					(thickness 0.15)
				)
				(justify left bottom mirror)
			)
		)
		(fp_text user "${REFERENCE}"
			(at -0.939 -4.599 180)
			(layer "B.Fab")
			(effects
				(font
					(size 0.7 0.7)
					(thickness 0.15)
				)
				(justify left bottom mirror)
			)
		)
		(fp_text user "Author: Antmicro"
			(at -0.939 -3.399 180)
			(layer "B.Fab")
			(effects
				(font
					(size 0.7 0.7)
					(thickness 0.15)
				)
				(justify left bottom mirror)
			)
		)
		(pad "1" smd roundrect
			(at -0.48 0)
			(size 0.59 0.64)
			(layers "B.Cu" "B.Mask" "B.Paste")
			(roundrect_rratio 0.25)
			(net 417 "GND")
			(pintype "passive")
		)
		(pad "2" smd roundrect
			(at 0.48 0)
			(size 0.59 0.64)
			(layers "B.Cu" "B.Mask" "B.Paste")
			(roundrect_rratio 0.25)
			(net 2 "+1V1")
			(pintype "passive")
		)
	)
	(footprint "antmicro-footprints:R_0402_1005Metric"
		(layer "B.Cu")
		(at 225.5875 146.32)
		(descr "Resistor SMD 0402")
		(tags "resistor SMD 0402")
		(property "Reference" "R153"
			(at 3.8625 0.48 180)
			(layer "B.SilkS")
			(effects
				(font
					(size 0.7 0.7)
					(thickness 0.15)
				)
				(justify left bottom mirror)
			)
		)
		(property "Value" "R_4k75_0.5%_0402"
			(at -1.011843 -1.772047 180)
			(layer "B.Fab")
			(hide yes)
			(effects
				(font
					(size 0.7 0.7)
					(thickness 0.15)
				)
				(justify left bottom mirror)
			)
		)
		(property "Datasheet" "https://industrial.panasonic.com/cdbs/www-data/pdf/RDQ0000/ast-ind-151033.pdf"
			(at 0 0 0)
			(layer "F.Fab")
			(hide yes)
			(effects
				(font
					(size 1.27 1.27)
					(thickness 0.15)
				)
			)
		)
		(property "Description" "SMD Chip Resistor, 4.75 kohm, ± 0.5%, 100 mW, 0402 [1005 Metric], Thick Film, High Temperature"
			(at 0 0 0)
			(layer "F.Fab")
			(hide yes)
			(effects
				(font
					(size 1.27 1.27)
					(thickness 0.15)
				)
			)
		)
		(property "Author" "Antmicro"
			(at 0 0 0)
			(layer "B.Fab")
			(hide yes)
			(effects
				(font
					(size 1 1)
					(thickness 0.15)
				)
				(justify mirror)
			)
		)
		(property "License" "Apache-2.0"
			(at 0 0 0)
			(layer "B.Fab")
			(hide yes)
			(effects
				(font
					(size 1 1)
					(thickness 0.15)
				)
				(justify mirror)
			)
		)
		(property "MPN" "ERJ-H2RD4751X"
			(at 0 0 0)
			(layer "B.Fab")
			(hide yes)
			(effects
				(font
					(size 1 1)
					(thickness 0.15)
				)
				(justify mirror)
			)
		)
		(property "Manufacturer" "Panasonic"
			(at 0 0 0)
			(layer "B.Fab")
			(hide yes)
			(effects
				(font
					(size 1 1)
					(thickness 0.15)
				)
				(justify mirror)
			)
		)
		(property "Public" ""
			(at 0 0 0)
			(layer "B.Fab")
			(hide yes)
			(effects
				(font
					(size 1 1)
					(thickness 0.15)
				)
				(justify mirror)
			)
		)
		(property "Tolerance" "0.5%"
			(at 0 0 0)
			(layer "B.Fab")
			(hide yes)
			(effects
				(font
					(size 1 1)
					(thickness 0.15)
				)
				(justify mirror)
			)
		)
		(property "Val" "4k75"
			(at 0 0 0)
			(layer "B.Fab")
			(hide yes)
			(effects
				(font
					(size 1 1)
					(thickness 0.15)
				)
				(justify mirror)
			)
		)
		(sheetname "/WiFi_Bluetooth/")
		(sheetfile "wifi_bt.kicad_sch")
		(attr smd)
		(fp_rect
			(start -0.925 0.47)
			(end 0.925 -0.47)
			(stroke
				(width 0.05)
				(type default)
			)
			(fill no)
			(layer "B.CrtYd")
		)
		(fp_rect
			(start -0.5 0.25)
			(end 0.5 -0.25)
			(stroke
				(width 0.15)
				(type solid)
			)
			(fill no)
			(layer "B.Fab")
		)
		(fp_text user "${REFERENCE}"
			(at -0.95 -3.168 180)
			(layer "B.Fab")
			(effects
				(font
					(size 0.7 0.7)
					(thickness 0.15)
				)
				(justify left bottom mirror)
			)
		)
		(fp_text user "License: Apache-2.0"
			(at -0.95 -5.169 180)
			(layer "B.Fab")
			(effects
				(font
					(size 0.7 0.7)
					(thickness 0.15)
				)
				(justify left bottom mirror)
			)
		)
		(fp_text user "Author: Antmicro"
			(at -0.95 -4.169 180)
			(layer "B.Fab")
			(effects
				(font
					(size 0.7 0.7)
					(thickness 0.15)
				)
				(justify left bottom mirror)
			)
		)
		(pad "1" smd roundrect
			(at -0.48 0)
			(size 0.59 0.64)
			(layers "B.Cu" "B.Mask" "B.Paste")
			(roundrect_rratio 0.25)
			(net 281 "Net-(U26A-USB2_RREF)")
			(pintype "passive")
		)
		(pad "2" smd roundrect
			(at 0.48 0)
			(size 0.59 0.64)
			(layers "B.Cu" "B.Mask" "B.Paste")
			(roundrect_rratio 0.25)
			(net 417 "GND")
			(pintype "passive")
		)
	)
	(footprint "antmicro-footprints:R_0603_1608Metric"
		(layer "B.Cu")
		(at 199.114212 146.469061 -45)
		(descr "Resistor SMD 0603")
		(tags "resistor SMD 0603")
		(property "Reference" "R62"
			(at 0.117894 1.552206 315)
			(layer "B.SilkS")
			(effects
				(font
					(size 0.7 0.7)
					(thickness 0.15)
				)
				(justify left bottom mirror)
			)
		)
		(property "Value" "R_0R_22.4A_0603"
			(at 0 -1.6 135)
			(layer "B.Fab")
			(hide yes)
			(effects
				(font
					(size 0.7 0.7)
					(thickness 0.15)
				)
				(justify left bottom mirror)
			)
		)
		(property "Datasheet" "https://fscdn.rohm.com/en/products/databook/datasheet/passive/resistor/chip_resistor/pmr-jpw-e.pdf"
			(at 0 0 315)
			(layer "F.Fab")
			(hide yes)
			(effects
				(font
					(size 1.27 1.27)
					(thickness 0.15)
				)
			)
		)
		(property "Description" "SMD Chip Resistor"
			(at 0 0 315)
			(layer "F.Fab")
			(hide yes)
			(effects
				(font
					(size 1.27 1.27)
					(thickness 0.15)
				)
			)
		)
		(property "Author" "Antmicro"
			(at -45.250064 183.694805 0)
			(layer "B.Fab")
			(hide yes)
			(effects
				(font
					(size 1 1)
					(thickness 0.15)
				)
				(justify mirror)
			)
		)
		(property "DNP" "DNP"
			(at -45.250064 183.694805 0)
			(layer "B.Fab")
			(hide yes)
			(effects
				(font
					(size 1 1)
					(thickness 0.15)
				)
				(justify mirror)
			)
		)
		(property "License" "Apache-2.0"
			(at -45.250064 183.694805 0)
			(layer "B.Fab")
			(hide yes)
			(effects
				(font
					(size 1 1)
					(thickness 0.15)
				)
				(justify mirror)
			)
		)
		(property "MPN" "PMR03EZPJ000"
			(at -45.250064 183.694805 0)
			(layer "B.Fab")
			(hide yes)
			(effects
				(font
					(size 1 1)
					(thickness 0.15)
				)
				(justify mirror)
			)
		)
		(property "Manufacturer" "ROHM Semiconductor"
			(at -45.250064 183.694805 0)
			(layer "B.Fab")
			(hide yes)
			(effects
				(font
					(size 1 1)
					(thickness 0.15)
				)
				(justify mirror)
			)
		)
		(property "Max. Curr." "22.4A"
			(at -45.250064 183.694805 0)
			(layer "B.Fab")
			(hide yes)
			(effects
				(font
					(size 1 1)
					(thickness 0.15)
				)
				(justify mirror)
			)
		)
		(property "Public" ""
			(at -45.250064 183.694805 0)
			(layer "B.Fab")
			(hide yes)
			(effects
				(font
					(size 1 1)
					(thickness 0.15)
				)
				(justify mirror)
			)
		)
		(property "Tolerance" "template_tolerance"
			(at -45.250064 183.694805 0)
			(layer "B.Fab")
			(hide yes)
			(effects
				(font
					(size 1 1)
					(thickness 0.15)
				)
				(justify mirror)
			)
		)
		(property "Val" "0R"
			(at -45.250064 183.694805 0)
			(layer "B.Fab")
			(hide yes)
			(effects
				(font
					(size 1 1)
					(thickness 0.15)
				)
				(justify mirror)
			)
		)
		(sheetname "/Bottom Connector/")
		(sheetfile "bottom-connector.kicad_sch")
		(attr smd dnp)
		(fp_line
			(start -0.15 0.4)
			(end 0.15 0.4)
			(stroke
				(width 0.15)
				(type solid)
			)
			(layer "B.SilkS")
		)
		(fp_line
			(start -0.15 -0.4)
			(end 0.15 -0.4)
			(stroke
				(width 0.15)
				(type solid)
			)
			(layer "B.SilkS")
		)
		(fp_poly
			(pts
				(xy -1.25 0.65) (xy 1.25 0.65) (xy 1.25 -0.65) (xy -1.25 -0.65)
			)
			(stroke
				(width 0.05)
				(type solid)
			)
			(fill no)
			(layer "B.CrtYd")
		)
		(fp_poly
			(pts
				(xy -0.8 0.4) (xy 0.8 0.4) (xy 0.8 -0.4) (xy -0.8 -0.4)
			)
			(stroke
				(width 0.15)
				(type solid)
			)
			(fill no)
			(layer "B.Fab")
		)
		(fp_text user "Author: Antmicro"
			(at -1.25 -4.9 135)
			(layer "B.Fab")
			(effects
				(font
					(size 0.7 0.7)
					(thickness 0.15)
				)
				(justify left bottom mirror)
			)
		)
		(fp_text user "License: Apache-2.0"
			(at -1.249999 -5.9 135)
			(layer "B.Fab")
			(effects
				(font
					(size 0.7 0.7)
					(thickness 0.15)
				)
				(justify left bottom mirror)
			)
		)
		(fp_text user "${REFERENCE}"
			(at -1.25 -3.898 135)
			(layer "B.Fab")
			(effects
				(font
					(size 0.7 0.7)
					(thickness 0.15)
				)
				(justify left bottom mirror)
			)
		)
		(pad "1" smd roundrect
			(at -0.7 0 315)
			(size 0.8 1)
			(layers "B.Cu" "B.Mask" "B.Paste")
			(roundrect_rratio 0.2)
			(net 90 "+5V")
			(pintype "passive")
		)
		(pad "2" smd roundrect
			(at 0.7 0 315)
			(size 0.8 1)
			(layers "B.Cu" "B.Mask" "B.Paste")
			(roundrect_rratio 0.2)
			(net 410 "Net-(Q3-D)")
			(pintype "passive")
		)
	)
	(footprint "antmicro-footprints:C_0402_1005Metric"
		(layer "B.Cu")
		(at 184.4 129.25)
		(descr "Capacitor SMD 0402")
		(tags "capacitor SMD 0402")
		(property "Reference" "C148"
			(at -3.75 0.3 0)
			(layer "B.SilkS")
			(effects
				(font
					(size 0.7 0.7)
					(thickness 0.15)
				)
				(justify right bottom mirror)
			)
		)
		(property "Value" "C_1u_0402"
			(at -1.022927 -2.155213 0)
			(layer "B.Fab")
			(hide yes)
			(effects
				(font
					(size 0.7 0.7)
					(thickness 0.15)
				)
				(justify right bottom mirror)
			)
		)
		(property "Datasheet" "https://product.tdk.com/en/search/capacitor/ceramic/mlcc/info?part_no=C1005X6S1A105K050BC"
			(at 0 0 0)
			(layer "F.Fab")
			(hide yes)
			(effects
				(font
					(size 1.27 1.27)
					(thickness 0.15)
				)
			)
		)
		(property "Description" "SMD Multilayer Ceramic Capacitor, 1 µF, 10 V, 0402 [1005 Metric], ± 10%, X6S, C"
			(at 0 0 0)
			(layer "F.Fab")
			(hide yes)
			(effects
				(font
					(size 1.27 1.27)
					(thickness 0.15)
				)
			)
		)
		(property "Author" "Antmicro"
			(at 0 0 0)
			(layer "B.Fab")
			(hide yes)
			(effects
				(font
					(size 1 1)
					(thickness 0.15)
				)
				(justify mirror)
			)
		)
		(property "Dielectric" "X5R"
			(at 0 0 0)
			(layer "B.Fab")
			(hide yes)
			(effects
				(font
					(size 1 1)
					(thickness 0.15)
				)
				(justify mirror)
			)
		)
		(property "License" "Apache-2.0"
			(at 0 0 0)
			(layer "B.Fab")
			(hide yes)
			(effects
				(font
					(size 1 1)
					(thickness 0.15)
				)
				(justify mirror)
			)
		)
		(property "MPN" "C1005X6S1A105K050BC"
			(at 0 0 0)
			(layer "B.Fab")
			(hide yes)
			(effects
				(font
					(size 1 1)
					(thickness 0.15)
				)
				(justify mirror)
			)
		)
		(property "Manufacturer" "TDK"
			(at 0 0 0)
			(layer "B.Fab")
			(hide yes)
			(effects
				(font
					(size 1 1)
					(thickness 0.15)
				)
				(justify mirror)
			)
		)
		(property "Public" ""
			(at 0 0 0)
			(layer "B.Fab")
			(hide yes)
			(effects
				(font
					(size 1 1)
					(thickness 0.15)
				)
				(justify mirror)
			)
		)
		(property "Val" "1u"
			(at 0 0 0)
			(layer "B.Fab")
			(hide yes)
			(effects
				(font
					(size 1 1)
					(thickness 0.15)
				)
				(justify mirror)
			)
		)
		(property "Voltage" "16V"
			(at 0 0 0)
			(layer "B.Fab")
			(hide yes)
			(effects
				(font
					(size 1 1)
					(thickness 0.15)
				)
				(justify mirror)
			)
		)
		(sheetname "/LPDDR4/")
		(sheetfile "lpddr.kicad_sch")
		(attr smd)
		(fp_rect
			(start -0.925 0.47)
			(end 0.925 -0.47)
			(stroke
				(width 0.05)
				(type default)
			)
			(fill no)
			(layer "B.CrtYd")
		)
		(fp_line
			(start -0.494 -0.248)
			(end -0.494 0.25)
			(stroke
				(width 0.15)
				(type solid)
			)
			(layer "B.Fab")
		)
		(fp_line
			(start -0.494 0.25)
			(end 0.504 0.25)
			(stroke
				(width 0.15)
				(type solid)
			)
			(layer "B.Fab")
		)
		(fp_line
			(start 0.504 -0.248)
			(end -0.494 -0.248)
			(stroke
				(width 0.15)
				(type solid)
			)
			(layer "B.Fab")
		)
		(fp_line
			(start 0.504 0.25)
			(end 0.504 -0.248)
			(stroke
				(width 0.15)
				(type solid)
			)
			(layer "B.Fab")
		)
		(fp_text user "Author: Antmicro"
			(at -0.939 -3.399 180)
			(layer "B.Fab")
			(effects
				(font
					(size 0.7 0.7)
					(thickness 0.15)
				)
				(justify left bottom mirror)
			)
		)
		(fp_text user "${REFERENCE}"
			(at -0.939 -4.599 180)
			(layer "B.Fab")
			(effects
				(font
					(size 0.7 0.7)
					(thickness 0.15)
				)
				(justify left bottom mirror)
			)
		)
		(fp_text user "License: Apache-2.0"
			(at -0.939 -5.799 180)
			(layer "B.Fab")
			(effects
				(font
					(size 0.7 0.7)
					(thickness 0.15)
				)
				(justify left bottom mirror)
			)
		)
		(pad "1" smd roundrect
			(at -0.48 0)
			(size 0.59 0.64)
			(layers "B.Cu" "B.Mask" "B.Paste")
			(roundrect_rratio 0.25)
			(net 417 "GND")
			(pintype "passive")
		)
		(pad "2" smd roundrect
			(at 0.48 0)
			(size 0.59 0.64)
			(layers "B.Cu" "B.Mask" "B.Paste")
			(roundrect_rratio 0.25)
			(net 2 "+1V1")
			(pintype "passive")
		)
	)
	(footprint "antmicro-footprints:C_0402_1005Metric"
		(layer "B.Cu")
		(at 214.1925 132.697)
		(descr "Capacitor SMD 0402")
		(tags "capacitor SMD 0402")
		(property "Reference" "C69"
			(at 0.3875 1.423 0)
			(layer "B.SilkS")
			(effects
				(font
					(size 0.7 0.7)
					(thickness 0.15)
				)
				(justify right bottom mirror)
			)
		)
		(property "Value" "C_10u_0402"
			(at -1.022927 -2.155213 0)
			(layer "B.Fab")
			(hide yes)
			(effects
				(font
					(size 0.7 0.7)
					(thickness 0.15)
				)
				(justify right bottom mirror)
			)
		)
		(property "Datasheet" "https://www.yageo.com/en/Chart/Download/pdf/CC0402MRX5R5BB106"
			(at 0 0 0)
			(layer "F.Fab")
			(hide yes)
			(effects
				(font
					(size 1.27 1.27)
					(thickness 0.15)
				)
			)
		)
		(property "Description" "SMD Multilayer Ceramic Capacitor, 10 µF, 6.3 V, 0402 [1005 Metric], ± 20%, X5R, CC Series"
			(at 0 0 0)
			(layer "F.Fab")
			(hide yes)
			(effects
				(font
					(size 1.27 1.27)
					(thickness 0.15)
				)
			)
		)
		(property "Author" "Antmicro"
			(at 0 0 0)
			(layer "B.Fab")
			(hide yes)
			(effects
				(font
					(size 1 1)
					(thickness 0.15)
				)
				(justify mirror)
			)
		)
		(property "Dielectric" ""
			(at 0 0 0)
			(layer "B.Fab")
			(hide yes)
			(effects
				(font
					(size 1 1)
					(thickness 0.15)
				)
				(justify mirror)
			)
		)
		(property "License" "Apache-2.0"
			(at 0 0 0)
			(layer "B.Fab")
			(hide yes)
			(effects
				(font
					(size 1 1)
					(thickness 0.15)
				)
				(justify mirror)
			)
		)
		(property "MPN" "CC0402MRX5R5BB106"
			(at 0 0 0)
			(layer "B.Fab")
			(hide yes)
			(effects
				(font
					(size 1 1)
					(thickness 0.15)
				)
				(justify mirror)
			)
		)
		(property "Manufacturer" "YAGEO"
			(at 0 0 0)
			(layer "B.Fab")
			(hide yes)
			(effects
				(font
					(size 1 1)
					(thickness 0.15)
				)
				(justify mirror)
			)
		)
		(property "Public" ""
			(at 0 0 0)
			(layer "B.Fab")
			(hide yes)
			(effects
				(font
					(size 1 1)
					(thickness 0.15)
				)
				(justify mirror)
			)
		)
		(property "Val" "10u"
			(at 0 0 0)
			(layer "B.Fab")
			(hide yes)
			(effects
				(font
					(size 1 1)
					(thickness 0.15)
				)
				(justify mirror)
			)
		)
		(property "Voltage" ""
			(at 0 0 0)
			(layer "B.Fab")
			(hide yes)
			(effects
				(font
					(size 1 1)
					(thickness 0.15)
				)
				(justify mirror)
			)
		)
		(sheetname "/Memory/")
		(sheetfile "memory.kicad_sch")
		(attr smd)
		(fp_rect
			(start -0.925 0.47)
			(end 0.925 -0.47)
			(stroke
				(width 0.05)
				(type default)
			)
			(fill no)
			(layer "B.CrtYd")
		)
		(fp_line
			(start -0.494 -0.248)
			(end -0.494 0.25)
			(stroke
				(width 0.15)
				(type solid)
			)
			(layer "B.Fab")
		)
		(fp_line
			(start -0.494 0.25)
			(end 0.504 0.25)
			(stroke
				(width 0.15)
				(type solid)
			)
			(layer "B.Fab")
		)
		(fp_line
			(start 0.504 -0.248)
			(end -0.494 -0.248)
			(stroke
				(width 0.15)
				(type solid)
			)
			(layer "B.Fab")
		)
		(fp_line
			(start 0.504 0.25)
			(end 0.504 -0.248)
			(stroke
				(width 0.15)
				(type solid)
			)
			(layer "B.Fab")
		)
		(fp_text user "License: Apache-2.0"
			(at -0.939 -5.799 180)
			(layer "B.Fab")
			(effects
				(font
					(size 0.7 0.7)
					(thickness 0.15)
				)
				(justify left bottom mirror)
			)
		)
		(fp_text user "${REFERENCE}"
			(at -0.939 -4.599 180)
			(layer "B.Fab")
			(effects
				(font
					(size 0.7 0.7)
					(thickness 0.15)
				)
				(justify left bottom mirror)
			)
		)
		(fp_text user "Author: Antmicro"
			(at -0.939 -3.399 180)
			(layer "B.Fab")
			(effects
				(font
					(size 0.7 0.7)
					(thickness 0.15)
				)
				(justify left bottom mirror)
			)
		)
		(pad "1" smd roundrect
			(at -0.48 0)
			(size 0.59 0.64)
			(layers "B.Cu" "B.Mask" "B.Paste")
			(roundrect_rratio 0.25)
			(net 417 "GND")
			(pintype "passive")
		)
		(pad "2" smd roundrect
			(at 0.48 0)
			(size 0.59 0.64)
			(layers "B.Cu" "B.Mask" "B.Paste")
			(roundrect_rratio 0.25)
			(net 50 "+3V3")
			(pintype "passive")
		)
	)
	(footprint "antmicro-footprints:R_0402_1005Metric"
		(layer "B.Cu")
		(at 221.7175 144.895 90)
		(descr "Resistor SMD 0402")
		(tags "resistor SMD 0402")
		(property "Reference" "R144"
			(at 9.93 7.3275 270)
			(layer "B.SilkS")
			(effects
				(font
					(size 0.7 0.7)
					(thickness 0.15)
				)
				(justify left bottom mirror)
			)
		)
		(property "Value" "R_10k_0402"
			(at -1.011843 -1.772047 270)
			(layer "B.Fab")
			(hide yes)
			(effects
				(font
					(size 0.7 0.7)
					(thickness 0.15)
				)
				(justify left bottom mirror)
			)
		)
		(property "Datasheet" "https://www.bourns.com/docs/product-datasheets/cr.pdf"
			(at 0 0 90)
			(layer "F.Fab")
			(hide yes)
			(effects
				(font
					(size 1.27 1.27)
					(thickness 0.15)
				)
			)
		)
		(property "Description" "SMD Chip Resistor, 10 kohm, ± 1%, 62.5 mW, 0402 [1005 Metric], Thick Film, General Purpose"
			(at 0 0 90)
			(layer "F.Fab")
			(hide yes)
			(effects
				(font
					(size 1.27 1.27)
					(thickness 0.15)
				)
			)
		)
		(property "Author" "Antmicro"
			(at 366.6125 -76.8225 0)
			(layer "B.Fab")
			(hide yes)
			(effects
				(font
					(size 1 1)
					(thickness 0.15)
				)
				(justify mirror)
			)
		)
		(property "License" "Apache-2.0"
			(at 366.6125 -76.8225 0)
			(layer "B.Fab")
			(hide yes)
			(effects
				(font
					(size 1 1)
					(thickness 0.15)
				)
				(justify mirror)
			)
		)
		(property "MPN" "CR0402-FX-1002GLF"
			(at 366.6125 -76.8225 0)
			(layer "B.Fab")
			(hide yes)
			(effects
				(font
					(size 1 1)
					(thickness 0.15)
				)
				(justify mirror)
			)
		)
		(property "Manufacturer" "Bourns"
			(at 366.6125 -76.8225 0)
			(layer "B.Fab")
			(hide yes)
			(effects
				(font
					(size 1 1)
					(thickness 0.15)
				)
				(justify mirror)
			)
		)
		(property "Public" ""
			(at 366.6125 -76.8225 0)
			(layer "B.Fab")
			(hide yes)
			(effects
				(font
					(size 1 1)
					(thickness 0.15)
				)
				(justify mirror)
			)
		)
		(property "Tolerance" "1%"
			(at 366.6125 -76.8225 0)
			(layer "B.Fab")
			(hide yes)
			(effects
				(font
					(size 1 1)
					(thickness 0.15)
				)
				(justify mirror)
			)
		)
		(property "Val" "10k"
			(at 366.6125 -76.8225 0)
			(layer "B.Fab")
			(hide yes)
			(effects
				(font
					(size 1 1)
					(thickness 0.15)
				)
				(justify mirror)
			)
		)
		(sheetname "/WiFi_Bluetooth/")
		(sheetfile "wifi_bt.kicad_sch")
		(attr smd)
		(fp_rect
			(start -0.925 0.47)
			(end 0.925 -0.47)
			(stroke
				(width 0.05)
				(type default)
			)
			(fill no)
			(layer "B.CrtYd")
		)
		(fp_rect
			(start -0.5 0.25)
			(end 0.5 -0.25)
			(stroke
				(width 0.15)
				(type solid)
			)
			(fill no)
			(layer "B.Fab")
		)
		(fp_text user "${REFERENCE}"
			(at -0.95 -3.168 270)
			(layer "B.Fab")
			(effects
				(font
					(size 0.7 0.7)
					(thickness 0.15)
				)
				(justify left bottom mirror)
			)
		)
		(fp_text user "Author: Antmicro"
			(at -0.95 -4.169 270)
			(layer "B.Fab")
			(effects
				(font
					(size 0.7 0.7)
					(thickness 0.15)
				)
				(justify left bottom mirror)
			)
		)
		(fp_text user "License: Apache-2.0"
			(at -0.95 -5.169 270)
			(layer "B.Fab")
			(effects
				(font
					(size 0.7 0.7)
					(thickness 0.15)
				)
				(justify left bottom mirror)
			)
		)
		(pad "1" smd roundrect
			(at -0.48 0 90)
			(size 0.59 0.64)
			(layers "B.Cu" "B.Mask" "B.Paste")
			(roundrect_rratio 0.25)
			(net 171 "WL_REG_ON")
			(pintype "passive")
		)
		(pad "2" smd roundrect
			(at 0.48 0 90)
			(size 0.59 0.64)
			(layers "B.Cu" "B.Mask" "B.Paste")
			(roundrect_rratio 0.25)
			(net 50 "+3V3")
			(pintype "passive")
		)
	)
	(footprint "antmicro-footprints:C_0402_1005Metric"
		(layer "B.Cu")
		(at 211.7266 118.37)
		(descr "Capacitor SMD 0402")
		(tags "capacitor SMD 0402")
		(property "Reference" "C260"
			(at -1.7016 -0.42 0)
			(layer "B.SilkS")
			(effects
				(font
					(size 0.7 0.7)
					(thickness 0.15)
				)
				(justify right bottom mirror)
			)
		)
		(property "Value" "C_100n_0402"
			(at -1.022927 -2.155213 0)
			(layer "B.Fab")
			(hide yes)
			(effects
				(font
					(size 0.7 0.7)
					(thickness 0.15)
				)
				(justify right bottom mirror)
			)
		)
		(property "Datasheet" "https://www.murata.com/products/productdetail?partno=GRM155R61H104KE14%23"
			(at 0 0 0)
			(layer "F.Fab")
			(hide yes)
			(effects
				(font
					(size 1.27 1.27)
					(thickness 0.15)
				)
			)
		)
		(property "Description" "SMD Multilayer Ceramic Capacitor, 0.1 µF, 50 V, 0402 [1005 Metric], ± 10%, X5R, GRM Series"
			(at 0 0 0)
			(layer "F.Fab")
			(hide yes)
			(effects
				(font
					(size 1.27 1.27)
					(thickness 0.15)
				)
			)
		)
		(property "Author" "Antmicro"
			(at 0 0 0)
			(layer "B.Fab")
			(hide yes)
			(effects
				(font
					(size 1 1)
					(thickness 0.15)
				)
				(justify mirror)
			)
		)
		(property "Dielectric" "X5R"
			(at 0 0 0)
			(layer "B.Fab")
			(hide yes)
			(effects
				(font
					(size 1 1)
					(thickness 0.15)
				)
				(justify mirror)
			)
		)
		(property "License" "Apache-2.0"
			(at 0 0 0)
			(layer "B.Fab")
			(hide yes)
			(effects
				(font
					(size 1 1)
					(thickness 0.15)
				)
				(justify mirror)
			)
		)
		(property "MPN" "GRM155R61H104KE14D"
			(at 0 0 0)
			(layer "B.Fab")
			(hide yes)
			(effects
				(font
					(size 1 1)
					(thickness 0.15)
				)
				(justify mirror)
			)
		)
		(property "Manufacturer" "Murata"
			(at 0 0 0)
			(layer "B.Fab")
			(hide yes)
			(effects
				(font
					(size 1 1)
					(thickness 0.15)
				)
				(justify mirror)
			)
		)
		(property "Public" ""
			(at 0 0 0)
			(layer "B.Fab")
			(hide yes)
			(effects
				(font
					(size 1 1)
					(thickness 0.15)
				)
				(justify mirror)
			)
		)
		(property "Val" "100n"
			(at 0 0 0)
			(layer "B.Fab")
			(hide yes)
			(effects
				(font
					(size 1 1)
					(thickness 0.15)
				)
				(justify mirror)
			)
		)
		(property "Voltage" "50V"
			(at 0 0 0)
			(layer "B.Fab")
			(hide yes)
			(effects
				(font
					(size 1 1)
					(thickness 0.15)
				)
				(justify mirror)
			)
		)
		(sheetname "/Ethernet/")
		(sheetfile "ethernet.kicad_sch")
		(attr smd)
		(fp_rect
			(start -0.925 0.47)
			(end 0.925 -0.47)
			(stroke
				(width 0.05)
				(type default)
			)
			(fill no)
			(layer "B.CrtYd")
		)
		(fp_line
			(start -0.494 -0.248)
			(end -0.494 0.25)
			(stroke
				(width 0.15)
				(type solid)
			)
			(layer "B.Fab")
		)
		(fp_line
			(start -0.494 0.25)
			(end 0.504 0.25)
			(stroke
				(width 0.15)
				(type solid)
			)
			(layer "B.Fab")
		)
		(fp_line
			(start 0.504 -0.248)
			(end -0.494 -0.248)
			(stroke
				(width 0.15)
				(type solid)
			)
			(layer "B.Fab")
		)
		(fp_line
			(start 0.504 0.25)
			(end 0.504 -0.248)
			(stroke
				(width 0.15)
				(type solid)
			)
			(layer "B.Fab")
		)
		(fp_text user "${REFERENCE}"
			(at -0.939 -4.599 180)
			(layer "B.Fab")
			(effects
				(font
					(size 0.7 0.7)
					(thickness 0.15)
				)
				(justify left bottom mirror)
			)
		)
		(fp_text user "Author: Antmicro"
			(at -0.939 -3.399 180)
			(layer "B.Fab")
			(effects
				(font
					(size 0.7 0.7)
					(thickness 0.15)
				)
				(justify left bottom mirror)
			)
		)
		(fp_text user "License: Apache-2.0"
			(at -0.939 -5.799 180)
			(layer "B.Fab")
			(effects
				(font
					(size 0.7 0.7)
					(thickness 0.15)
				)
				(justify left bottom mirror)
			)
		)
		(pad "1" smd roundrect
			(at -0.48 0)
			(size 0.59 0.64)
			(layers "B.Cu" "B.Mask" "B.Paste")
			(roundrect_rratio 0.25)
			(net 43 "/Ethernet/SGMII.TX0_P")
			(pintype "passive")
		)
		(pad "2" smd roundrect
			(at 0.48 0)
			(size 0.59 0.64)
			(layers "B.Cu" "B.Mask" "B.Paste")
			(roundrect_rratio 0.25)
			(net 164 "/Ethernet/SGMII_SI_P")
			(pintype "passive")
		)
	)
	(footprint "antmicro-footprints:C_0402_1005Metric"
		(layer "B.Cu")
		(at 203.36 145.416 180)
		(descr "Capacitor SMD 0402")
		(tags "capacitor SMD 0402")
		(property "Reference" "C199"
			(at -1.47 0.526 0)
			(layer "B.SilkS")
			(effects
				(font
					(size 0.7 0.7)
					(thickness 0.15)
				)
				(justify left bottom mirror)
			)
		)
		(property "Value" "C_100n_0402"
			(at -1.022927 -2.155213 0)
			(layer "B.Fab")
			(hide yes)
			(effects
				(font
					(size 0.7 0.7)
					(thickness 0.15)
				)
				(justify left bottom mirror)
			)
		)
		(property "Datasheet" "https://www.murata.com/products/productdetail?partno=GRM155R61H104KE14%23"
			(at 0 0 180)
			(layer "F.Fab")
			(hide yes)
			(effects
				(font
					(size 1.27 1.27)
					(thickness 0.15)
				)
			)
		)
		(property "Description" "SMD Multilayer Ceramic Capacitor, 0.1 µF, 50 V, 0402 [1005 Metric], ± 10%, X5R, GRM Series"
			(at 0 0 180)
			(layer "F.Fab")
			(hide yes)
			(effects
				(font
					(size 1.27 1.27)
					(thickness 0.15)
				)
			)
		)
		(property "Author" "Antmicro"
			(at 406.72 290.832 0)
			(layer "B.Fab")
			(hide yes)
			(effects
				(font
					(size 1 1)
					(thickness 0.15)
				)
				(justify mirror)
			)
		)
		(property "Dielectric" "X5R"
			(at 406.72 290.832 0)
			(layer "B.Fab")
			(hide yes)
			(effects
				(font
					(size 1 1)
					(thickness 0.15)
				)
				(justify mirror)
			)
		)
		(property "License" "Apache-2.0"
			(at 406.72 290.832 0)
			(layer "B.Fab")
			(hide yes)
			(effects
				(font
					(size 1 1)
					(thickness 0.15)
				)
				(justify mirror)
			)
		)
		(property "MPN" "GRM155R61H104KE14D"
			(at 406.72 290.832 0)
			(layer "B.Fab")
			(hide yes)
			(effects
				(font
					(size 1 1)
					(thickness 0.15)
				)
				(justify mirror)
			)
		)
		(property "Manufacturer" "Murata"
			(at 406.72 290.832 0)
			(layer "B.Fab")
			(hide yes)
			(effects
				(font
					(size 1 1)
					(thickness 0.15)
				)
				(justify mirror)
			)
		)
		(property "Public" ""
			(at 406.72 290.832 0)
			(layer "B.Fab")
			(hide yes)
			(effects
				(font
					(size 1 1)
					(thickness 0.15)
				)
				(justify mirror)
			)
		)
		(property "Val" "100n"
			(at 406.72 290.832 0)
			(layer "B.Fab")
			(hide yes)
			(effects
				(font
					(size 1 1)
					(thickness 0.15)
				)
				(justify mirror)
			)
		)
		(property "Voltage" "50V"
			(at 406.72 290.832 0)
			(layer "B.Fab")
			(hide yes)
			(effects
				(font
					(size 1 1)
					(thickness 0.15)
				)
				(justify mirror)
			)
		)
		(sheetname "/MIPI CrossLink/")
		(sheetfile "crosslink.kicad_sch")
		(attr smd)
		(fp_rect
			(start -0.925 0.47)
			(end 0.925 -0.47)
			(stroke
				(width 0.05)
				(type default)
			)
			(fill no)
			(layer "B.CrtYd")
		)
		(fp_line
			(start 0.504 0.25)
			(end 0.504 -0.248)
			(stroke
				(width 0.15)
				(type solid)
			)
			(layer "B.Fab")
		)
		(fp_line
			(start 0.504 -0.248)
			(end -0.494 -0.248)
			(stroke
				(width 0.15)
				(type solid)
			)
			(layer "B.Fab")
		)
		(fp_line
			(start -0.494 0.25)
			(end 0.504 0.25)
			(stroke
				(width 0.15)
				(type solid)
			)
			(layer "B.Fab")
		)
		(fp_line
			(start -0.494 -0.248)
			(end -0.494 0.25)
			(stroke
				(width 0.15)
				(type solid)
			)
			(layer "B.Fab")
		)
		(fp_text user "License: Apache-2.0"
			(at -0.939 -5.799 0)
			(layer "B.Fab")
			(effects
				(font
					(size 0.7 0.7)
					(thickness 0.15)
				)
				(justify left bottom mirror)
			)
		)
		(fp_text user "${REFERENCE}"
			(at -0.939 -4.599 0)
			(layer "B.Fab")
			(effects
				(font
					(size 0.7 0.7)
					(thickness 0.15)
				)
				(justify left bottom mirror)
			)
		)
		(fp_text user "Author: Antmicro"
			(at -0.939 -3.399 0)
			(layer "B.Fab")
			(effects
				(font
					(size 0.7 0.7)
					(thickness 0.15)
				)
				(justify left bottom mirror)
			)
		)
		(pad "1" smd roundrect
			(at -0.48 0 180)
			(size 0.59 0.64)
			(layers "B.Cu" "B.Mask" "B.Paste")
			(roundrect_rratio 0.25)
			(net 417 "GND")
			(pintype "passive")
		)
		(pad "2" smd roundrect
			(at 0.48 0 180)
			(size 0.59 0.64)
			(layers "B.Cu" "B.Mask" "B.Paste")
			(roundrect_rratio 0.25)
			(net 180 "/MIPI CrossLink/CL_VCCGPLL")
			(pintype "passive")
		)
	)
	(footprint "antmicro-footprints:R_0402_1005Metric"
		(layer "B.Cu")
		(at 210.1775 135.347)
		(descr "Resistor SMD 0402")
		(tags "resistor SMD 0402")
		(property "Reference" "R29"
			(at 1.6225 3.353 180)
			(layer "B.SilkS")
			(effects
				(font
					(size 0.7 0.7)
					(thickness 0.15)
				)
				(justify left bottom mirror)
			)
		)
		(property "Value" "R_10k_0402"
			(at -1.011843 -1.772047 180)
			(layer "B.Fab")
			(hide yes)
			(effects
				(font
					(size 0.7 0.7)
					(thickness 0.15)
				)
				(justify left bottom mirror)
			)
		)
		(property "Datasheet" "https://www.bourns.com/docs/product-datasheets/cr.pdf"
			(at 0 0 0)
			(layer "F.Fab")
			(hide yes)
			(effects
				(font
					(size 1.27 1.27)
					(thickness 0.15)
				)
			)
		)
		(property "Description" "SMD Chip Resistor, 10 kohm, ± 1%, 62.5 mW, 0402 [1005 Metric], Thick Film, General Purpose"
			(at 0 0 0)
			(layer "F.Fab")
			(hide yes)
			(effects
				(font
					(size 1.27 1.27)
					(thickness 0.15)
				)
			)
		)
		(property "Author" "Antmicro"
			(at 0 0 0)
			(layer "B.Fab")
			(hide yes)
			(effects
				(font
					(size 1 1)
					(thickness 0.15)
				)
				(justify mirror)
			)
		)
		(property "License" "Apache-2.0"
			(at 0 0 0)
			(layer "B.Fab")
			(hide yes)
			(effects
				(font
					(size 1 1)
					(thickness 0.15)
				)
				(justify mirror)
			)
		)
		(property "MPN" "CR0402-FX-1002GLF"
			(at 0 0 0)
			(layer "B.Fab")
			(hide yes)
			(effects
				(font
					(size 1 1)
					(thickness 0.15)
				)
				(justify mirror)
			)
		)
		(property "Manufacturer" "Bourns"
			(at 0 0 0)
			(layer "B.Fab")
			(hide yes)
			(effects
				(font
					(size 1 1)
					(thickness 0.15)
				)
				(justify mirror)
			)
		)
		(property "Public" ""
			(at 0 0 0)
			(layer "B.Fab")
			(hide yes)
			(effects
				(font
					(size 1 1)
					(thickness 0.15)
				)
				(justify mirror)
			)
		)
		(property "Tolerance" "1%"
			(at 0 0 0)
			(layer "B.Fab")
			(hide yes)
			(effects
				(font
					(size 1 1)
					(thickness 0.15)
				)
				(justify mirror)
			)
		)
		(property "Val" "10k"
			(at 0 0 0)
			(layer "B.Fab")
			(hide yes)
			(effects
				(font
					(size 1 1)
					(thickness 0.15)
				)
				(justify mirror)
			)
		)
		(sheetname "/Memory/")
		(sheetfile "memory.kicad_sch")
		(attr smd)
		(fp_rect
			(start -0.925 0.47)
			(end 0.925 -0.47)
			(stroke
				(width 0.05)
				(type default)
			)
			(fill no)
			(layer "B.CrtYd")
		)
		(fp_rect
			(start -0.5 0.25)
			(end 0.5 -0.25)
			(stroke
				(width 0.15)
				(type solid)
			)
			(fill no)
			(layer "B.Fab")
		)
		(fp_text user "${REFERENCE}"
			(at -0.95 -3.168 180)
			(layer "B.Fab")
			(effects
				(font
					(size 0.7 0.7)
					(thickness 0.15)
				)
				(justify left bottom mirror)
			)
		)
		(fp_text user "Author: Antmicro"
			(at -0.95 -4.169 180)
			(layer "B.Fab")
			(effects
				(font
					(size 0.7 0.7)
					(thickness 0.15)
				)
				(justify left bottom mirror)
			)
		)
		(fp_text user "License: Apache-2.0"
			(at -0.95 -5.169 180)
			(layer "B.Fab")
			(effects
				(font
					(size 0.7 0.7)
					(thickness 0.15)
				)
				(justify left bottom mirror)
			)
		)
		(pad "1" smd roundrect
			(at -0.48 0)
			(size 0.59 0.64)
			(layers "B.Cu" "B.Mask" "B.Paste")
			(roundrect_rratio 0.25)
			(net 391 "/FPGA MSSIO/EMMC.CMD")
			(pintype "passive")
		)
		(pad "2" smd roundrect
			(at 0.48 0)
			(size 0.59 0.64)
			(layers "B.Cu" "B.Mask" "B.Paste")
			(roundrect_rratio 0.25)
			(net 137 "SD_VDD")
			(pintype "passive")
		)
	)
	(footprint "antmicro-footprints:R_0402_1005Metric"
		(layer "B.Cu")
		(at 223.4 125.945 -90)
		(descr "Resistor SMD 0402")
		(tags "resistor SMD 0402")
		(property "Reference" "R46"
			(at -1.345 -2.475 90)
			(layer "B.SilkS")
			(effects
				(font
					(size 0.7 0.7)
					(thickness 0.15)
				)
				(justify left bottom mirror)
			)
		)
		(property "Value" "R_10k_0402"
			(at -1.011843 -1.772047 90)
			(layer "B.Fab")
			(hide yes)
			(effects
				(font
					(size 0.7 0.7)
					(thickness 0.15)
				)
				(justify left bottom mirror)
			)
		)
		(property "Datasheet" "https://www.bourns.com/docs/product-datasheets/cr.pdf"
			(at 0 0 270)
			(layer "F.Fab")
			(hide yes)
			(effects
				(font
					(size 1.27 1.27)
					(thickness 0.15)
				)
			)
		)
		(property "Description" "SMD Chip Resistor, 10 kohm, ± 1%, 62.5 mW, 0402 [1005 Metric], Thick Film, General Purpose"
			(at 0 0 270)
			(layer "F.Fab")
			(hide yes)
			(effects
				(font
					(size 1.27 1.27)
					(thickness 0.15)
				)
			)
		)
		(property "Author" "Antmicro"
			(at 97.455 349.345 0)
			(layer "B.Fab")
			(hide yes)
			(effects
				(font
					(size 1 1)
					(thickness 0.15)
				)
				(justify mirror)
			)
		)
		(property "License" "Apache-2.0"
			(at 97.455 349.345 0)
			(layer "B.Fab")
			(hide yes)
			(effects
				(font
					(size 1 1)
					(thickness 0.15)
				)
				(justify mirror)
			)
		)
		(property "MPN" "CR0402-FX-1002GLF"
			(at 97.455 349.345 0)
			(layer "B.Fab")
			(hide yes)
			(effects
				(font
					(size 1 1)
					(thickness 0.15)
				)
				(justify mirror)
			)
		)
		(property "Manufacturer" "Bourns"
			(at 97.455 349.345 0)
			(layer "B.Fab")
			(hide yes)
			(effects
				(font
					(size 1 1)
					(thickness 0.15)
				)
				(justify mirror)
			)
		)
		(property "Public" ""
			(at 97.455 349.345 0)
			(layer "B.Fab")
			(hide yes)
			(effects
				(font
					(size 1 1)
					(thickness 0.15)
				)
				(justify mirror)
			)
		)
		(property "Tolerance" "1%"
			(at 97.455 349.345 0)
			(layer "B.Fab")
			(hide yes)
			(effects
				(font
					(size 1 1)
					(thickness 0.15)
				)
				(justify mirror)
			)
		)
		(property "Val" "10k"
			(at 97.455 349.345 0)
			(layer "B.Fab")
			(hide yes)
			(effects
				(font
					(size 1 1)
					(thickness 0.15)
				)
				(justify mirror)
			)
		)
		(sheetname "/FPGA Config/")
		(sheetfile "fpga-config.kicad_sch")
		(attr smd)
		(fp_rect
			(start -0.925 0.47)
			(end 0.925 -0.47)
			(stroke
				(width 0.05)
				(type default)
			)
			(fill no)
			(layer "B.CrtYd")
		)
		(fp_rect
			(start -0.5 0.25)
			(end 0.5 -0.25)
			(stroke
				(width 0.15)
				(type solid)
			)
			(fill no)
			(layer "B.Fab")
		)
		(fp_text user "Author: Antmicro"
			(at -0.95 -4.169 90)
			(layer "B.Fab")
			(effects
				(font
					(size 0.7 0.7)
					(thickness 0.15)
				)
				(justify left bottom mirror)
			)
		)
		(fp_text user "${REFERENCE}"
			(at -0.95 -3.168 90)
			(layer "B.Fab")
			(effects
				(font
					(size 0.7 0.7)
					(thickness 0.15)
				)
				(justify left bottom mirror)
			)
		)
		(fp_text user "License: Apache-2.0"
			(at -0.95 -5.169 90)
			(layer "B.Fab")
			(effects
				(font
					(size 0.7 0.7)
					(thickness 0.15)
				)
				(justify left bottom mirror)
			)
		)
		(pad "1" smd roundrect
			(at -0.48 0 270)
			(size 0.59 0.64)
			(layers "B.Cu" "B.Mask" "B.Paste")
			(roundrect_rratio 0.25)
			(net 259 "Net-(U3-HOLD#{slash}DQ3)")
			(pintype "passive")
		)
		(pad "2" smd roundrect
			(at 0.48 0 270)
			(size 0.59 0.64)
			(layers "B.Cu" "B.Mask" "B.Paste")
			(roundrect_rratio 0.25)
			(net 50 "+3V3")
			(pintype "passive")
		)
	)
	(footprint "antmicro-footprints:C_0402_1005Metric"
		(layer "B.Cu")
		(at 197.299 124.784 -90)
		(descr "Capacitor SMD 0402")
		(tags "capacitor SMD 0402")
		(property "Reference" "C22"
			(at 0.741 0.924 135)
			(layer "B.SilkS")
			(effects
				(font
					(size 0.7 0.7)
					(thickness 0.15)
				)
				(justify left bottom mirror)
			)
		)
		(property "Value" "C_10u_0402"
			(at -1.022927 -2.155213 90)
			(layer "B.Fab")
			(hide yes)
			(effects
				(font
					(size 0.7 0.7)
					(thickness 0.15)
				)
				(justify left bottom mirror)
			)
		)
		(property "Datasheet" "https://www.yageo.com/en/Chart/Download/pdf/CC0402MRX5R5BB106"
			(at 0 0 270)
			(layer "F.Fab")
			(hide yes)
			(effects
				(font
					(size 1.27 1.27)
					(thickness 0.15)
				)
			)
		)
		(property "Description" "SMD Multilayer Ceramic Capacitor, 10 µF, 6.3 V, 0402 [1005 Metric], ± 20%, X5R, CC Series"
			(at 0 0 270)
			(layer "F.Fab")
			(hide yes)
			(effects
				(font
					(size 1.27 1.27)
					(thickness 0.15)
				)
			)
		)
		(property "Author" "Antmicro"
			(at 72.515 322.083 0)
			(layer "B.Fab")
			(hide yes)
			(effects
				(font
					(size 1 1)
					(thickness 0.15)
				)
				(justify mirror)
			)
		)
		(property "Dielectric" ""
			(at 72.515 322.083 0)
			(layer "B.Fab")
			(hide yes)
			(effects
				(font
					(size 1 1)
					(thickness 0.15)
				)
				(justify mirror)
			)
		)
		(property "License" "Apache-2.0"
			(at 72.515 322.083 0)
			(layer "B.Fab")
			(hide yes)
			(effects
				(font
					(size 1 1)
					(thickness 0.15)
				)
				(justify mirror)
			)
		)
		(property "MPN" "CC0402MRX5R5BB106"
			(at 72.515 322.083 0)
			(layer "B.Fab")
			(hide yes)
			(effects
				(font
					(size 1 1)
					(thickness 0.15)
				)
				(justify mirror)
			)
		)
		(property "Manufacturer" "YAGEO"
			(at 72.515 322.083 0)
			(layer "B.Fab")
			(hide yes)
			(effects
				(font
					(size 1 1)
					(thickness 0.15)
				)
				(justify mirror)
			)
		)
		(property "Public" ""
			(at 72.515 322.083 0)
			(layer "B.Fab")
			(hide yes)
			(effects
				(font
					(size 1 1)
					(thickness 0.15)
				)
				(justify mirror)
			)
		)
		(property "Val" "10u"
			(at 72.515 322.083 0)
			(layer "B.Fab")
			(hide yes)
			(effects
				(font
					(size 1 1)
					(thickness 0.15)
				)
				(justify mirror)
			)
		)
		(property "Voltage" ""
			(at 72.515 322.083 0)
			(layer "B.Fab")
			(hide yes)
			(effects
				(font
					(size 1 1)
					(thickness 0.15)
				)
				(justify mirror)
			)
		)
		(sheetname "/FPGA Supply/")
		(sheetfile "fpga-supply.kicad_sch")
		(attr smd)
		(fp_rect
			(start -0.925 0.47)
			(end 0.925 -0.47)
			(stroke
				(width 0.05)
				(type default)
			)
			(fill no)
			(layer "B.CrtYd")
		)
		(fp_line
			(start -0.494 0.25)
			(end 0.504 0.25)
			(stroke
				(width 0.15)
				(type solid)
			)
			(layer "B.Fab")
		)
		(fp_line
			(start 0.504 0.25)
			(end 0.504 -0.248)
			(stroke
				(width 0.15)
				(type solid)
			)
			(layer "B.Fab")
		)
		(fp_line
			(start -0.494 -0.248)
			(end -0.494 0.25)
			(stroke
				(width 0.15)
				(type solid)
			)
			(layer "B.Fab")
		)
		(fp_line
			(start 0.504 -0.248)
			(end -0.494 -0.248)
			(stroke
				(width 0.15)
				(type solid)
			)
			(layer "B.Fab")
		)
		(fp_text user "${REFERENCE}"
			(at -0.939 -4.599 90)
			(layer "B.Fab")
			(effects
				(font
					(size 0.7 0.7)
					(thickness 0.15)
				)
				(justify left bottom mirror)
			)
		)
		(fp_text user "Author: Antmicro"
			(at -0.939 -3.399 90)
			(layer "B.Fab")
			(effects
				(font
					(size 0.7 0.7)
					(thickness 0.15)
				)
				(justify left bottom mirror)
			)
		)
		(fp_text user "License: Apache-2.0"
			(at -0.939 -5.799 90)
			(layer "B.Fab")
			(effects
				(font
					(size 0.7 0.7)
					(thickness 0.15)
				)
				(justify left bottom mirror)
			)
		)
		(pad "1" smd roundrect
			(at -0.48 0 270)
			(size 0.59 0.64)
			(layers "B.Cu" "B.Mask" "B.Paste")
			(roundrect_rratio 0.25)
			(net 417 "GND")
			(pintype "passive")
		)
		(pad "2" smd roundrect
			(at 0.48 0 270)
			(size 0.59 0.64)
			(layers "B.Cu" "B.Mask" "B.Paste")
			(roundrect_rratio 0.25)
			(net 137 "SD_VDD")
			(pintype "passive")
		)
	)
	(footprint "antmicro-footprints:XSON-8_1x1.95mm_P0.5mm"
		(layer "B.Cu")
		(at 223.51 144.71 180)
		(property "Reference" "U30"
			(at -5.32 3.13 0)
			(layer "B.SilkS")
			(effects
				(font
					(size 0.7 0.7)
					(thickness 0.15)
				)
				(justify left bottom mirror)
			)
		)
		(property "Value" "NTS0102_XSON"
			(at 0 -2.2 0)
			(layer "B.Fab")
			(hide yes)
			(effects
				(font
					(size 0.7 0.7)
					(thickness 0.15)
				)
				(justify left bottom mirror)
			)
		)
		(property "Datasheet" "http://www.farnell.com/datasheets/1760723.pdf"
			(at 0 0 180)
			(layer "F.Fab")
			(hide yes)
			(effects
				(font
					(size 1.27 1.27)
					(thickness 0.15)
				)
			)
		)
		(property "Description" "Transceiver, 1.65 V to 3.6 V, XSON-8"
			(at 0 0 180)
			(layer "F.Fab")
			(hide yes)
			(effects
				(font
					(size 1.27 1.27)
					(thickness 0.15)
				)
			)
		)
		(property "Author" "Antmicro"
			(at 447.02 289.42 0)
			(layer "B.Fab")
			(hide yes)
			(effects
				(font
					(size 1 1)
					(thickness 0.15)
				)
				(justify mirror)
			)
		)
		(property "License" "Apache-2.0"
			(at 447.02 289.42 0)
			(layer "B.Fab")
			(hide yes)
			(effects
				(font
					(size 1 1)
					(thickness 0.15)
				)
				(justify mirror)
			)
		)
		(property "MPN" "NTS0102GT"
			(at 447.02 289.42 0)
			(layer "B.Fab")
			(hide yes)
			(effects
				(font
					(size 1 1)
					(thickness 0.15)
				)
				(justify mirror)
			)
		)
		(property "Manufacturer" "NXP"
			(at 447.02 289.42 0)
			(layer "B.Fab")
			(hide yes)
			(effects
				(font
					(size 1 1)
					(thickness 0.15)
				)
				(justify mirror)
			)
		)
		(sheetname "/FPGA MSSIO/")
		(sheetfile "fpga-mssio.kicad_sch")
		(attr smd)
		(fp_line
			(start 0.5 -1.1)
			(end -0.5 -1.1)
			(stroke
				(width 0.15)
				(type solid)
			)
			(layer "B.SilkS")
		)
		(fp_line
			(start -0.5 1.1)
			(end 0.5 1.1)
			(stroke
				(width 0.15)
				(type solid)
			)
			(layer "B.SilkS")
		)
		(fp_circle
			(center -0.75 1.1)
			(end -0.701 1.1)
			(stroke
				(width 0.15)
				(type solid)
			)
			(fill no)
			(layer "B.SilkS")
		)
		(fp_rect
			(start -0.8 1.2)
			(end 0.8 -1.2)
			(stroke
				(width 0.05)
				(type solid)
			)
			(fill no)
			(layer "B.CrtYd")
		)
		(fp_line
			(start 0.5305 1.001)
			(end 0.5305 -1)
			(stroke
				(width 0.15)
				(type solid)
			)
			(layer "B.Fab")
		)
		(fp_line
			(start 0.5305 -1)
			(end -0.5305 -1)
			(stroke
				(width 0.15)
				(type solid)
			)
			(layer "B.Fab")
		)
		(fp_line
			(start -0.5305 1.001)
			(end 0.5305 1.001)
			(stroke
				(width 0.15)
				(type solid)
			)
			(layer "B.Fab")
		)
		(fp_line
			(start -0.5305 -1)
			(end -0.5305 1.001)
			(stroke
				(width 0.15)
				(type solid)
			)
			(layer "B.Fab")
		)
		(fp_text user "${REFERENCE}"
			(at -0.527 -5.905 0)
			(layer "B.Fab")
			(effects
				(font
					(size 0.7 0.7)
					(thickness 0.15)
				)
				(justify left bottom mirror)
			)
		)
		(fp_text user "License: Apache-2.0"
			(at -0.527 -8.306 0)
			(layer "B.Fab")
			(effects
				(font
					(size 0.7 0.7)
					(thickness 0.15)
				)
				(justify left bottom mirror)
			)
		)
		(fp_text user "Author: Antmicro"
			(at -0.527 -7.105 0)
			(layer "B.Fab")
			(effects
				(font
					(size 0.7 0.7)
					(thickness 0.15)
				)
				(justify left bottom mirror)
			)
		)
		(pad "1" smd roundrect
			(at -0.45 0.75)
			(size 0.6 0.3)
			(layers "B.Cu" "B.Mask" "B.Paste")
			(roundrect_rratio 0.25)
			(net 117 "/FPGA MSSIO/PF_BT.RX")
			(pinfunction "B_{2}")
			(pintype "bidirectional")
		)
		(pad "2" smd roundrect
			(at -0.45 0.25)
			(size 0.6 0.25)
			(layers "B.Cu" "B.Mask" "B.Paste")
			(roundrect_rratio 0.25)
			(net 417 "GND")
			(pinfunction "GND")
			(pintype "power_in")
		)
		(pad "3" smd roundrect
			(at -0.45 -0.25)
			(size 0.6 0.25)
			(layers "B.Cu" "B.Mask" "B.Paste")
			(roundrect_rratio 0.25)
			(net 649 "VDD")
			(pinfunction "VCC_{A}")
			(pintype "power_in")
		)
		(pad "4" smd roundrect
			(at -0.45 -0.75)
			(size 0.6 0.3)
			(layers "B.Cu" "B.Mask" "B.Paste")
			(roundrect_rratio 0.25)
			(net 194 "/FPGA MSSIO/BT_UART_RX")
			(pinfunction "A_{2}")
			(pintype "bidirectional")
		)
		(pad "5" smd roundrect
			(at 0.45 -0.75)
			(size 0.6 0.3)
			(layers "B.Cu" "B.Mask" "B.Paste")
			(roundrect_rratio 0.25)
			(net 193 "/FPGA MSSIO/BT_UART_TX")
			(pinfunction "A_{1}")
			(pintype "bidirectional")
		)
		(pad "6" smd roundrect
			(at 0.45 -0.25)
			(size 0.6 0.25)
			(layers "B.Cu" "B.Mask" "B.Paste")
			(roundrect_rratio 0.25)
			(net 649 "VDD")
			(pinfunction "OE")
			(pintype "input")
		)
		(pad "7" smd roundrect
			(at 0.45 0.25)
			(size 0.6 0.25)
			(layers "B.Cu" "B.Mask" "B.Paste")
			(roundrect_rratio 0.25)
			(net 50 "+3V3")
			(pinfunction "VCC_{B}")
			(pintype "power_in")
		)
		(pad "8" smd roundrect
			(at 0.45 0.75)
			(size 0.6 0.3)
			(layers "B.Cu" "B.Mask" "B.Paste")
			(roundrect_rratio 0.25)
			(net 85 "/FPGA MSSIO/PF_BT.TX")
			(pinfunction "B_{1}")
			(pintype "bidirectional")
		)
	)
	(footprint "antmicro-footprints:R_0402_1005Metric"
		(layer "B.Cu")
		(at 208.25 133.35 180)
		(descr "Resistor SMD 0402")
		(tags "resistor SMD 0402")
		(property "Reference" "R40"
			(at 0.85 -0.4 0)
			(layer "B.SilkS")
			(effects
				(font
					(size 0.7 0.7)
					(thickness 0.15)
				)
				(justify left bottom mirror)
			)
		)
		(property "Value" "R_4k7_0402"
			(at -1.011843 -1.772047 0)
			(layer "B.Fab")
			(hide yes)
			(effects
				(font
					(size 0.7 0.7)
					(thickness 0.15)
				)
				(justify left bottom mirror)
			)
		)
		(property "Datasheet" "https://www.bourns.com/docs/product-datasheets/cr.pdf"
			(at 0 0 180)
			(layer "F.Fab")
			(hide yes)
			(effects
				(font
					(size 1.27 1.27)
					(thickness 0.15)
				)
			)
		)
		(property "Description" "SMD Chip Resistor, 4.7 kohm, ± 1%, 62.5 mW, 0402 [1005 Metric], Thick Film, General Purpose"
			(at 0 0 180)
			(layer "F.Fab")
			(hide yes)
			(effects
				(font
					(size 1.27 1.27)
					(thickness 0.15)
				)
			)
		)
		(property "Author" "Antmicro"
			(at 416.5 266.7 0)
			(layer "B.Fab")
			(hide yes)
			(effects
				(font
					(size 1 1)
					(thickness 0.15)
				)
				(justify mirror)
			)
		)
		(property "License" "Apache-2.0"
			(at 416.5 266.7 0)
			(layer "B.Fab")
			(hide yes)
			(effects
				(font
					(size 1 1)
					(thickness 0.15)
				)
				(justify mirror)
			)
		)
		(property "MPN" "CR0402-FX-4701GLF"
			(at 416.5 266.7 0)
			(layer "B.Fab")
			(hide yes)
			(effects
				(font
					(size 1 1)
					(thickness 0.15)
				)
				(justify mirror)
			)
		)
		(property "Manufacturer" "Bourns"
			(at 416.5 266.7 0)
			(layer "B.Fab")
			(hide yes)
			(effects
				(font
					(size 1 1)
					(thickness 0.15)
				)
				(justify mirror)
			)
		)
		(property "Public" ""
			(at 416.5 266.7 0)
			(layer "B.Fab")
			(hide yes)
			(effects
				(font
					(size 1 1)
					(thickness 0.15)
				)
				(justify mirror)
			)
		)
		(property "Tolerance" "1%"
			(at 416.5 266.7 0)
			(layer "B.Fab")
			(hide yes)
			(effects
				(font
					(size 1 1)
					(thickness 0.15)
				)
				(justify mirror)
			)
		)
		(property "Val" "4k7"
			(at 416.5 266.7 0)
			(layer "B.Fab")
			(hide yes)
			(effects
				(font
					(size 1 1)
					(thickness 0.15)
				)
				(justify mirror)
			)
		)
		(sheetname "/FPGA Config/")
		(sheetfile "fpga-config.kicad_sch")
		(attr smd)
		(fp_rect
			(start -0.925 0.47)
			(end 0.925 -0.47)
			(stroke
				(width 0.05)
				(type default)
			)
			(fill no)
			(layer "B.CrtYd")
		)
		(fp_rect
			(start -0.5 0.25)
			(end 0.5 -0.25)
			(stroke
				(width 0.15)
				(type solid)
			)
			(fill no)
			(layer "B.Fab")
		)
		(fp_text user "License: Apache-2.0"
			(at -0.95 -5.169 0)
			(layer "B.Fab")
			(effects
				(font
					(size 0.7 0.7)
					(thickness 0.15)
				)
				(justify left bottom mirror)
			)
		)
		(fp_text user "Author: Antmicro"
			(at -0.95 -4.169 0)
			(layer "B.Fab")
			(effects
				(font
					(size 0.7 0.7)
					(thickness 0.15)
				)
				(justify left bottom mirror)
			)
		)
		(fp_text user "${REFERENCE}"
			(at -0.95 -3.168 0)
			(layer "B.Fab")
			(effects
				(font
					(size 0.7 0.7)
					(thickness 0.15)
				)
				(justify left bottom mirror)
			)
		)
		(pad "1" smd roundrect
			(at -0.48 0 180)
			(size 0.59 0.64)
			(layers "B.Cu" "B.Mask" "B.Paste")
			(roundrect_rratio 0.25)
			(net 50 "+3V3")
			(pintype "passive")
		)
		(pad "2" smd roundrect
			(at 0.48 0 180)
			(size 0.59 0.64)
			(layers "B.Cu" "B.Mask" "B.Paste")
			(roundrect_rratio 0.25)
			(net 255 "Net-(U1D-IO_CFG_INTF)")
			(pintype "passive")
		)
	)
	(footprint "antmicro-footprints:C_0402_1005Metric"
		(layer "B.Cu")
		(at 197.04 130.824 90)
		(descr "Capacitor SMD 0402")
		(tags "capacitor SMD 0402")
		(property "Reference" "C10"
			(at 5.824 -9.59 90)
			(layer "B.SilkS")
			(effects
				(font
					(size 0.7 0.7)
					(thickness 0.15)
				)
				(justify right bottom mirror)
			)
		)
		(property "Value" "C_10u_0402"
			(at -1.022927 -2.155213 90)
			(layer "B.Fab")
			(hide yes)
			(effects
				(font
					(size 0.7 0.7)
					(thickness 0.15)
				)
				(justify right bottom mirror)
			)
		)
		(property "Datasheet" "https://www.yageo.com/en/Chart/Download/pdf/CC0402MRX5R5BB106"
			(at 0 0 90)
			(layer "F.Fab")
			(hide yes)
			(effects
				(font
					(size 1.27 1.27)
					(thickness 0.15)
				)
			)
		)
		(property "Description" "SMD Multilayer Ceramic Capacitor, 10 µF, 6.3 V, 0402 [1005 Metric], ± 20%, X5R, CC Series"
			(at 0 0 90)
			(layer "F.Fab")
			(hide yes)
			(effects
				(font
					(size 1.27 1.27)
					(thickness 0.15)
				)
			)
		)
		(property "Author" "Antmicro"
			(at 327.864 -66.216 0)
			(layer "B.Fab")
			(hide yes)
			(effects
				(font
					(size 1 1)
					(thickness 0.15)
				)
				(justify mirror)
			)
		)
		(property "Dielectric" ""
			(at 327.864 -66.216 0)
			(layer "B.Fab")
			(hide yes)
			(effects
				(font
					(size 1 1)
					(thickness 0.15)
				)
				(justify mirror)
			)
		)
		(property "License" "Apache-2.0"
			(at 327.864 -66.216 0)
			(layer "B.Fab")
			(hide yes)
			(effects
				(font
					(size 1 1)
					(thickness 0.15)
				)
				(justify mirror)
			)
		)
		(property "MPN" "CC0402MRX5R5BB106"
			(at 327.864 -66.216 0)
			(layer "B.Fab")
			(hide yes)
			(effects
				(font
					(size 1 1)
					(thickness 0.15)
				)
				(justify mirror)
			)
		)
		(property "Manufacturer" "YAGEO"
			(at 327.864 -66.216 0)
			(layer "B.Fab")
			(hide yes)
			(effects
				(font
					(size 1 1)
					(thickness 0.15)
				)
				(justify mirror)
			)
		)
		(property "Public" ""
			(at 327.864 -66.216 0)
			(layer "B.Fab")
			(hide yes)
			(effects
				(font
					(size 1 1)
					(thickness 0.15)
				)
				(justify mirror)
			)
		)
		(property "Val" "10u"
			(at 327.864 -66.216 0)
			(layer "B.Fab")
			(hide yes)
			(effects
				(font
					(size 1 1)
					(thickness 0.15)
				)
				(justify mirror)
			)
		)
		(property "Voltage" ""
			(at 327.864 -66.216 0)
			(layer "B.Fab")
			(hide yes)
			(effects
				(font
					(size 1 1)
					(thickness 0.15)
				)
				(justify mirror)
			)
		)
		(sheetname "/FPGA Supply/")
		(sheetfile "fpga-supply.kicad_sch")
		(attr smd)
		(fp_rect
			(start -0.925 0.47)
			(end 0.925 -0.47)
			(stroke
				(width 0.05)
				(type default)
			)
			(fill no)
			(layer "B.CrtYd")
		)
		(fp_line
			(start 0.504 -0.248)
			(end -0.494 -0.248)
			(stroke
				(width 0.15)
				(type solid)
			)
			(layer "B.Fab")
		)
		(fp_line
			(start -0.494 -0.248)
			(end -0.494 0.25)
			(stroke
				(width 0.15)
				(type solid)
			)
			(layer "B.Fab")
		)
		(fp_line
			(start 0.504 0.25)
			(end 0.504 -0.248)
			(stroke
				(width 0.15)
				(type solid)
			)
			(layer "B.Fab")
		)
		(fp_line
			(start -0.494 0.25)
			(end 0.504 0.25)
			(stroke
				(width 0.15)
				(type solid)
			)
			(layer "B.Fab")
		)
		(fp_text user "Author: Antmicro"
			(at -0.939 -3.399 270)
			(layer "B.Fab")
			(effects
				(font
					(size 0.7 0.7)
					(thickness 0.15)
				)
				(justify left bottom mirror)
			)
		)
		(fp_text user "${REFERENCE}"
			(at -0.939 -4.599 270)
			(layer "B.Fab")
			(effects
				(font
					(size 0.7 0.7)
					(thickness 0.15)
				)
				(justify left bottom mirror)
			)
		)
		(fp_text user "License: Apache-2.0"
			(at -0.939 -5.799 270)
			(layer "B.Fab")
			(effects
				(font
					(size 0.7 0.7)
					(thickness 0.15)
				)
				(justify left bottom mirror)
			)
		)
		(pad "1" smd roundrect
			(at -0.48 0 90)
			(size 0.59 0.64)
			(layers "B.Cu" "B.Mask" "B.Paste")
			(roundrect_rratio 0.25)
			(net 417 "GND")
			(pintype "passive")
		)
		(pad "2" smd roundrect
			(at 0.48 0 90)
			(size 0.59 0.64)
			(layers "B.Cu" "B.Mask" "B.Paste")
			(roundrect_rratio 0.25)
			(net 50 "+3V3")
			(pintype "passive")
		)
	)
	(footprint "antmicro-footprints:R_0402_1005Metric"
		(layer "B.Cu")
		(at 210.1925 132.347)
		(descr "Resistor SMD 0402")
		(tags "resistor SMD 0402")
		(property "Reference" "R34"
			(at -0.8425 0.628 180)
			(layer "B.SilkS")
			(effects
				(font
					(size 0.7 0.7)
					(thickness 0.15)
				)
				(justify left bottom mirror)
			)
		)
		(property "Value" "R_49k9_0402"
			(at -1.011843 -1.772047 180)
			(layer "B.Fab")
			(hide yes)
			(effects
				(font
					(size 0.7 0.7)
					(thickness 0.15)
				)
				(justify left bottom mirror)
			)
		)
		(property "Datasheet" "https://www.bourns.com/docs/product-datasheets/cr.pdf"
			(at 0 0 0)
			(layer "F.Fab")
			(hide yes)
			(effects
				(font
					(size 1.27 1.27)
					(thickness 0.15)
				)
			)
		)
		(property "Description" "SMD Chip Resistor, 49.9 kohm, ± 1%, 63 mW, 0402 [1005 Metric], Thick Film, General Purpose"
			(at 0 0 0)
			(layer "F.Fab")
			(hide yes)
			(effects
				(font
					(size 1.27 1.27)
					(thickness 0.15)
				)
			)
		)
		(property "Author" "Antmicro"
			(at 0 0 0)
			(layer "B.Fab")
			(hide yes)
			(effects
				(font
					(size 1 1)
					(thickness 0.15)
				)
				(justify mirror)
			)
		)
		(property "License" "Apache-2.0"
			(at 0 0 0)
			(layer "B.Fab")
			(hide yes)
			(effects
				(font
					(size 1 1)
					(thickness 0.15)
				)
				(justify mirror)
			)
		)
		(property "MPN" "CR0402-FX-4992GLF"
			(at 0 0 0)
			(layer "B.Fab")
			(hide yes)
			(effects
				(font
					(size 1 1)
					(thickness 0.15)
				)
				(justify mirror)
			)
		)
		(property "Manufacturer" "Bourns"
			(at 0 0 0)
			(layer "B.Fab")
			(hide yes)
			(effects
				(font
					(size 1 1)
					(thickness 0.15)
				)
				(justify mirror)
			)
		)
		(property "Public" ""
			(at 0 0 0)
			(layer "B.Fab")
			(hide yes)
			(effects
				(font
					(size 1 1)
					(thickness 0.15)
				)
				(justify mirror)
			)
		)
		(property "Tolerance" "1%"
			(at 0 0 0)
			(layer "B.Fab")
			(hide yes)
			(effects
				(font
					(size 1 1)
					(thickness 0.15)
				)
				(justify mirror)
			)
		)
		(property "Val" "49k9"
			(at 0 0 0)
			(layer "B.Fab")
			(hide yes)
			(effects
				(font
					(size 1 1)
					(thickness 0.15)
				)
				(justify mirror)
			)
		)
		(sheetname "/Memory/")
		(sheetfile "memory.kicad_sch")
		(attr smd)
		(fp_rect
			(start -0.925 0.47)
			(end 0.925 -0.47)
			(stroke
				(width 0.05)
				(type default)
			)
			(fill no)
			(layer "B.CrtYd")
		)
		(fp_rect
			(start -0.5 0.25)
			(end 0.5 -0.25)
			(stroke
				(width 0.15)
				(type solid)
			)
			(fill no)
			(layer "B.Fab")
		)
		(fp_text user "License: Apache-2.0"
			(at -0.95 -5.169 180)
			(layer "B.Fab")
			(effects
				(font
					(size 0.7 0.7)
					(thickness 0.15)
				)
				(justify left bottom mirror)
			)
		)
		(fp_text user "Author: Antmicro"
			(at -0.95 -4.169 180)
			(layer "B.Fab")
			(effects
				(font
					(size 0.7 0.7)
					(thickness 0.15)
				)
				(justify left bottom mirror)
			)
		)
		(fp_text user "${REFERENCE}"
			(at -0.95 -3.168 180)
			(layer "B.Fab")
			(effects
				(font
					(size 0.7 0.7)
					(thickness 0.15)
				)
				(justify left bottom mirror)
			)
		)
		(pad "1" smd roundrect
			(at -0.48 0)
			(size 0.59 0.64)
			(layers "B.Cu" "B.Mask" "B.Paste")
			(roundrect_rratio 0.25)
			(net 250 "/FPGA MSSIO/EMMC.DAT4")
			(pintype "passive")
		)
		(pad "2" smd roundrect
			(at 0.48 0)
			(size 0.59 0.64)
			(layers "B.Cu" "B.Mask" "B.Paste")
			(roundrect_rratio 0.25)
			(net 137 "SD_VDD")
			(pintype "passive")
		)
	)
	(footprint "antmicro-footprints:C_0603_1608Metric"
		(layer "B.Cu")
		(at 206.09 131.6 90)
		(descr "Capacitor SMD 0603")
		(tags "capacitor 0603")
		(property "Reference" "C67"
			(at 1.25 0.36 90)
			(layer "B.SilkS")
			(effects
				(font
					(size 0.7 0.7)
					(thickness 0.15)
				)
				(justify right bottom mirror)
			)
		)
		(property "Value" "C_47u_0603"
			(at -1.42757 -1.770288 90)
			(layer "B.Fab")
			(hide yes)
			(effects
				(font
					(size 0.7 0.7)
					(thickness 0.15)
				)
				(justify right bottom mirror)
			)
		)
		(property "Datasheet" "https://www.murata.com/products/productdetail?partno=GRM188R60J476ME15%23"
			(at 0 0 90)
			(layer "F.Fab")
			(hide yes)
			(effects
				(font
					(size 1.27 1.27)
					(thickness 0.15)
				)
			)
		)
		(property "Description" "SMD Multilayer Ceramic Capacitor, 47 µF, 6.3 V, 0603 [1608 Metric], ± 20%, X5R, GRM Series"
			(at 0 0 90)
			(layer "F.Fab")
			(hide yes)
			(effects
				(font
					(size 1.27 1.27)
					(thickness 0.15)
				)
			)
		)
		(property "Author" "Antmicro"
			(at 337.69 -74.49 0)
			(layer "B.Fab")
			(hide yes)
			(effects
				(font
					(size 1 1)
					(thickness 0.15)
				)
				(justify mirror)
			)
		)
		(property "Capacitance" "47u"
			(at 337.69 -74.49 0)
			(layer "B.Fab")
			(hide yes)
			(effects
				(font
					(size 1 1)
					(thickness 0.15)
				)
				(justify mirror)
			)
		)
		(property "Dielectric" "X7R"
			(at 337.69 -74.49 0)
			(layer "B.Fab")
			(hide yes)
			(effects
				(font
					(size 1 1)
					(thickness 0.15)
				)
				(justify mirror)
			)
		)
		(property "License" "Apache-2.0"
			(at 337.69 -74.49 0)
			(layer "B.Fab")
			(hide yes)
			(effects
				(font
					(size 1 1)
					(thickness 0.15)
				)
				(justify mirror)
			)
		)
		(property "MPN" "GRM188R60J476ME15D"
			(at 337.69 -74.49 0)
			(layer "B.Fab")
			(hide yes)
			(effects
				(font
					(size 1 1)
					(thickness 0.15)
				)
				(justify mirror)
			)
		)
		(property "Manufacturer" "Murata"
			(at 337.69 -74.49 0)
			(layer "B.Fab")
			(hide yes)
			(effects
				(font
					(size 1 1)
					(thickness 0.15)
				)
				(justify mirror)
			)
		)
		(property "Public" ""
			(at 337.69 -74.49 0)
			(layer "B.Fab")
			(hide yes)
			(effects
				(font
					(size 1 1)
					(thickness 0.15)
				)
				(justify mirror)
			)
		)
		(property "Val" "47u"
			(at 337.69 -74.49 0)
			(layer "B.Fab")
			(hide yes)
			(effects
				(font
					(size 1 1)
					(thickness 0.15)
				)
				(justify mirror)
			)
		)
		(property "Voltage" "50V"
			(at 337.69 -74.49 0)
			(layer "B.Fab")
			(hide yes)
			(effects
				(font
					(size 1 1)
					(thickness 0.15)
				)
				(justify mirror)
			)
		)
		(sheetname "/FPGA Supply/")
		(sheetfile "fpga-supply.kicad_sch")
		(attr smd)
		(fp_line
			(start -0.15 -0.4)
			(end 0.15 -0.4)
			(stroke
				(width 0.15)
				(type solid)
			)
			(layer "B.SilkS")
		)
		(fp_line
			(start -0.15 0.4)
			(end 0.15 0.4)
			(stroke
				(width 0.15)
				(type solid)
			)
			(layer "B.SilkS")
		)
		(fp_rect
			(start -1.25 0.65)
			(end 1.25 -0.65)
			(stroke
				(width 0.05)
				(type solid)
			)
			(fill no)
			(layer "B.CrtYd")
		)
		(fp_rect
			(start -0.8 0.4)
			(end 0.8 -0.4)
			(stroke
				(width 0.15)
				(type solid)
			)
			(fill no)
			(layer "B.Fab")
		)
		(fp_text user "License: Apache-2.0"
			(at -1.682 -5.895 270)
			(layer "B.Fab")
			(effects
				(font
					(size 0.7 0.7)
					(thickness 0.15)
				)
				(justify left bottom mirror)
			)
		)
		(fp_text user "Author: Antmicro"
			(at -1.682 -4.894 270)
			(layer "B.Fab")
			(effects
				(font
					(size 0.7 0.7)
					(thickness 0.15)
				)
				(justify left bottom mirror)
			)
		)
		(fp_text user "${REFERENCE}"
			(at -1.682 -3.895 270)
			(layer "B.Fab")
			(effects
				(font
					(size 0.7 0.7)
					(thickness 0.15)
				)
				(justify left bottom mirror)
			)
		)
		(pad "1" smd roundrect
			(at -0.7 0 90)
			(size 0.8 1)
			(layers "B.Cu" "B.Mask" "B.Paste")
			(roundrect_rratio 0.2)
			(net 417 "GND")
			(pintype "passive")
		)
		(pad "2" smd roundrect
			(at 0.7 0 90)
			(size 0.8 1)
			(layers "B.Cu" "B.Mask" "B.Paste")
			(roundrect_rratio 0.2)
			(net 649 "VDD")
			(pintype "passive")
		)
	)
	(footprint "antmicro-footprints:R_0402_1005Metric"
		(layer "B.Cu")
		(at 219.32 154.14 180)
		(descr "Resistor SMD 0402")
		(tags "resistor SMD 0402")
		(property "Reference" "R89"
			(at 0.96 -0.43 0)
			(layer "B.SilkS")
			(effects
				(font
					(size 0.7 0.7)
					(thickness 0.15)
				)
				(justify left bottom mirror)
			)
		)
		(property "Value" "R_50R_0402"
			(at -1.011843 -1.772047 0)
			(layer "B.Fab")
			(hide yes)
			(effects
				(font
					(size 0.7 0.7)
					(thickness 0.15)
				)
				(justify left bottom mirror)
			)
		)
		(property "Datasheet" "https://www.bourns.com/docs/product-datasheets/cr.pdf"
			(at 0 0 180)
			(layer "F.Fab")
			(hide yes)
			(effects
				(font
					(size 1.27 1.27)
					(thickness 0.15)
				)
			)
		)
		(property "Description" "SMD Chip Resistor"
			(at 0 0 180)
			(layer "F.Fab")
			(hide yes)
			(effects
				(font
					(size 1.27 1.27)
					(thickness 0.15)
				)
			)
		)
		(property "Author" "Antmicro"
			(at 438.64 308.28 0)
			(layer "B.Fab")
			(hide yes)
			(effects
				(font
					(size 1 1)
					(thickness 0.15)
				)
				(justify mirror)
			)
		)
		(property "License" "Apache-2.0"
			(at 438.64 308.28 0)
			(layer "B.Fab")
			(hide yes)
			(effects
				(font
					(size 1 1)
					(thickness 0.15)
				)
				(justify mirror)
			)
		)
		(property "MPN" "CR0402-FX-50R0GLF"
			(at 438.64 308.28 0)
			(layer "B.Fab")
			(hide yes)
			(effects
				(font
					(size 1 1)
					(thickness 0.15)
				)
				(justify mirror)
			)
		)
		(property "Manufacturer" "Bourns"
			(at 438.64 308.28 0)
			(layer "B.Fab")
			(hide yes)
			(effects
				(font
					(size 1 1)
					(thickness 0.15)
				)
				(justify mirror)
			)
		)
		(property "Public" ""
			(at 438.64 308.28 0)
			(layer "B.Fab")
			(hide yes)
			(effects
				(font
					(size 1 1)
					(thickness 0.15)
				)
				(justify mirror)
			)
		)
		(property "Tolerance" "1%"
			(at 438.64 308.28 0)
			(layer "B.Fab")
			(hide yes)
			(effects
				(font
					(size 1 1)
					(thickness 0.15)
				)
				(justify mirror)
			)
		)
		(property "Val" "50R"
			(at 438.64 308.28 0)
			(layer "B.Fab")
			(hide yes)
			(effects
				(font
					(size 1 1)
					(thickness 0.15)
				)
				(justify mirror)
			)
		)
		(sheetname "/PCIe/")
		(sheetfile "pcie.kicad_sch")
		(attr smd)
		(fp_rect
			(start -0.925 0.47)
			(end 0.925 -0.47)
			(stroke
				(width 0.05)
				(type default)
			)
			(fill no)
			(layer "B.CrtYd")
		)
		(fp_rect
			(start -0.5 0.25)
			(end 0.5 -0.25)
			(stroke
				(width 0.15)
				(type solid)
			)
			(fill no)
			(layer "B.Fab")
		)
		(fp_text user "Author: Antmicro"
			(at -0.95 -4.169 0)
			(layer "B.Fab")
			(effects
				(font
					(size 0.7 0.7)
					(thickness 0.15)
				)
				(justify left bottom mirror)
			)
		)
		(fp_text user "${REFERENCE}"
			(at -0.95 -3.168 0)
			(layer "B.Fab")
			(effects
				(font
					(size 0.7 0.7)
					(thickness 0.15)
				)
				(justify left bottom mirror)
			)
		)
		(fp_text user "License: Apache-2.0"
			(at -0.95 -5.169 0)
			(layer "B.Fab")
			(effects
				(font
					(size 0.7 0.7)
					(thickness 0.15)
				)
				(justify left bottom mirror)
			)
		)
		(pad "1" smd roundrect
			(at -0.48 0 180)
			(size 0.59 0.64)
			(layers "B.Cu" "B.Mask" "B.Paste")
			(roundrect_rratio 0.25)
			(net 417 "GND")
			(pintype "passive")
		)
		(pad "2" smd roundrect
			(at 0.48 0 180)
			(size 0.59 0.64)
			(layers "B.Cu" "B.Mask" "B.Paste")
			(roundrect_rratio 0.25)
			(net 315 "Net-(U17-CLK1+)")
			(pintype "passive")
		)
	)
	(footprint "antmicro-footprints:R_0603_1608Metric"
		(layer "B.Cu")
		(at 184.25 144.65 -45)
		(descr "Resistor SMD 0603")
		(tags "resistor SMD 0603")
		(property "Reference" "R49"
			(at 3.196123 -1.682914 135)
			(layer "B.SilkS")
			(effects
				(font
					(size 0.7 0.7)
					(thickness 0.15)
				)
				(justify left bottom mirror)
			)
		)
		(property "Value" "R_0R01_0603"
			(at 0 -1.6 135)
			(layer "B.Fab")
			(hide yes)
			(effects
				(font
					(size 0.7 0.7)
					(thickness 0.15)
				)
				(justify left bottom mirror)
			)
		)
		(property "Datasheet" "https://www.bourns.com/docs/product-datasheets/cfn-a.pdf"
			(at 0 0 315)
			(layer "F.Fab")
			(hide yes)
			(effects
				(font
					(size 1.27 1.27)
					(thickness 0.15)
				)
			)
		)
		(property "Description" "SMD Chip Resistor, 10 mohm, ± 1%, 0.5 W, 0603 [1608 Metric], Metal Foil, Current Sensing"
			(at 0 0 315)
			(layer "F.Fab")
			(hide yes)
			(effects
				(font
					(size 1.27 1.27)
					(thickness 0.15)
				)
			)
		)
		(property "Author" "Antmicro"
			(at -48.31742 172.651428 0)
			(layer "B.Fab")
			(hide yes)
			(effects
				(font
					(size 1 1)
					(thickness 0.15)
				)
				(justify mirror)
			)
		)
		(property "License" "Apache-2.0"
			(at -48.31742 172.651428 0)
			(layer "B.Fab")
			(hide yes)
			(effects
				(font
					(size 1 1)
					(thickness 0.15)
				)
				(justify mirror)
			)
		)
		(property "MPN" "CFN0603AFZ-R010ELF"
			(at -48.31742 172.651428 0)
			(layer "B.Fab")
			(hide yes)
			(effects
				(font
					(size 1 1)
					(thickness 0.15)
				)
				(justify mirror)
			)
		)
		(property "Manufacturer" "Bourns"
			(at -48.31742 172.651428 0)
			(layer "B.Fab")
			(hide yes)
			(effects
				(font
					(size 1 1)
					(thickness 0.15)
				)
				(justify mirror)
			)
		)
		(property "Public" ""
			(at -48.31742 172.651428 0)
			(layer "B.Fab")
			(hide yes)
			(effects
				(font
					(size 1 1)
					(thickness 0.15)
				)
				(justify mirror)
			)
		)
		(property "Tolerance" "1%"
			(at -48.31742 172.651428 0)
			(layer "B.Fab")
			(hide yes)
			(effects
				(font
					(size 1 1)
					(thickness 0.15)
				)
				(justify mirror)
			)
		)
		(property "Val" "0R01"
			(at -48.31742 172.651428 0)
			(layer "B.Fab")
			(hide yes)
			(effects
				(font
					(size 1 1)
					(thickness 0.15)
				)
				(justify mirror)
			)
		)
		(sheetname "/Supply/")
		(sheetfile "supply.kicad_sch")
		(attr smd)
		(fp_line
			(start -0.15 0.4)
			(end 0.15 0.4)
			(stroke
				(width 0.15)
				(type solid)
			)
			(layer "B.SilkS")
		)
		(fp_line
			(start -0.15 -0.4)
			(end 0.15 -0.4)
			(stroke
				(width 0.15)
				(type solid)
			)
			(layer "B.SilkS")
		)
		(fp_poly
			(pts
				(xy -1.25 0.65) (xy 1.25 0.65) (xy 1.25 -0.65) (xy -1.25 -0.65)
			)
			(stroke
				(width 0.05)
				(type solid)
			)
			(fill no)
			(layer "B.CrtYd")
		)
		(fp_poly
			(pts
				(xy -0.8 0.4) (xy 0.8 0.4) (xy 0.8 -0.4) (xy -0.8 -0.4)
			)
			(stroke
				(width 0.15)
				(type solid)
			)
			(fill no)
			(layer "B.Fab")
		)
		(fp_text user "${REFERENCE}"
			(at -1.25 -3.898 135)
			(layer "B.Fab")
			(effects
				(font
					(size 0.7 0.7)
					(thickness 0.15)
				)
				(justify left bottom mirror)
			)
		)
		(fp_text user "Author: Antmicro"
			(at -1.25 -4.9 135)
			(layer "B.Fab")
			(effects
				(font
					(size 0.7 0.7)
					(thickness 0.15)
				)
				(justify left bottom mirror)
			)
		)
		(fp_text user "License: Apache-2.0"
			(at -1.249999 -5.9 135)
			(layer "B.Fab")
			(effects
				(font
					(size 0.7 0.7)
					(thickness 0.15)
				)
				(justify left bottom mirror)
			)
		)
		(pad "1" smd roundrect
			(at -0.7 0 315)
			(size 0.8 1)
			(layers "B.Cu" "B.Mask" "B.Paste")
			(roundrect_rratio 0.2)
			(net 409 "/Supply/SENSE4_P")
			(pintype "passive")
		)
		(pad "2" smd roundrect
			(at 0.7 0 315)
			(size 0.8 1)
			(layers "B.Cu" "B.Mask" "B.Paste")
			(roundrect_rratio 0.2)
			(net 96 "+1V2")
			(pintype "passive")
		)
	)
	(footprint "antmicro-footprints:C_0402_1005Metric"
		(layer "B.Cu")
		(at 203.216 148.675)
		(descr "Capacitor SMD 0402")
		(tags "capacitor SMD 0402")
		(property "Reference" "C200"
			(at -0.366 2.225 0)
			(layer "B.SilkS")
			(effects
				(font
					(size 0.7 0.7)
					(thickness 0.15)
				)
				(justify right bottom mirror)
			)
		)
		(property "Value" "C_1u_0402"
			(at -1.022927 -2.155213 0)
			(layer "B.Fab")
			(hide yes)
			(effects
				(font
					(size 0.7 0.7)
					(thickness 0.15)
				)
				(justify right bottom mirror)
			)
		)
		(property "Datasheet" "https://product.tdk.com/en/search/capacitor/ceramic/mlcc/info?part_no=C1005X6S1A105K050BC"
			(at 0 0 0)
			(layer "F.Fab")
			(hide yes)
			(effects
				(font
					(size 1.27 1.27)
					(thickness 0.15)
				)
			)
		)
		(property "Description" "SMD Multilayer Ceramic Capacitor, 1 µF, 10 V, 0402 [1005 Metric], ± 10%, X6S, C"
			(at 0 0 0)
			(layer "F.Fab")
			(hide yes)
			(effects
				(font
					(size 1.27 1.27)
					(thickness 0.15)
				)
			)
		)
		(property "Author" "Antmicro"
			(at 0 0 0)
			(layer "B.Fab")
			(hide yes)
			(effects
				(font
					(size 1 1)
					(thickness 0.15)
				)
				(justify mirror)
			)
		)
		(property "Dielectric" ""
			(at 0 0 0)
			(layer "B.Fab")
			(hide yes)
			(effects
				(font
					(size 1 1)
					(thickness 0.15)
				)
				(justify mirror)
			)
		)
		(property "License" "Apache-2.0"
			(at 0 0 0)
			(layer "B.Fab")
			(hide yes)
			(effects
				(font
					(size 1 1)
					(thickness 0.15)
				)
				(justify mirror)
			)
		)
		(property "MPN" "C1005X6S1A105K050BC"
			(at 0 0 0)
			(layer "B.Fab")
			(hide yes)
			(effects
				(font
					(size 1 1)
					(thickness 0.15)
				)
				(justify mirror)
			)
		)
		(property "Manufacturer" "TDK"
			(at 0 0 0)
			(layer "B.Fab")
			(hide yes)
			(effects
				(font
					(size 1 1)
					(thickness 0.15)
				)
				(justify mirror)
			)
		)
		(property "Public" ""
			(at 0 0 0)
			(layer "B.Fab")
			(hide yes)
			(effects
				(font
					(size 1 1)
					(thickness 0.15)
				)
				(justify mirror)
			)
		)
		(property "Val" "1u"
			(at 0 0 0)
			(layer "B.Fab")
			(hide yes)
			(effects
				(font
					(size 1 1)
					(thickness 0.15)
				)
				(justify mirror)
			)
		)
		(property "Voltage" ""
			(at 0 0 0)
			(layer "B.Fab")
			(hide yes)
			(effects
				(font
					(size 1 1)
					(thickness 0.15)
				)
				(justify mirror)
			)
		)
		(sheetname "/MIPI CrossLink/")
		(sheetfile "crosslink.kicad_sch")
		(attr smd)
		(fp_rect
			(start -0.925 0.47)
			(end 0.925 -0.47)
			(stroke
				(width 0.05)
				(type default)
			)
			(fill no)
			(layer "B.CrtYd")
		)
		(fp_line
			(start -0.494 -0.248)
			(end -0.494 0.25)
			(stroke
				(width 0.15)
				(type solid)
			)
			(layer "B.Fab")
		)
		(fp_line
			(start -0.494 0.25)
			(end 0.504 0.25)
			(stroke
				(width 0.15)
				(type solid)
			)
			(layer "B.Fab")
		)
		(fp_line
			(start 0.504 -0.248)
			(end -0.494 -0.248)
			(stroke
				(width 0.15)
				(type solid)
			)
			(layer "B.Fab")
		)
		(fp_line
			(start 0.504 0.25)
			(end 0.504 -0.248)
			(stroke
				(width 0.15)
				(type solid)
			)
			(layer "B.Fab")
		)
		(fp_text user "Author: Antmicro"
			(at -0.939 -3.399 180)
			(layer "B.Fab")
			(effects
				(font
					(size 0.7 0.7)
					(thickness 0.15)
				)
				(justify left bottom mirror)
			)
		)
		(fp_text user "License: Apache-2.0"
			(at -0.939 -5.799 180)
			(layer "B.Fab")
			(effects
				(font
					(size 0.7 0.7)
					(thickness 0.15)
				)
				(justify left bottom mirror)
			)
		)
		(fp_text user "${REFERENCE}"
			(at -0.939 -4.599 180)
			(layer "B.Fab")
			(effects
				(font
					(size 0.7 0.7)
					(thickness 0.15)
				)
				(justify left bottom mirror)
			)
		)
		(pad "1" smd roundrect
			(at -0.48 0)
			(size 0.59 0.64)
			(layers "B.Cu" "B.Mask" "B.Paste")
			(roundrect_rratio 0.25)
			(net 417 "GND")
			(pintype "passive")
		)
		(pad "2" smd roundrect
			(at 0.48 0)
			(size 0.59 0.64)
			(layers "B.Cu" "B.Mask" "B.Paste")
			(roundrect_rratio 0.25)
			(net 103 "2V5_CL")
			(pintype "passive")
		)
	)
	(footprint "antmicro-footprints:C_0402_1005Metric"
		(layer "B.Cu")
		(at 208.1 150.33 180)
		(descr "Capacitor SMD 0402")
		(tags "capacitor SMD 0402")
		(property "Reference" "C248"
			(at 4.9 18.375 0)
			(layer "B.SilkS")
			(effects
				(font
					(size 0.7 0.7)
					(thickness 0.15)
				)
				(justify left bottom mirror)
			)
		)
		(property "Value" "C_10u_10V_0402"
			(at -1.022927 -2.155213 0)
			(layer "B.Fab")
			(hide yes)
			(effects
				(font
					(size 0.7 0.7)
					(thickness 0.15)
				)
				(justify left bottom mirror)
			)
		)
		(property "Datasheet" "https://www.murata.com/products/productdetail?partno=GRM155R61A106ME11%23"
			(at 0 0 180)
			(layer "F.Fab")
			(hide yes)
			(effects
				(font
					(size 1.27 1.27)
					(thickness 0.15)
				)
			)
		)
		(property "Description" "Multilayer Ceramic Capacitors MLCC - SMD/SMT 10 uF 10 VDC 20% 0402 X5R"
			(at 0 0 180)
			(layer "F.Fab")
			(hide yes)
			(effects
				(font
					(size 1.27 1.27)
					(thickness 0.15)
				)
			)
		)
		(property "Author" "Antmicro"
			(at 416.2 300.66 0)
			(layer "B.Fab")
			(hide yes)
			(effects
				(font
					(size 1 1)
					(thickness 0.15)
				)
				(justify mirror)
			)
		)
		(property "Dielectric" "X5R"
			(at 416.2 300.66 0)
			(layer "B.Fab")
			(hide yes)
			(effects
				(font
					(size 1 1)
					(thickness 0.15)
				)
				(justify mirror)
			)
		)
		(property "License" "Apache-2.0"
			(at 416.2 300.66 0)
			(layer "B.Fab")
			(hide yes)
			(effects
				(font
					(size 1 1)
					(thickness 0.15)
				)
				(justify mirror)
			)
		)
		(property "MPN" "GRM155R61A106ME11D"
			(at 416.2 300.66 0)
			(layer "B.Fab")
			(hide yes)
			(effects
				(font
					(size 1 1)
					(thickness 0.15)
				)
				(justify mirror)
			)
		)
		(property "Manufacturer" "Murata"
			(at 416.2 300.66 0)
			(layer "B.Fab")
			(hide yes)
			(effects
				(font
					(size 1 1)
					(thickness 0.15)
				)
				(justify mirror)
			)
		)
		(property "Public" ""
			(at 416.2 300.66 0)
			(layer "B.Fab")
			(hide yes)
			(effects
				(font
					(size 1 1)
					(thickness 0.15)
				)
				(justify mirror)
			)
		)
		(property "Val" "10u"
			(at 416.2 300.66 0)
			(layer "B.Fab")
			(hide yes)
			(effects
				(font
					(size 1 1)
					(thickness 0.15)
				)
				(justify mirror)
			)
		)
		(property "Voltage" "10V"
			(at 416.2 300.66 0)
			(layer "B.Fab")
			(hide yes)
			(effects
				(font
					(size 1 1)
					(thickness 0.15)
				)
				(justify mirror)
			)
		)
		(sheetname "/MIPI CrossLink/")
		(sheetfile "crosslink.kicad_sch")
		(attr smd)
		(fp_rect
			(start -0.925 0.47)
			(end 0.925 -0.47)
			(stroke
				(width 0.05)
				(type default)
			)
			(fill no)
			(layer "B.CrtYd")
		)
		(fp_line
			(start 0.504 0.25)
			(end 0.504 -0.248)
			(stroke
				(width 0.15)
				(type solid)
			)
			(layer "B.Fab")
		)
		(fp_line
			(start 0.504 -0.248)
			(end -0.494 -0.248)
			(stroke
				(width 0.15)
				(type solid)
			)
			(layer "B.Fab")
		)
		(fp_line
			(start -0.494 0.25)
			(end 0.504 0.25)
			(stroke
				(width 0.15)
				(type solid)
			)
			(layer "B.Fab")
		)
		(fp_line
			(start -0.494 -0.248)
			(end -0.494 0.25)
			(stroke
				(width 0.15)
				(type solid)
			)
			(layer "B.Fab")
		)
		(fp_text user "${REFERENCE}"
			(at -0.939 -4.599 0)
			(layer "B.Fab")
			(effects
				(font
					(size 0.7 0.7)
					(thickness 0.15)
				)
				(justify left bottom mirror)
			)
		)
		(fp_text user "Author: Antmicro"
			(at -0.939 -3.399 0)
			(layer "B.Fab")
			(effects
				(font
					(size 0.7 0.7)
					(thickness 0.15)
				)
				(justify left bottom mirror)
			)
		)
		(fp_text user "License: Apache-2.0"
			(at -0.939 -5.799 0)
			(layer "B.Fab")
			(effects
				(font
					(size 0.7 0.7)
					(thickness 0.15)
				)
				(justify left bottom mirror)
			)
		)
		(pad "1" smd roundrect
			(at -0.48 0 180)
			(size 0.59 0.64)
			(layers "B.Cu" "B.Mask" "B.Paste")
			(roundrect_rratio 0.25)
			(net 417 "GND")
			(pintype "passive")
		)
		(pad "2" smd roundrect
			(at 0.48 0 180)
			(size 0.59 0.64)
			(layers "B.Cu" "B.Mask" "B.Paste")
			(roundrect_rratio 0.25)
			(net 204 "/MIPI CrossLink/CL_VCCPLL_DPHY0")
			(pintype "passive")
		)
	)
	(footprint "antmicro-footprints:C_0402_1005Metric"
		(layer "B.Cu")
		(at 195.3 125.77)
		(descr "Capacitor SMD 0402")
		(tags "capacitor SMD 0402")
		(property "Reference" "C17"
			(at -3 -0.095 0)
			(layer "B.SilkS")
			(effects
				(font
					(size 0.7 0.7)
					(thickness 0.15)
				)
				(justify right bottom mirror)
			)
		)
		(property "Value" "C_100n_0402"
			(at -1.022927 -2.155213 0)
			(layer "B.Fab")
			(hide yes)
			(effects
				(font
					(size 0.7 0.7)
					(thickness 0.15)
				)
				(justify right bottom mirror)
			)
		)
		(property "Datasheet" "https://www.murata.com/products/productdetail?partno=GRM155R61H104KE14%23"
			(at 0 0 0)
			(layer "F.Fab")
			(hide yes)
			(effects
				(font
					(size 1.27 1.27)
					(thickness 0.15)
				)
			)
		)
		(property "Description" "SMD Multilayer Ceramic Capacitor, 0.1 µF, 50 V, 0402 [1005 Metric], ± 10%, X5R, GRM Series"
			(at 0 0 0)
			(layer "F.Fab")
			(hide yes)
			(effects
				(font
					(size 1.27 1.27)
					(thickness 0.15)
				)
			)
		)
		(property "Author" "Antmicro"
			(at 0 0 0)
			(layer "B.Fab")
			(hide yes)
			(effects
				(font
					(size 1 1)
					(thickness 0.15)
				)
				(justify mirror)
			)
		)
		(property "Dielectric" "X5R"
			(at 0 0 0)
			(layer "B.Fab")
			(hide yes)
			(effects
				(font
					(size 1 1)
					(thickness 0.15)
				)
				(justify mirror)
			)
		)
		(property "License" "Apache-2.0"
			(at 0 0 0)
			(layer "B.Fab")
			(hide yes)
			(effects
				(font
					(size 1 1)
					(thickness 0.15)
				)
				(justify mirror)
			)
		)
		(property "MPN" "GRM155R61H104KE14D"
			(at 0 0 0)
			(layer "B.Fab")
			(hide yes)
			(effects
				(font
					(size 1 1)
					(thickness 0.15)
				)
				(justify mirror)
			)
		)
		(property "Manufacturer" "Murata"
			(at 0 0 0)
			(layer "B.Fab")
			(hide yes)
			(effects
				(font
					(size 1 1)
					(thickness 0.15)
				)
				(justify mirror)
			)
		)
		(property "Public" ""
			(at 0 0 0)
			(layer "B.Fab")
			(hide yes)
			(effects
				(font
					(size 1 1)
					(thickness 0.15)
				)
				(justify mirror)
			)
		)
		(property "Val" "100n"
			(at 0 0 0)
			(layer "B.Fab")
			(hide yes)
			(effects
				(font
					(size 1 1)
					(thickness 0.15)
				)
				(justify mirror)
			)
		)
		(property "Voltage" "50V"
			(at 0 0 0)
			(layer "B.Fab")
			(hide yes)
			(effects
				(font
					(size 1 1)
					(thickness 0.15)
				)
				(justify mirror)
			)
		)
		(sheetname "/FPGA Supply/")
		(sheetfile "fpga-supply.kicad_sch")
		(attr smd)
		(fp_rect
			(start -0.925 0.47)
			(end 0.925 -0.47)
			(stroke
				(width 0.05)
				(type default)
			)
			(fill no)
			(layer "B.CrtYd")
		)
		(fp_line
			(start -0.494 -0.248)
			(end -0.494 0.25)
			(stroke
				(width 0.15)
				(type solid)
			)
			(layer "B.Fab")
		)
		(fp_line
			(start -0.494 0.25)
			(end 0.504 0.25)
			(stroke
				(width 0.15)
				(type solid)
			)
			(layer "B.Fab")
		)
		(fp_line
			(start 0.504 -0.248)
			(end -0.494 -0.248)
			(stroke
				(width 0.15)
				(type solid)
			)
			(layer "B.Fab")
		)
		(fp_line
			(start 0.504 0.25)
			(end 0.504 -0.248)
			(stroke
				(width 0.15)
				(type solid)
			)
			(layer "B.Fab")
		)
		(fp_text user "Author: Antmicro"
			(at -0.939 -3.399 180)
			(layer "B.Fab")
			(effects
				(font
					(size 0.7 0.7)
					(thickness 0.15)
				)
				(justify left bottom mirror)
			)
		)
		(fp_text user "${REFERENCE}"
			(at -0.939 -4.599 180)
			(layer "B.Fab")
			(effects
				(font
					(size 0.7 0.7)
					(thickness 0.15)
				)
				(justify left bottom mirror)
			)
		)
		(fp_text user "License: Apache-2.0"
			(at -0.939 -5.799 180)
			(layer "B.Fab")
			(effects
				(font
					(size 0.7 0.7)
					(thickness 0.15)
				)
				(justify left bottom mirror)
			)
		)
		(pad "1" smd roundrect
			(at -0.48 0)
			(size 0.59 0.64)
			(layers "B.Cu" "B.Mask" "B.Paste")
			(roundrect_rratio 0.25)
			(net 417 "GND")
			(pintype "passive")
		)
		(pad "2" smd roundrect
			(at 0.48 0)
			(size 0.59 0.64)
			(layers "B.Cu" "B.Mask" "B.Paste")
			(roundrect_rratio 0.25)
			(net 2 "+1V1")
			(pintype "passive")
		)
	)
	(footprint "antmicro-footprints:C_0402_1005Metric"
		(layer "B.Cu")
		(at 180 123.1 90)
		(descr "Capacitor SMD 0402")
		(tags "capacitor SMD 0402")
		(property "Reference" "C264"
			(at 0.75 0.21 225)
			(layer "B.SilkS")
			(effects
				(font
					(size 0.7 0.7)
					(thickness 0.15)
				)
				(justify right bottom mirror)
			)
		)
		(property "Value" "C_10u_0402"
			(at -1.022927 -2.155213 90)
			(layer "B.Fab")
			(hide yes)
			(effects
				(font
					(size 0.7 0.7)
					(thickness 0.15)
				)
				(justify right bottom mirror)
			)
		)
		(property "Datasheet" "https://www.yageo.com/en/Chart/Download/pdf/CC0402MRX5R5BB106"
			(at 0 0 90)
			(layer "F.Fab")
			(hide yes)
			(effects
				(font
					(size 1.27 1.27)
					(thickness 0.15)
				)
			)
		)
		(property "Description" "SMD Multilayer Ceramic Capacitor, 10 µF, 6.3 V, 0402 [1005 Metric], ± 20%, X5R, CC Series"
			(at 0 0 90)
			(layer "F.Fab")
			(hide yes)
			(effects
				(font
					(size 1.27 1.27)
					(thickness 0.15)
				)
			)
		)
		(property "Author" "Antmicro"
			(at 303.1 -56.9 0)
			(layer "B.Fab")
			(hide yes)
			(effects
				(font
					(size 1 1)
					(thickness 0.15)
				)
				(justify mirror)
			)
		)
		(property "Dielectric" ""
			(at 303.1 -56.9 0)
			(layer "B.Fab")
			(hide yes)
			(effects
				(font
					(size 1 1)
					(thickness 0.15)
				)
				(justify mirror)
			)
		)
		(property "License" "Apache-2.0"
			(at 303.1 -56.9 0)
			(layer "B.Fab")
			(hide yes)
			(effects
				(font
					(size 1 1)
					(thickness 0.15)
				)
				(justify mirror)
			)
		)
		(property "MPN" "CC0402MRX5R5BB106"
			(at 303.1 -56.9 0)
			(layer "B.Fab")
			(hide yes)
			(effects
				(font
					(size 1 1)
					(thickness 0.15)
				)
				(justify mirror)
			)
		)
		(property "Manufacturer" "YAGEO"
			(at 303.1 -56.9 0)
			(layer "B.Fab")
			(hide yes)
			(effects
				(font
					(size 1 1)
					(thickness 0.15)
				)
				(justify mirror)
			)
		)
		(property "Public" ""
			(at 303.1 -56.9 0)
			(layer "B.Fab")
			(hide yes)
			(effects
				(font
					(size 1 1)
					(thickness 0.15)
				)
				(justify mirror)
			)
		)
		(property "Val" "10u"
			(at 303.1 -56.9 0)
			(layer "B.Fab")
			(hide yes)
			(effects
				(font
					(size 1 1)
					(thickness 0.15)
				)
				(justify mirror)
			)
		)
		(property "Voltage" ""
			(at 303.1 -56.9 0)
			(layer "B.Fab")
			(hide yes)
			(effects
				(font
					(size 1 1)
					(thickness 0.15)
				)
				(justify mirror)
			)
		)
		(sheetname "/LPDDR4/")
		(sheetfile "lpddr.kicad_sch")
		(attr smd)
		(fp_rect
			(start -0.925 0.47)
			(end 0.925 -0.47)
			(stroke
				(width 0.05)
				(type default)
			)
			(fill no)
			(layer "B.CrtYd")
		)
		(fp_line
			(start 0.504 -0.248)
			(end -0.494 -0.248)
			(stroke
				(width 0.15)
				(type solid)
			)
			(layer "B.Fab")
		)
		(fp_line
			(start -0.494 -0.248)
			(end -0.494 0.25)
			(stroke
				(width 0.15)
				(type solid)
			)
			(layer "B.Fab")
		)
		(fp_line
			(start 0.504 0.25)
			(end 0.504 -0.248)
			(stroke
				(width 0.15)
				(type solid)
			)
			(layer "B.Fab")
		)
		(fp_line
			(start -0.494 0.25)
			(end 0.504 0.25)
			(stroke
				(width 0.15)
				(type solid)
			)
			(layer "B.Fab")
		)
		(fp_text user "Author: Antmicro"
			(at -0.939 -3.399 270)
			(layer "B.Fab")
			(effects
				(font
					(size 0.7 0.7)
					(thickness 0.15)
				)
				(justify left bottom mirror)
			)
		)
		(fp_text user "License: Apache-2.0"
			(at -0.939 -5.799 270)
			(layer "B.Fab")
			(effects
				(font
					(size 0.7 0.7)
					(thickness 0.15)
				)
				(justify left bottom mirror)
			)
		)
		(fp_text user "${REFERENCE}"
			(at -0.939 -4.599 270)
			(layer "B.Fab")
			(effects
				(font
					(size 0.7 0.7)
					(thickness 0.15)
				)
				(justify left bottom mirror)
			)
		)
		(pad "1" smd roundrect
			(at -0.48 0 90)
			(size 0.59 0.64)
			(layers "B.Cu" "B.Mask" "B.Paste")
			(roundrect_rratio 0.25)
			(net 417 "GND")
			(pintype "passive")
		)
		(pad "2" smd roundrect
			(at 0.48 0 90)
			(size 0.59 0.64)
			(layers "B.Cu" "B.Mask" "B.Paste")
			(roundrect_rratio 0.25)
			(net 2 "+1V1")
			(pintype "passive")
		)
	)
	(footprint "antmicro-footprints:R_0402_1005Metric"
		(layer "B.Cu")
		(at 218.975 135.775 180)
		(descr "Resistor SMD 0402")
		(tags "resistor SMD 0402")
		(property "Reference" "R8"
			(at 0.75 -0.475 0)
			(layer "B.SilkS")
			(effects
				(font
					(size 0.7 0.7)
					(thickness 0.15)
				)
				(justify left bottom mirror)
			)
		)
		(property "Value" "R_0R_0402"
			(at -1.011843 -1.772047 0)
			(layer "B.Fab")
			(hide yes)
			(effects
				(font
					(size 0.7 0.7)
					(thickness 0.15)
				)
				(justify left bottom mirror)
			)
		)
		(property "Datasheet" "https://industrial.panasonic.com/cdbs/www-data/pdf/RDA0000/AOA0000C301.pdf"
			(at 0 0 180)
			(layer "F.Fab")
			(hide yes)
			(effects
				(font
					(size 1.27 1.27)
					(thickness 0.15)
				)
			)
		)
		(property "Description" "SMD Chip Resistor, Jumper, 0 ohm, 100 mW, 0402 [1005 Metric], Thick Film, General Purpose"
			(at 0 0 180)
			(layer "F.Fab")
			(hide yes)
			(effects
				(font
					(size 1.27 1.27)
					(thickness 0.15)
				)
			)
		)
		(property "Author" "Antmicro"
			(at 437.95 271.55 0)
			(layer "B.Fab")
			(hide yes)
			(effects
				(font
					(size 1 1)
					(thickness 0.15)
				)
				(justify mirror)
			)
		)
		(property "Current" "1A"
			(at 437.95 271.55 0)
			(layer "B.Fab")
			(hide yes)
			(effects
				(font
					(size 1 1)
					(thickness 0.15)
				)
				(justify mirror)
			)
		)
		(property "License" "Apache-2.0"
			(at 437.95 271.55 0)
			(layer "B.Fab")
			(hide yes)
			(effects
				(font
					(size 1 1)
					(thickness 0.15)
				)
				(justify mirror)
			)
		)
		(property "MPN" "ERJ2GE0R00X"
			(at 437.95 271.55 0)
			(layer "B.Fab")
			(hide yes)
			(effects
				(font
					(size 1 1)
					(thickness 0.15)
				)
				(justify mirror)
			)
		)
		(property "Manufacturer" "Panasonic"
			(at 437.95 271.55 0)
			(layer "B.Fab")
			(hide yes)
			(effects
				(font
					(size 1 1)
					(thickness 0.15)
				)
				(justify mirror)
			)
		)
		(property "Public" ""
			(at 437.95 271.55 0)
			(layer "B.Fab")
			(hide yes)
			(effects
				(font
					(size 1 1)
					(thickness 0.15)
				)
				(justify mirror)
			)
		)
		(property "Tolerance" "~"
			(at 437.95 271.55 0)
			(layer "B.Fab")
			(hide yes)
			(effects
				(font
					(size 1 1)
					(thickness 0.15)
				)
				(justify mirror)
			)
		)
		(property "Val" "0R"
			(at 437.95 271.55 0)
			(layer "B.Fab")
			(hide yes)
			(effects
				(font
					(size 1 1)
					(thickness 0.15)
				)
				(justify mirror)
			)
		)
		(sheetname "/Supply/")
		(sheetfile "supply.kicad_sch")
		(attr smd)
		(fp_rect
			(start -0.925 0.47)
			(end 0.925 -0.47)
			(stroke
				(width 0.05)
				(type default)
			)
			(fill no)
			(layer "B.CrtYd")
		)
		(fp_rect
			(start -0.5 0.25)
			(end 0.5 -0.25)
			(stroke
				(width 0.15)
				(type solid)
			)
			(fill no)
			(layer "B.Fab")
		)
		(fp_text user "License: Apache-2.0"
			(at -0.95 -5.169 0)
			(layer "B.Fab")
			(effects
				(font
					(size 0.7 0.7)
					(thickness 0.15)
				)
				(justify left bottom mirror)
			)
		)
		(fp_text user "${REFERENCE}"
			(at -0.95 -3.168 0)
			(layer "B.Fab")
			(effects
				(font
					(size 0.7 0.7)
					(thickness 0.15)
				)
				(justify left bottom mirror)
			)
		)
		(fp_text user "Author: Antmicro"
			(at -0.95 -4.169 0)
			(layer "B.Fab")
			(effects
				(font
					(size 0.7 0.7)
					(thickness 0.15)
				)
				(justify left bottom mirror)
			)
		)
		(pad "1" smd roundrect
			(at -0.48 0 180)
			(size 0.59 0.64)
			(layers "B.Cu" "B.Mask" "B.Paste")
			(roundrect_rratio 0.25)
			(net 296 "Net-(R10-Pad2)")
			(pintype "passive")
		)
		(pad "2" smd roundrect
			(at 0.48 0 180)
			(size 0.59 0.64)
			(layers "B.Cu" "B.Mask" "B.Paste")
			(roundrect_rratio 0.25)
			(net 649 "VDD")
			(pintype "passive")
		)
	)
	(footprint "antmicro-footprints:C_0402_1005Metric"
		(layer "B.Cu")
		(at 215.1925 130.697 180)
		(descr "Capacitor SMD 0402")
		(tags "capacitor SMD 0402")
		(property "Reference" "C71"
			(at -2.9975 -0.433 0)
			(layer "B.SilkS")
			(effects
				(font
					(size 0.7 0.7)
					(thickness 0.15)
				)
				(justify left bottom mirror)
			)
		)
		(property "Value" "C_100n_0402"
			(at -1.022927 -2.155213 0)
			(layer "B.Fab")
			(hide yes)
			(effects
				(font
					(size 0.7 0.7)
					(thickness 0.15)
				)
				(justify left bottom mirror)
			)
		)
		(property "Datasheet" "https://www.murata.com/products/productdetail?partno=GRM155R61H104KE14%23"
			(at 0 0 180)
			(layer "F.Fab")
			(hide yes)
			(effects
				(font
					(size 1.27 1.27)
					(thickness 0.15)
				)
			)
		)
		(property "Description" "SMD Multilayer Ceramic Capacitor, 0.1 µF, 50 V, 0402 [1005 Metric], ± 10%, X5R, GRM Series"
			(at 0 0 180)
			(layer "F.Fab")
			(hide yes)
			(effects
				(font
					(size 1.27 1.27)
					(thickness 0.15)
				)
			)
		)
		(property "Author" "Antmicro"
			(at 430.385 261.394 0)
			(layer "B.Fab")
			(hide yes)
			(effects
				(font
					(size 1 1)
					(thickness 0.15)
				)
				(justify mirror)
			)
		)
		(property "Dielectric" "X5R"
			(at 430.385 261.394 0)
			(layer "B.Fab")
			(hide yes)
			(effects
				(font
					(size 1 1)
					(thickness 0.15)
				)
				(justify mirror)
			)
		)
		(property "License" "Apache-2.0"
			(at 430.385 261.394 0)
			(layer "B.Fab")
			(hide yes)
			(effects
				(font
					(size 1 1)
					(thickness 0.15)
				)
				(justify mirror)
			)
		)
		(property "MPN" "GRM155R61H104KE14D"
			(at 430.385 261.394 0)
			(layer "B.Fab")
			(hide yes)
			(effects
				(font
					(size 1 1)
					(thickness 0.15)
				)
				(justify mirror)
			)
		)
		(property "Manufacturer" "Murata"
			(at 430.385 261.394 0)
			(layer "B.Fab")
			(hide yes)
			(effects
				(font
					(size 1 1)
					(thickness 0.15)
				)
				(justify mirror)
			)
		)
		(property "Public" ""
			(at 430.385 261.394 0)
			(layer "B.Fab")
			(hide yes)
			(effects
				(font
					(size 1 1)
					(thickness 0.15)
				)
				(justify mirror)
			)
		)
		(property "Val" "100n"
			(at 430.385 261.394 0)
			(layer "B.Fab")
			(hide yes)
			(effects
				(font
					(size 1 1)
					(thickness 0.15)
				)
				(justify mirror)
			)
		)
		(property "Voltage" "50V"
			(at 430.385 261.394 0)
			(layer "B.Fab")
			(hide yes)
			(effects
				(font
					(size 1 1)
					(thickness 0.15)
				)
				(justify mirror)
			)
		)
		(sheetname "/Memory/")
		(sheetfile "memory.kicad_sch")
		(attr smd)
		(fp_rect
			(start -0.925 0.47)
			(end 0.925 -0.47)
			(stroke
				(width 0.05)
				(type default)
			)
			(fill no)
			(layer "B.CrtYd")
		)
		(fp_line
			(start 0.504 0.25)
			(end 0.504 -0.248)
			(stroke
				(width 0.15)
				(type solid)
			)
			(layer "B.Fab")
		)
		(fp_line
			(start 0.504 -0.248)
			(end -0.494 -0.248)
			(stroke
				(width 0.15)
				(type solid)
			)
			(layer "B.Fab")
		)
		(fp_line
			(start -0.494 0.25)
			(end 0.504 0.25)
			(stroke
				(width 0.15)
				(type solid)
			)
			(layer "B.Fab")
		)
		(fp_line
			(start -0.494 -0.248)
			(end -0.494 0.25)
			(stroke
				(width 0.15)
				(type solid)
			)
			(layer "B.Fab")
		)
		(fp_text user "Author: Antmicro"
			(at -0.939 -3.399 0)
			(layer "B.Fab")
			(effects
				(font
					(size 0.7 0.7)
					(thickness 0.15)
				)
				(justify left bottom mirror)
			)
		)
		(fp_text user "${REFERENCE}"
			(at -0.939 -4.599 0)
			(layer "B.Fab")
			(effects
				(font
					(size 0.7 0.7)
					(thickness 0.15)
				)
				(justify left bottom mirror)
			)
		)
		(fp_text user "License: Apache-2.0"
			(at -0.939 -5.799 0)
			(layer "B.Fab")
			(effects
				(font
					(size 0.7 0.7)
					(thickness 0.15)
				)
				(justify left bottom mirror)
			)
		)
		(pad "1" smd roundrect
			(at -0.48 0 180)
			(size 0.59 0.64)
			(layers "B.Cu" "B.Mask" "B.Paste")
			(roundrect_rratio 0.25)
			(net 417 "GND")
			(pintype "passive")
		)
		(pad "2" smd roundrect
			(at 0.48 0 180)
			(size 0.59 0.64)
			(layers "B.Cu" "B.Mask" "B.Paste")
			(roundrect_rratio 0.25)
			(net 50 "+3V3")
			(pintype "passive")
		)
	)
	(footprint "antmicro-footprints:R_0402_1005Metric"
		(layer "B.Cu")
		(at 182.3 152.05 -90)
		(descr "Resistor SMD 0402")
		(tags "resistor SMD 0402")
		(property "Reference" "R16"
			(at -2.95 -0.3 90)
			(layer "B.SilkS")
			(effects
				(font
					(size 0.7 0.7)
					(thickness 0.15)
				)
				(justify left bottom mirror)
			)
		)
		(property "Value" "R_10k_0402"
			(at -1.011843 -1.772047 90)
			(layer "B.Fab")
			(hide yes)
			(effects
				(font
					(size 0.7 0.7)
					(thickness 0.15)
				)
				(justify left bottom mirror)
			)
		)
		(property "Datasheet" "https://www.bourns.com/docs/product-datasheets/cr.pdf"
			(at 0 0 270)
			(layer "F.Fab")
			(hide yes)
			(effects
				(font
					(size 1.27 1.27)
					(thickness 0.15)
				)
			)
		)
		(property "Description" "SMD Chip Resistor, 10 kohm, ± 1%, 62.5 mW, 0402 [1005 Metric], Thick Film, General Purpose"
			(at 0 0 270)
			(layer "F.Fab")
			(hide yes)
			(effects
				(font
					(size 1.27 1.27)
					(thickness 0.15)
				)
			)
		)
		(property "Author" "Antmicro"
			(at 30.25 334.35 0)
			(layer "B.Fab")
			(hide yes)
			(effects
				(font
					(size 1 1)
					(thickness 0.15)
				)
				(justify mirror)
			)
		)
		(property "License" "Apache-2.0"
			(at 30.25 334.35 0)
			(layer "B.Fab")
			(hide yes)
			(effects
				(font
					(size 1 1)
					(thickness 0.15)
				)
				(justify mirror)
			)
		)
		(property "MPN" "CR0402-FX-1002GLF"
			(at 30.25 334.35 0)
			(layer "B.Fab")
			(hide yes)
			(effects
				(font
					(size 1 1)
					(thickness 0.15)
				)
				(justify mirror)
			)
		)
		(property "Manufacturer" "Bourns"
			(at 30.25 334.35 0)
			(layer "B.Fab")
			(hide yes)
			(effects
				(font
					(size 1 1)
					(thickness 0.15)
				)
				(justify mirror)
			)
		)
		(property "Public" ""
			(at 30.25 334.35 0)
			(layer "B.Fab")
			(hide yes)
			(effects
				(font
					(size 1 1)
					(thickness 0.15)
				)
				(justify mirror)
			)
		)
		(property "Tolerance" "1%"
			(at 30.25 334.35 0)
			(layer "B.Fab")
			(hide yes)
			(effects
				(font
					(size 1 1)
					(thickness 0.15)
				)
				(justify mirror)
			)
		)
		(property "Val" "10k"
			(at 30.25 334.35 0)
			(layer "B.Fab")
			(hide yes)
			(effects
				(font
					(size 1 1)
					(thickness 0.15)
				)
				(justify mirror)
			)
		)
		(sheetname "/Supply/")
		(sheetfile "supply.kicad_sch")
		(attr smd)
		(fp_rect
			(start -0.925 0.47)
			(end 0.925 -0.47)
			(stroke
				(width 0.05)
				(type default)
			)
			(fill no)
			(layer "B.CrtYd")
		)
		(fp_rect
			(start -0.5 0.25)
			(end 0.5 -0.25)
			(stroke
				(width 0.15)
				(type solid)
			)
			(fill no)
			(layer "B.Fab")
		)
		(fp_text user "${REFERENCE}"
			(at -0.95 -3.168 90)
			(layer "B.Fab")
			(effects
				(font
					(size 0.7 0.7)
					(thickness 0.15)
				)
				(justify left bottom mirror)
			)
		)
		(fp_text user "License: Apache-2.0"
			(at -0.95 -5.169 90)
			(layer "B.Fab")
			(effects
				(font
					(size 0.7 0.7)
					(thickness 0.15)
				)
				(justify left bottom mirror)
			)
		)
		(fp_text user "Author: Antmicro"
			(at -0.95 -4.169 90)
			(layer "B.Fab")
			(effects
				(font
					(size 0.7 0.7)
					(thickness 0.15)
				)
				(justify left bottom mirror)
			)
		)
		(pad "1" smd roundrect
			(at -0.48 0 270)
			(size 0.59 0.64)
			(layers "B.Cu" "B.Mask" "B.Paste")
			(roundrect_rratio 0.25)
			(net 398 "/Supply/1V05_FB")
			(pintype "passive")
		)
		(pad "2" smd roundrect
			(at 0.48 0 270)
			(size 0.59 0.64)
			(layers "B.Cu" "B.Mask" "B.Paste")
			(roundrect_rratio 0.25)
			(net 14 "Net-(C111-Pad1)")
			(pintype "passive")
		)
	)
	(footprint "antmicro-footprints:C_0402_1005Metric"
		(layer "B.Cu")
		(at 204.01 129.25 180)
		(descr "Capacitor SMD 0402")
		(tags "capacitor SMD 0402")
		(property "Reference" "C11"
			(at -1.465 0.55 0)
			(layer "B.SilkS")
			(effects
				(font
					(size 0.7 0.7)
					(thickness 0.15)
				)
				(justify left bottom mirror)
			)
		)
		(property "Value" "C_10u_0402"
			(at -1.022927 -2.155213 0)
			(layer "B.Fab")
			(hide yes)
			(effects
				(font
					(size 0.7 0.7)
					(thickness 0.15)
				)
				(justify left bottom mirror)
			)
		)
		(property "Datasheet" "https://www.yageo.com/en/Chart/Download/pdf/CC0402MRX5R5BB106"
			(at 0 0 180)
			(layer "F.Fab")
			(hide yes)
			(effects
				(font
					(size 1.27 1.27)
					(thickness 0.15)
				)
			)
		)
		(property "Description" "SMD Multilayer Ceramic Capacitor, 10 µF, 6.3 V, 0402 [1005 Metric], ± 20%, X5R, CC Series"
			(at 0 0 180)
			(layer "F.Fab")
			(hide yes)
			(effects
				(font
					(size 1.27 1.27)
					(thickness 0.15)
				)
			)
		)
		(property "Author" "Antmicro"
			(at 408.02 258.5 0)
			(layer "B.Fab")
			(hide yes)
			(effects
				(font
					(size 1 1)
					(thickness 0.15)
				)
				(justify mirror)
			)
		)
		(property "Dielectric" ""
			(at 408.02 258.5 0)
			(layer "B.Fab")
			(hide yes)
			(effects
				(font
					(size 1 1)
					(thickness 0.15)
				)
				(justify mirror)
			)
		)
		(property "License" "Apache-2.0"
			(at 408.02 258.5 0)
			(layer "B.Fab")
			(hide yes)
			(effects
				(font
					(size 1 1)
					(thickness 0.15)
				)
				(justify mirror)
			)
		)
		(property "MPN" "CC0402MRX5R5BB106"
			(at 408.02 258.5 0)
			(layer "B.Fab")
			(hide yes)
			(effects
				(font
					(size 1 1)
					(thickness 0.15)
				)
				(justify mirror)
			)
		)
		(property "Manufacturer" "YAGEO"
			(at 408.02 258.5 0)
			(layer "B.Fab")
			(hide yes)
			(effects
				(font
					(size 1 1)
					(thickness 0.15)
				)
				(justify mirror)
			)
		)
		(property "Public" ""
			(at 408.02 258.5 0)
			(layer "B.Fab")
			(hide yes)
			(effects
				(font
					(size 1 1)
					(thickness 0.15)
				)
				(justify mirror)
			)
		)
		(property "Val" "10u"
			(at 408.02 258.5 0)
			(layer "B.Fab")
			(hide yes)
			(effects
				(font
					(size 1 1)
					(thickness 0.15)
				)
				(justify mirror)
			)
		)
		(property "Voltage" ""
			(at 408.02 258.5 0)
			(layer "B.Fab")
			(hide yes)
			(effects
				(font
					(size 1 1)
					(thickness 0.15)
				)
				(justify mirror)
			)
		)
		(sheetname "/FPGA Supply/")
		(sheetfile "fpga-supply.kicad_sch")
		(attr smd)
		(fp_rect
			(start -0.925 0.47)
			(end 0.925 -0.47)
			(stroke
				(width 0.05)
				(type default)
			)
			(fill no)
			(layer "B.CrtYd")
		)
		(fp_line
			(start 0.504 0.25)
			(end 0.504 -0.248)
			(stroke
				(width 0.15)
				(type solid)
			)
			(layer "B.Fab")
		)
		(fp_line
			(start 0.504 -0.248)
			(end -0.494 -0.248)
			(stroke
				(width 0.15)
				(type solid)
			)
			(layer "B.Fab")
		)
		(fp_line
			(start -0.494 0.25)
			(end 0.504 0.25)
			(stroke
				(width 0.15)
				(type solid)
			)
			(layer "B.Fab")
		)
		(fp_line
			(start -0.494 -0.248)
			(end -0.494 0.25)
			(stroke
				(width 0.15)
				(type solid)
			)
			(layer "B.Fab")
		)
		(fp_text user "Author: Antmicro"
			(at -0.939 -3.399 0)
			(layer "B.Fab")
			(effects
				(font
					(size 0.7 0.7)
					(thickness 0.15)
				)
				(justify left bottom mirror)
			)
		)
		(fp_text user "License: Apache-2.0"
			(at -0.939 -5.799 0)
			(layer "B.Fab")
			(effects
				(font
					(size 0.7 0.7)
					(thickness 0.15)
				)
				(justify left bottom mirror)
			)
		)
		(fp_text user "${REFERENCE}"
			(at -0.939 -4.599 0)
			(layer "B.Fab")
			(effects
				(font
					(size 0.7 0.7)
					(thickness 0.15)
				)
				(justify left bottom mirror)
			)
		)
		(pad "1" smd roundrect
			(at -0.48 0 180)
			(size 0.59 0.64)
			(layers "B.Cu" "B.Mask" "B.Paste")
			(roundrect_rratio 0.25)
			(net 417 "GND")
			(pintype "passive")
		)
		(pad "2" smd roundrect
			(at 0.48 0 180)
			(size 0.59 0.64)
			(layers "B.Cu" "B.Mask" "B.Paste")
			(roundrect_rratio 0.25)
			(net 50 "+3V3")
			(pintype "passive")
		)
	)
	(footprint "antmicro-footprints:C_0402_1005Metric"
		(layer "B.Cu")
		(at 178.8 127 180)
		(descr "Capacitor SMD 0402")
		(tags "capacitor SMD 0402")
		(property "Reference" "C121"
			(at -1.54 -1.375 0)
			(layer "B.SilkS")
			(effects
				(font
					(size 0.7 0.7)
					(thickness 0.15)
				)
				(justify left bottom mirror)
			)
		)
		(property "Value" "C_1u_0402"
			(at -1.022927 -2.155213 0)
			(layer "B.Fab")
			(hide yes)
			(effects
				(font
					(size 0.7 0.7)
					(thickness 0.15)
				)
				(justify left bottom mirror)
			)
		)
		(property "Datasheet" "https://product.tdk.com/en/search/capacitor/ceramic/mlcc/info?part_no=C1005X6S1A105K050BC"
			(at 0 0 180)
			(layer "F.Fab")
			(hide yes)
			(effects
				(font
					(size 1.27 1.27)
					(thickness 0.15)
				)
			)
		)
		(property "Description" "SMD Multilayer Ceramic Capacitor, 1 µF, 10 V, 0402 [1005 Metric], ± 10%, X6S, C"
			(at 0 0 180)
			(layer "F.Fab")
			(hide yes)
			(effects
				(font
					(size 1.27 1.27)
					(thickness 0.15)
				)
			)
		)
		(property "Author" "Antmicro"
			(at 357.6 254 0)
			(layer "B.Fab")
			(hide yes)
			(effects
				(font
					(size 1 1)
					(thickness 0.15)
				)
				(justify mirror)
			)
		)
		(property "Dielectric" "X5R"
			(at 357.6 254 0)
			(layer "B.Fab")
			(hide yes)
			(effects
				(font
					(size 1 1)
					(thickness 0.15)
				)
				(justify mirror)
			)
		)
		(property "License" "Apache-2.0"
			(at 357.6 254 0)
			(layer "B.Fab")
			(hide yes)
			(effects
				(font
					(size 1 1)
					(thickness 0.15)
				)
				(justify mirror)
			)
		)
		(property "MPN" "C1005X6S1A105K050BC"
			(at 357.6 254 0)
			(layer "B.Fab")
			(hide yes)
			(effects
				(font
					(size 1 1)
					(thickness 0.15)
				)
				(justify mirror)
			)
		)
		(property "Manufacturer" "TDK"
			(at 357.6 254 0)
			(layer "B.Fab")
			(hide yes)
			(effects
				(font
					(size 1 1)
					(thickness 0.15)
				)
				(justify mirror)
			)
		)
		(property "Public" ""
			(at 357.6 254 0)
			(layer "B.Fab")
			(hide yes)
			(effects
				(font
					(size 1 1)
					(thickness 0.15)
				)
				(justify mirror)
			)
		)
		(property "Val" "1u"
			(at 357.6 254 0)
			(layer "B.Fab")
			(hide yes)
			(effects
				(font
					(size 1 1)
					(thickness 0.15)
				)
				(justify mirror)
			)
		)
		(property "Voltage" "16V"
			(at 357.6 254 0)
			(layer "B.Fab")
			(hide yes)
			(effects
				(font
					(size 1 1)
					(thickness 0.15)
				)
				(justify mirror)
			)
		)
		(sheetname "/LPDDR4/")
		(sheetfile "lpddr.kicad_sch")
		(attr smd)
		(fp_rect
			(start -0.925 0.47)
			(end 0.925 -0.47)
			(stroke
				(width 0.05)
				(type default)
			)
			(fill no)
			(layer "B.CrtYd")
		)
		(fp_line
			(start 0.504 0.25)
			(end 0.504 -0.248)
			(stroke
				(width 0.15)
				(type solid)
			)
			(layer "B.Fab")
		)
		(fp_line
			(start 0.504 -0.248)
			(end -0.494 -0.248)
			(stroke
				(width 0.15)
				(type solid)
			)
			(layer "B.Fab")
		)
		(fp_line
			(start -0.494 0.25)
			(end 0.504 0.25)
			(stroke
				(width 0.15)
				(type solid)
			)
			(layer "B.Fab")
		)
		(fp_line
			(start -0.494 -0.248)
			(end -0.494 0.25)
			(stroke
				(width 0.15)
				(type solid)
			)
			(layer "B.Fab")
		)
		(fp_text user "Author: Antmicro"
			(at -0.939 -3.399 0)
			(layer "B.Fab")
			(effects
				(font
					(size 0.7 0.7)
					(thickness 0.15)
				)
				(justify left bottom mirror)
			)
		)
		(fp_text user "License: Apache-2.0"
			(at -0.939 -5.799 0)
			(layer "B.Fab")
			(effects
				(font
					(size 0.7 0.7)
					(thickness 0.15)
				)
				(justify left bottom mirror)
			)
		)
		(fp_text user "${REFERENCE}"
			(at -0.939 -4.599 0)
			(layer "B.Fab")
			(effects
				(font
					(size 0.7 0.7)
					(thickness 0.15)
				)
				(justify left bottom mirror)
			)
		)
		(pad "1" smd roundrect
			(at -0.48 0 180)
			(size 0.59 0.64)
			(layers "B.Cu" "B.Mask" "B.Paste")
			(roundrect_rratio 0.25)
			(net 417 "GND")
			(pintype "passive")
		)
		(pad "2" smd roundrect
			(at 0.48 0 180)
			(size 0.59 0.64)
			(layers "B.Cu" "B.Mask" "B.Paste")
			(roundrect_rratio 0.25)
			(net 48 "+1V8")
			(pintype "passive")
		)
	)
	(footprint "antmicro-footprints:SOT-523"
		(layer "B.Cu")
		(at 224.38 129.9 180)
		(property "Reference" "Q7"
			(at -2.02 0.3 180)
			(layer "B.SilkS")
			(effects
				(font
					(size 0.7 0.7)
					(thickness 0.15)
				)
				(justify left bottom mirror)
			)
		)
		(property "Value" "DMG1012T-7"
			(at 0.1 -1.824 0)
			(layer "B.Fab")
			(hide yes)
			(effects
				(font
					(size 0.7 0.7)
					(thickness 0.15)
				)
				(justify left bottom mirror)
			)
		)
		(property "Datasheet" "https://www.diodes.com/assets/Datasheets/ds31783.pdf"
			(at 0 0 180)
			(layer "F.Fab")
			(hide yes)
			(effects
				(font
					(size 1.27 1.27)
					(thickness 0.15)
				)
			)
		)
		(property "Description" "Power MOSFET, N Channel, 20 V, 630 mA, 0.3 ohm, SOT-523, Surface Mount"
			(at 0 0 180)
			(layer "F.Fab")
			(hide yes)
			(effects
				(font
					(size 1.27 1.27)
					(thickness 0.15)
				)
			)
		)
		(property "Author" "Antmicro"
			(at 448.76 259.8 0)
			(layer "B.Fab")
			(hide yes)
			(effects
				(font
					(size 1 1)
					(thickness 0.15)
				)
				(justify mirror)
			)
		)
		(property "License" "Apache-2.0"
			(at 448.76 259.8 0)
			(layer "B.Fab")
			(hide yes)
			(effects
				(font
					(size 1 1)
					(thickness 0.15)
				)
				(justify mirror)
			)
		)
		(property "MPN" "DMG1012T-7"
			(at 448.76 259.8 0)
			(layer "B.Fab")
			(hide yes)
			(effects
				(font
					(size 1 1)
					(thickness 0.15)
				)
				(justify mirror)
			)
		)
		(property "Manufacturer" "Diodes Incorporated"
			(at 448.76 259.8 0)
			(layer "B.Fab")
			(hide yes)
			(effects
				(font
					(size 1 1)
					(thickness 0.15)
				)
				(justify mirror)
			)
		)
		(property "Public" ""
			(at 448.76 259.8 0)
			(layer "B.Fab")
			(hide yes)
			(effects
				(font
					(size 1 1)
					(thickness 0.15)
				)
				(justify mirror)
			)
		)
		(sheetname "/FPGA GPIO/")
		(sheetfile "fpga-gpio.kicad_sch")
		(attr smd)
		(fp_line
			(start -0.277 0.551)
			(end -0.277 0.75)
			(stroke
				(width 0.15)
				(type solid)
			)
			(layer "B.SilkS")
		)
		(fp_line
			(start -0.725 0.551)
			(end -0.277 0.551)
			(stroke
				(width 0.15)
				(type solid)
			)
			(layer "B.SilkS")
		)
		(fp_line
			(start -0.927 0.351)
			(end -0.725 0.551)
			(stroke
				(width 0.15)
				(type solid)
			)
			(layer "B.SilkS")
		)
		(fp_line
			(start -0.927 0.051)
			(end -0.927 0.351)
			(stroke
				(width 0.15)
				(type solid)
			)
			(layer "B.SilkS")
		)
		(fp_circle
			(center -0.9652 -0.9652)
			(end -0.9152 -0.9652)
			(stroke
				(width 0.15)
				(type solid)
			)
			(fill yes)
			(layer "B.SilkS")
		)
		(fp_line
			(start 1.1 1.16)
			(end 1.1 -1.15)
			(stroke
				(width 0.05)
				(type solid)
			)
			(layer "B.CrtYd")
		)
		(fp_line
			(start -1.12 1.16)
			(end 1.1 1.16)
			(stroke
				(width 0.05)
				(type solid)
			)
			(layer "B.CrtYd")
		)
		(fp_line
			(start -1.12 1.16)
			(end -1.12 -1.15)
			(stroke
				(width 0.05)
				(type solid)
			)
			(layer "B.CrtYd")
		)
		(fp_line
			(start -1.12 -1.15)
			(end 1.1 -1.15)
			(stroke
				(width 0.05)
				(type solid)
			)
			(layer "B.CrtYd")
		)
		(fp_line
			(start 0.8 0.425)
			(end 0.8 -0.424)
			(stroke
				(width 0.15)
				(type solid)
			)
			(layer "B.Fab")
		)
		(fp_line
			(start 0.8 0.425)
			(end -0.652 0.425)
			(stroke
				(width 0.15)
				(type solid)
			)
			(layer "B.Fab")
		)
		(fp_line
			(start 0.8 -0.424)
			(end -0.802 -0.424)
			(stroke
				(width 0.15)
				(type solid)
			)
			(layer "B.Fab")
		)
		(fp_line
			(start -0.652 0.425)
			(end -0.802 0.276)
			(stroke
				(width 0.15)
				(type solid)
			)
			(layer "B.Fab")
		)
		(fp_line
			(start -0.802 0.276)
			(end -0.802 -0.424)
			(stroke
				(width 0.15)
				(type solid)
			)
			(layer "B.Fab")
		)
		(fp_circle
			(center -0.9652 -0.9652)
			(end -0.9144 -0.9652)
			(stroke
				(width 0.15)
				(type solid)
			)
			(fill no)
			(layer "B.Fab")
		)
		(fp_text user "${REFERENCE}"
			(at -1.12 -3.824 0)
			(layer "B.Fab")
			(effects
				(font
					(size 0.7 0.7)
					(thickness 0.15)
				)
				(justify left bottom mirror)
			)
		)
		(fp_text user "License: Apache-2.0"
			(at -1.12 -5.024 0)
			(layer "B.Fab")
			(effects
				(font
					(size 0.7 0.7)
					(thickness 0.15)
				)
				(justify left bottom mirror)
			)
		)
		(fp_text user "Author: Antmicro"
			(at -1.12 -6.224 0)
			(layer "B.Fab")
			(effects
				(font
					(size 0.7 0.7)
					(thickness 0.15)
				)
				(justify left bottom mirror)
			)
		)
		(pad "1" smd rect
			(at -0.5 -0.65 180)
			(size 0.4 0.51)
			(layers "B.Cu" "B.Mask" "B.Paste")
			(net 341 "/FPGA GPIO/USER_LED_G")
			(pinfunction "G")
			(pintype "input")
		)
		(pad "2" smd rect
			(at 0.498 -0.65 180)
			(size 0.4 0.51)
			(layers "B.Cu" "B.Mask" "B.Paste")
			(net 417 "GND")
			(pinfunction "S")
			(pintype "passive")
		)
		(pad "3" smd rect
			(at 0 0.652 180)
			(size 0.4 0.51)
			(layers "B.Cu" "B.Mask" "B.Paste")
			(net 541 "Net-(Q7-D)")
			(pinfunction "D")
			(pintype "passive")
		)
	)
	(footprint "antmicro-footprints:C_0402_1005Metric"
		(layer "B.Cu")
		(at 184.8 125.834 -90)
		(descr "Capacitor SMD 0402")
		(tags "capacitor SMD 0402")
		(property "Reference" "C119"
			(at -1.534 -1.4 90)
			(layer "B.SilkS")
			(effects
				(font
					(size 0.7 0.7)
					(thickness 0.15)
				)
				(justify left bottom mirror)
			)
		)
		(property "Value" "C_1u_0402"
			(at -1.022927 -2.155213 90)
			(layer "B.Fab")
			(hide yes)
			(effects
				(font
					(size 0.7 0.7)
					(thickness 0.15)
				)
				(justify left bottom mirror)
			)
		)
		(property "Datasheet" "https://product.tdk.com/en/search/capacitor/ceramic/mlcc/info?part_no=C1005X6S1A105K050BC"
			(at 0 0 270)
			(layer "F.Fab")
			(hide yes)
			(effects
				(font
					(size 1.27 1.27)
					(thickness 0.15)
				)
			)
		)
		(property "Description" "SMD Multilayer Ceramic Capacitor, 1 µF, 10 V, 0402 [1005 Metric], ± 10%, X6S, C"
			(at 0 0 270)
			(layer "F.Fab")
			(hide yes)
			(effects
				(font
					(size 1.27 1.27)
					(thickness 0.15)
				)
			)
		)
		(property "Author" "Antmicro"
			(at 58.966 310.634 0)
			(layer "B.Fab")
			(hide yes)
			(effects
				(font
					(size 1 1)
					(thickness 0.15)
				)
				(justify mirror)
			)
		)
		(property "Dielectric" "X5R"
			(at 58.966 310.634 0)
			(layer "B.Fab")
			(hide yes)
			(effects
				(font
					(size 1 1)
					(thickness 0.15)
				)
				(justify mirror)
			)
		)
		(property "License" "Apache-2.0"
			(at 58.966 310.634 0)
			(layer "B.Fab")
			(hide yes)
			(effects
				(font
					(size 1 1)
					(thickness 0.15)
				)
				(justify mirror)
			)
		)
		(property "MPN" "C1005X6S1A105K050BC"
			(at 58.966 310.634 0)
			(layer "B.Fab")
			(hide yes)
			(effects
				(font
					(size 1 1)
					(thickness 0.15)
				)
				(justify mirror)
			)
		)
		(property "Manufacturer" "TDK"
			(at 58.966 310.634 0)
			(layer "B.Fab")
			(hide yes)
			(effects
				(font
					(size 1 1)
					(thickness 0.15)
				)
				(justify mirror)
			)
		)
		(property "Public" ""
			(at 58.966 310.634 0)
			(layer "B.Fab")
			(hide yes)
			(effects
				(font
					(size 1 1)
					(thickness 0.15)
				)
				(justify mirror)
			)
		)
		(property "Val" "1u"
			(at 58.966 310.634 0)
			(layer "B.Fab")
			(hide yes)
			(effects
				(font
					(size 1 1)
					(thickness 0.15)
				)
				(justify mirror)
			)
		)
		(property "Voltage" "16V"
			(at 58.966 310.634 0)
			(layer "B.Fab")
			(hide yes)
			(effects
				(font
					(size 1 1)
					(thickness 0.15)
				)
				(justify mirror)
			)
		)
		(sheetname "/LPDDR4/")
		(sheetfile "lpddr.kicad_sch")
		(attr smd)
		(fp_rect
			(start -0.925 0.47)
			(end 0.925 -0.47)
			(stroke
				(width 0.05)
				(type default)
			)
			(fill no)
			(layer "B.CrtYd")
		)
		(fp_line
			(start -0.494 0.25)
			(end 0.504 0.25)
			(stroke
				(width 0.15)
				(type solid)
			)
			(layer "B.Fab")
		)
		(fp_line
			(start 0.504 0.25)
			(end 0.504 -0.248)
			(stroke
				(width 0.15)
				(type solid)
			)
			(layer "B.Fab")
		)
		(fp_line
			(start -0.494 -0.248)
			(end -0.494 0.25)
			(stroke
				(width 0.15)
				(type solid)
			)
			(layer "B.Fab")
		)
		(fp_line
			(start 0.504 -0.248)
			(end -0.494 -0.248)
			(stroke
				(width 0.15)
				(type solid)
			)
			(layer "B.Fab")
		)
		(fp_text user "License: Apache-2.0"
			(at -0.939 -5.799 90)
			(layer "B.Fab")
			(effects
				(font
					(size 0.7 0.7)
					(thickness 0.15)
				)
				(justify left bottom mirror)
			)
		)
		(fp_text user "${REFERENCE}"
			(at -0.939 -4.599 90)
			(layer "B.Fab")
			(effects
				(font
					(size 0.7 0.7)
					(thickness 0.15)
				)
				(justify left bottom mirror)
			)
		)
		(fp_text user "Author: Antmicro"
			(at -0.939 -3.399 90)
			(layer "B.Fab")
			(effects
				(font
					(size 0.7 0.7)
					(thickness 0.15)
				)
				(justify left bottom mirror)
			)
		)
		(pad "1" smd roundrect
			(at -0.48 0 270)
			(size 0.59 0.64)
			(layers "B.Cu" "B.Mask" "B.Paste")
			(roundrect_rratio 0.25)
			(net 417 "GND")
			(pintype "passive")
		)
		(pad "2" smd roundrect
			(at 0.48 0 270)
			(size 0.59 0.64)
			(layers "B.Cu" "B.Mask" "B.Paste")
			(roundrect_rratio 0.25)
			(net 48 "+1V8")
			(pintype "passive")
		)
	)
	(footprint "antmicro-footprints:C_0402_1005Metric"
		(layer "B.Cu")
		(at 181.1 140.9875 180)
		(descr "Capacitor SMD 0402")
		(tags "capacitor SMD 0402")
		(property "Reference" "C86"
			(at -11.175 -9.8375 180)
			(layer "B.SilkS")
			(effects
				(font
					(size 0.7 0.7)
					(thickness 0.15)
				)
				(justify left bottom mirror)
			)
		)
		(property "Value" "C_22u_0402"
			(at -1.022927 -2.155213 0)
			(layer "B.Fab")
			(hide yes)
			(effects
				(font
					(size 0.7 0.7)
					(thickness 0.15)
				)
				(justify left bottom mirror)
			)
		)
		(property "Datasheet" "https://www.murata.com/products/productdetail?partno=GRM158R60J226ME01%23"
			(at 0 0 180)
			(layer "F.Fab")
			(hide yes)
			(effects
				(font
					(size 1.27 1.27)
					(thickness 0.15)
				)
			)
		)
		(property "Description" "SMD Multilayer Ceramic Capacitor, 22 uF, 4 V, 0402 [1005 Metric], X6S"
			(at 0 0 180)
			(layer "F.Fab")
			(hide yes)
			(effects
				(font
					(size 1.27 1.27)
					(thickness 0.15)
				)
			)
		)
		(property "Author" "Antmicro"
			(at 362.2 281.975 0)
			(layer "B.Fab")
			(hide yes)
			(effects
				(font
					(size 1 1)
					(thickness 0.15)
				)
				(justify mirror)
			)
		)
		(property "Dielectric" ""
			(at 362.2 281.975 0)
			(layer "B.Fab")
			(hide yes)
			(effects
				(font
					(size 1 1)
					(thickness 0.15)
				)
				(justify mirror)
			)
		)
		(property "License" "Apache-2.0"
			(at 362.2 281.975 0)
			(layer "B.Fab")
			(hide yes)
			(effects
				(font
					(size 1 1)
					(thickness 0.15)
				)
				(justify mirror)
			)
		)
		(property "MPN" "GRM158R60J226ME01D"
			(at 362.2 281.975 0)
			(layer "B.Fab")
			(hide yes)
			(effects
				(font
					(size 1 1)
					(thickness 0.15)
				)
				(justify mirror)
			)
		)
		(property "Manufacturer" "Murata"
			(at 362.2 281.975 0)
			(layer "B.Fab")
			(hide yes)
			(effects
				(font
					(size 1 1)
					(thickness 0.15)
				)
				(justify mirror)
			)
		)
		(property "Public" ""
			(at 362.2 281.975 0)
			(layer "B.Fab")
			(hide yes)
			(effects
				(font
					(size 1 1)
					(thickness 0.15)
				)
				(justify mirror)
			)
		)
		(property "Val" "22u"
			(at 362.2 281.975 0)
			(layer "B.Fab")
			(hide yes)
			(effects
				(font
					(size 1 1)
					(thickness 0.15)
				)
				(justify mirror)
			)
		)
		(property "Voltage" ""
			(at 362.2 281.975 0)
			(layer "B.Fab")
			(hide yes)
			(effects
				(font
					(size 1 1)
					(thickness 0.15)
				)
				(justify mirror)
			)
		)
		(sheetname "/Supply/")
		(sheetfile "supply.kicad_sch")
		(attr smd)
		(fp_rect
			(start -0.925 0.47)
			(end 0.925 -0.47)
			(stroke
				(width 0.05)
				(type default)
			)
			(fill no)
			(layer "B.CrtYd")
		)
		(fp_line
			(start 0.504 0.25)
			(end 0.504 -0.248)
			(stroke
				(width 0.15)
				(type solid)
			)
			(layer "B.Fab")
		)
		(fp_line
			(start 0.504 -0.248)
			(end -0.494 -0.248)
			(stroke
				(width 0.15)
				(type solid)
			)
			(layer "B.Fab")
		)
		(fp_line
			(start -0.494 0.25)
			(end 0.504 0.25)
			(stroke
				(width 0.15)
				(type solid)
			)
			(layer "B.Fab")
		)
		(fp_line
			(start -0.494 -0.248)
			(end -0.494 0.25)
			(stroke
				(width 0.15)
				(type solid)
			)
			(layer "B.Fab")
		)
		(fp_text user "Author: Antmicro"
			(at -0.939 -3.399 0)
			(layer "B.Fab")
			(effects
				(font
					(size 0.7 0.7)
					(thickness 0.15)
				)
				(justify left bottom mirror)
			)
		)
		(fp_text user "${REFERENCE}"
			(at -0.939 -4.599 0)
			(layer "B.Fab")
			(effects
				(font
					(size 0.7 0.7)
					(thickness 0.15)
				)
				(justify left bottom mirror)
			)
		)
		(fp_text user "License: Apache-2.0"
			(at -0.939 -5.799 0)
			(layer "B.Fab")
			(effects
				(font
					(size 0.7 0.7)
					(thickness 0.15)
				)
				(justify left bottom mirror)
			)
		)
		(pad "1" smd roundrect
			(at -0.48 0 180)
			(size 0.59 0.64)
			(layers "B.Cu" "B.Mask" "B.Paste")
			(roundrect_rratio 0.25)
			(net 417 "GND")
			(pintype "passive")
		)
		(pad "2" smd roundrect
			(at 0.48 0 180)
			(size 0.59 0.64)
			(layers "B.Cu" "B.Mask" "B.Paste")
			(roundrect_rratio 0.25)
			(net 90 "+5V")
			(pintype "passive")
		)
	)
	(footprint "antmicro-footprints:C_0402_1005Metric"
		(layer "B.Cu")
		(at 191.25 139.15 135)
		(descr "Capacitor SMD 0402")
		(tags "capacitor SMD 0402")
		(property "Reference" "C61"
			(at 3.464823 -0.883883 135)
			(layer "B.SilkS")
			(effects
				(font
					(size 0.7 0.7)
					(thickness 0.15)
				)
				(justify right bottom mirror)
			)
		)
		(property "Value" "C_100n_0402"
			(at -1.022927 -2.155213 135)
			(layer "B.Fab")
			(hide yes)
			(effects
				(font
					(size 0.7 0.7)
					(thickness 0.15)
				)
				(justify right bottom mirror)
			)
		)
		(property "Datasheet" "https://www.murata.com/products/productdetail?partno=GRM155R61H104KE14%23"
			(at 0 0 135)
			(layer "F.Fab")
			(hide yes)
			(effects
				(font
					(size 1.27 1.27)
					(thickness 0.15)
				)
			)
		)
		(property "Description" "SMD Multilayer Ceramic Capacitor, 0.1 µF, 50 V, 0402 [1005 Metric], ± 10%, X5R, GRM Series"
			(at 0 0 135)
			(layer "F.Fab")
			(hide yes)
			(effects
				(font
					(size 1.27 1.27)
					(thickness 0.15)
				)
			)
		)
		(property "Author" "Antmicro"
			(at 424.878081 102.309737 0)
			(layer "B.Fab")
			(hide yes)
			(effects
				(font
					(size 1 1)
					(thickness 0.15)
				)
				(justify mirror)
			)
		)
		(property "Dielectric" "X5R"
			(at 424.878081 102.309737 0)
			(layer "B.Fab")
			(hide yes)
			(effects
				(font
					(size 1 1)
					(thickness 0.15)
				)
				(justify mirror)
			)
		)
		(property "License" "Apache-2.0"
			(at 424.878081 102.309737 0)
			(layer "B.Fab")
			(hide yes)
			(effects
				(font
					(size 1 1)
					(thickness 0.15)
				)
				(justify mirror)
			)
		)
		(property "MPN" "GRM155R61H104KE14D"
			(at 424.878081 102.309737 0)
			(layer "B.Fab")
			(hide yes)
			(effects
				(font
					(size 1 1)
					(thickness 0.15)
				)
				(justify mirror)
			)
		)
		(property "Manufacturer" "Murata"
			(at 424.878081 102.309737 0)
			(layer "B.Fab")
			(hide yes)
			(effects
				(font
					(size 1 1)
					(thickness 0.15)
				)
				(justify mirror)
			)
		)
		(property "Public" ""
			(at 424.878081 102.309737 0)
			(layer "B.Fab")
			(hide yes)
			(effects
				(font
					(size 1 1)
					(thickness 0.15)
				)
				(justify mirror)
			)
		)
		(property "Val" "100n"
			(at 424.878081 102.309737 0)
			(layer "B.Fab")
			(hide yes)
			(effects
				(font
					(size 1 1)
					(thickness 0.15)
				)
				(justify mirror)
			)
		)
		(property "Voltage" "50V"
			(at 424.878081 102.309737 0)
			(layer "B.Fab")
			(hide yes)
			(effects
				(font
					(size 1 1)
					(thickness 0.15)
				)
				(justify mirror)
			)
		)
		(sheetname "/FPGA Supply/")
		(sheetfile "fpga-supply.kicad_sch")
		(attr smd)
		(fp_poly
			(pts
				(xy -0.925 0.47) (xy 0.925 0.47) (xy 0.925 -0.47) (xy -0.925 -0.47)
			)
			(stroke
				(width 0.05)
				(type default)
			)
			(fill no)
			(layer "B.CrtYd")
		)
		(fp_line
			(start 0.504 -0.248)
			(end -0.494 -0.248)
			(stroke
				(width 0.15)
				(type solid)
			)
			(layer "B.Fab")
		)
		(fp_line
			(start 0.504 0.25)
			(end 0.504 -0.248)
			(stroke
				(width 0.15)
				(type solid)
			)
			(layer "B.Fab")
		)
		(fp_line
			(start -0.494 -0.248)
			(end -0.494 0.25)
			(stroke
				(width 0.15)
				(type solid)
			)
			(layer "B.Fab")
		)
		(fp_line
			(start -0.494 0.25)
			(end 0.504 0.25)
			(stroke
				(width 0.15)
				(type solid)
			)
			(layer "B.Fab")
		)
		(fp_text user "Author: Antmicro"
			(at -0.939 -3.399 315)
			(layer "B.Fab")
			(effects
				(font
					(size 0.7 0.7)
					(thickness 0.15)
				)
				(justify left bottom mirror)
			)
		)
		(fp_text user "${REFERENCE}"
			(at -0.939 -4.599 315)
			(layer "B.Fab")
			(effects
				(font
					(size 0.7 0.7)
					(thickness 0.15)
				)
				(justify left bottom mirror)
			)
		)
		(fp_text user "License: Apache-2.0"
			(at -0.939 -5.799 315)
			(layer "B.Fab")
			(effects
				(font
					(size 0.7 0.7)
					(thickness 0.15)
				)
				(justify left bottom mirror)
			)
		)
		(pad "1" smd roundrect
			(at -0.48 0 135)
			(size 0.59 0.64)
			(layers "B.Cu" "B.Mask" "B.Paste")
			(roundrect_rratio 0.25)
			(net 417 "GND")
			(pintype "passive")
		)
		(pad "2" smd roundrect
			(at 0.48 0 135)
			(size 0.59 0.64)
			(layers "B.Cu" "B.Mask" "B.Paste")
			(roundrect_rratio 0.25)
			(net 48 "+1V8")
			(pintype "passive")
		)
	)
	(footprint "antmicro-footprints:C_0402_1005Metric"
		(layer "B.Cu")
		(at 199.89 130.85 90)
		(descr "Capacitor SMD 0402")
		(tags "capacitor SMD 0402")
		(property "Reference" "C58"
			(at 8.025 -9.565 270)
			(layer "B.SilkS")
			(effects
				(font
					(size 0.7 0.7)
					(thickness 0.15)
				)
				(justify left bottom mirror)
			)
		)
		(property "Value" "C_10n_0402"
			(at -1.022927 -2.155213 270)
			(layer "B.Fab")
			(hide yes)
			(effects
				(font
					(size 0.7 0.7)
					(thickness 0.15)
				)
				(justify left bottom mirror)
			)
		)
		(property "Datasheet" "https://www.murata.com/products/productdetail?partno=GRM155R71H103KA88%23"
			(at 0 0 90)
			(layer "F.Fab")
			(hide yes)
			(effects
				(font
					(size 1.27 1.27)
					(thickness 0.15)
				)
			)
		)
		(property "Description" "SMD Multilayer Ceramic Capacitor, 10000 pF, 50 V, 0402 [1005 Metric], ± 10%, X7R, GRM Series"
			(at 0 0 90)
			(layer "F.Fab")
			(hide yes)
			(effects
				(font
					(size 1.27 1.27)
					(thickness 0.15)
				)
			)
		)
		(property "Author" "Antmicro"
			(at 330.74 -69.04 0)
			(layer "B.Fab")
			(hide yes)
			(effects
				(font
					(size 1 1)
					(thickness 0.15)
				)
				(justify mirror)
			)
		)
		(property "Dielectric" "X7R"
			(at 330.74 -69.04 0)
			(layer "B.Fab")
			(hide yes)
			(effects
				(font
					(size 1 1)
					(thickness 0.15)
				)
				(justify mirror)
			)
		)
		(property "License" "Apache-2.0"
			(at 330.74 -69.04 0)
			(layer "B.Fab")
			(hide yes)
			(effects
				(font
					(size 1 1)
					(thickness 0.15)
				)
				(justify mirror)
			)
		)
		(property "MPN" "GRM155R71H103KA88D"
			(at 330.74 -69.04 0)
			(layer "B.Fab")
			(hide yes)
			(effects
				(font
					(size 1 1)
					(thickness 0.15)
				)
				(justify mirror)
			)
		)
		(property "Manufacturer" "Murata"
			(at 330.74 -69.04 0)
			(layer "B.Fab")
			(hide yes)
			(effects
				(font
					(size 1 1)
					(thickness 0.15)
				)
				(justify mirror)
			)
		)
		(property "Public" ""
			(at 330.74 -69.04 0)
			(layer "B.Fab")
			(hide yes)
			(effects
				(font
					(size 1 1)
					(thickness 0.15)
				)
				(justify mirror)
			)
		)
		(property "Val" "10n"
			(at 330.74 -69.04 0)
			(layer "B.Fab")
			(hide yes)
			(effects
				(font
					(size 1 1)
					(thickness 0.15)
				)
				(justify mirror)
			)
		)
		(property "Voltage" "50V"
			(at 330.74 -69.04 0)
			(layer "B.Fab")
			(hide yes)
			(effects
				(font
					(size 1 1)
					(thickness 0.15)
				)
				(justify mirror)
			)
		)
		(sheetname "/FPGA Supply/")
		(sheetfile "fpga-supply.kicad_sch")
		(attr smd)
		(fp_rect
			(start -0.925 0.47)
			(end 0.925 -0.47)
			(stroke
				(width 0.05)
				(type default)
			)
			(fill no)
			(layer "B.CrtYd")
		)
		(fp_line
			(start 0.504 -0.248)
			(end -0.494 -0.248)
			(stroke
				(width 0.15)
				(type solid)
			)
			(layer "B.Fab")
		)
		(fp_line
			(start -0.494 -0.248)
			(end -0.494 0.25)
			(stroke
				(width 0.15)
				(type solid)
			)
			(layer "B.Fab")
		)
		(fp_line
			(start 0.504 0.25)
			(end 0.504 -0.248)
			(stroke
				(width 0.15)
				(type solid)
			)
			(layer "B.Fab")
		)
		(fp_line
			(start -0.494 0.25)
			(end 0.504 0.25)
			(stroke
				(width 0.15)
				(type solid)
			)
			(layer "B.Fab")
		)
		(fp_text user "License: Apache-2.0"
			(at -0.939 -5.799 270)
			(layer "B.Fab")
			(effects
				(font
					(size 0.7 0.7)
					(thickness 0.15)
				)
				(justify left bottom mirror)
			)
		)
		(fp_text user "Author: Antmicro"
			(at -0.939 -3.399 270)
			(layer "B.Fab")
			(effects
				(font
					(size 0.7 0.7)
					(thickness 0.15)
				)
				(justify left bottom mirror)
			)
		)
		(fp_text user "${REFERENCE}"
			(at -0.939 -4.599 270)
			(layer "B.Fab")
			(effects
				(font
					(size 0.7 0.7)
					(thickness 0.15)
				)
				(justify left bottom mirror)
			)
		)
		(pad "1" smd roundrect
			(at -0.48 0 90)
			(size 0.59 0.64)
			(layers "B.Cu" "B.Mask" "B.Paste")
			(roundrect_rratio 0.25)
			(net 417 "GND")
			(pintype "passive")
		)
		(pad "2" smd roundrect
			(at 0.48 0 90)
			(size 0.59 0.64)
			(layers "B.Cu" "B.Mask" "B.Paste")
			(roundrect_rratio 0.25)
			(net 49 "VDDAUX")
			(pintype "passive")
		)
	)
	(footprint "antmicro-footprints:TP_SMD_0.75mm"
		(layer "B.Cu")
		(at 185.4 146 180)
		(property "Reference" "TP22"
			(at 1.35 -1.475 45)
			(layer "B.SilkS")
			(hide yes)
			(effects
				(font
					(size 0.7 0.7)
					(thickness 0.15)
				)
				(justify left bottom mirror)
			)
		)
		(property "Value" "TP_0.75mm_SMD"
			(at 0 -1.2 0)
			(layer "B.Fab")
			(hide yes)
			(effects
				(font
					(size 0.7 0.7)
					(thickness 0.15)
				)
				(justify left bottom mirror)
			)
		)
		(property "Description" "SMT test point"
			(at 0 0 0)
			(layer "B.Fab")
			(hide yes)
			(effects
				(font
					(size 1.27 1.27)
					(thickness 0.15)
				)
				(justify mirror)
			)
		)
		(property "MPN" ""
			(at 0 0 0)
			(unlocked yes)
			(layer "B.Fab")
			(hide yes)
			(effects
				(font
					(size 1 1)
					(thickness 0.15)
				)
				(justify mirror)
			)
		)
		(property "Manufacturer" ""
			(at 0 0 0)
			(unlocked yes)
			(layer "B.Fab")
			(hide yes)
			(effects
				(font
					(size 1 1)
					(thickness 0.15)
				)
				(justify mirror)
			)
		)
		(property "Author" "Antmicro"
			(at 0 0 0)
			(unlocked yes)
			(layer "B.Fab")
			(hide yes)
			(effects
				(font
					(size 1 1)
					(thickness 0.15)
				)
				(justify mirror)
			)
		)
		(property "License" "Apache-2.0"
			(at 0 0 0)
			(unlocked yes)
			(layer "B.Fab")
			(hide yes)
			(effects
				(font
					(size 1 1)
					(thickness 0.15)
				)
				(justify mirror)
			)
		)
		(property "Public" "False"
			(at 0 0 0)
			(unlocked yes)
			(layer "B.Fab")
			(hide yes)
			(effects
				(font
					(size 1 1)
					(thickness 0.15)
				)
				(justify mirror)
			)
		)
		(sheetname "/Supply/")
		(sheetfile "supply.kicad_sch")
		(attr exclude_from_pos_files exclude_from_bom)
		(fp_circle
			(center 0 0)
			(end 0.475 0)
			(stroke
				(width 0.05)
				(type default)
			)
			(fill no)
			(layer "B.CrtYd")
		)
		(fp_text user "${REFERENCE}"
			(at -0.4 -2.7 0)
			(layer "B.Fab")
			(effects
				(font
					(size 0.7 0.7)
					(thickness 0.15)
				)
				(justify left bottom mirror)
			)
		)
		(fp_text user "Author: Antmicro"
			(at -0.4 -3.901 0)
			(layer "B.Fab")
			(effects
				(font
					(size 0.7 0.7)
					(thickness 0.15)
				)
				(justify left bottom mirror)
			)
		)
		(fp_text user "License: Apache-2.0"
			(at -0.4 -5.101 0)
			(layer "B.Fab")
			(effects
				(font
					(size 0.7 0.7)
					(thickness 0.15)
				)
				(justify left bottom mirror)
			)
		)
		(pad "1" smd circle
			(at 0 0 180)
			(size 0.75 0.75)
			(layers "B.Cu" "B.Mask")
			(net 634 "Net-(U7-OUT5)")
			(pinfunction "1")
			(pintype "passive")
		)
	)
	(footprint "antmicro-footprints:C_0402_1005Metric"
		(layer "B.Cu")
		(at 213.861 117.754 180)
		(descr "Capacitor SMD 0402")
		(tags "capacitor SMD 0402")
		(property "Reference" "C251"
			(at 24.711 -18.121 0)
			(layer "B.SilkS")
			(effects
				(font
					(size 0.7 0.7)
					(thickness 0.15)
				)
				(justify left bottom mirror)
			)
		)
		(property "Value" "C_1u_0402"
			(at -1.022927 -2.155213 0)
			(layer "B.Fab")
			(hide yes)
			(effects
				(font
					(size 0.7 0.7)
					(thickness 0.15)
				)
				(justify left bottom mirror)
			)
		)
		(property "Datasheet" "https://product.tdk.com/en/search/capacitor/ceramic/mlcc/info?part_no=C1005X6S1A105K050BC"
			(at 0 0 180)
			(layer "F.Fab")
			(hide yes)
			(effects
				(font
					(size 1.27 1.27)
					(thickness 0.15)
				)
			)
		)
		(property "Description" "SMD Multilayer Ceramic Capacitor, 1 µF, 10 V, 0402 [1005 Metric], ± 10%, X6S, C"
			(at 0 0 180)
			(layer "F.Fab")
			(hide yes)
			(effects
				(font
					(size 1.27 1.27)
					(thickness 0.15)
				)
			)
		)
		(property "Author" "Antmicro"
			(at 427.722 235.508 0)
			(layer "B.Fab")
			(hide yes)
			(effects
				(font
					(size 1 1)
					(thickness 0.15)
				)
				(justify mirror)
			)
		)
		(property "Dielectric" ""
			(at 427.722 235.508 0)
			(layer "B.Fab")
			(hide yes)
			(effects
				(font
					(size 1 1)
					(thickness 0.15)
				)
				(justify mirror)
			)
		)
		(property "License" "Apache-2.0"
			(at 427.722 235.508 0)
			(layer "B.Fab")
			(hide yes)
			(effects
				(font
					(size 1 1)
					(thickness 0.15)
				)
				(justify mirror)
			)
		)
		(property "MPN" "C1005X6S1A105K050BC"
			(at 427.722 235.508 0)
			(layer "B.Fab")
			(hide yes)
			(effects
				(font
					(size 1 1)
					(thickness 0.15)
				)
				(justify mirror)
			)
		)
		(property "Manufacturer" "TDK"
			(at 427.722 235.508 0)
			(layer "B.Fab")
			(hide yes)
			(effects
				(font
					(size 1 1)
					(thickness 0.15)
				)
				(justify mirror)
			)
		)
		(property "Public" ""
			(at 427.722 235.508 0)
			(layer "B.Fab")
			(hide yes)
			(effects
				(font
					(size 1 1)
					(thickness 0.15)
				)
				(justify mirror)
			)
		)
		(property "Val" "1u"
			(at 427.722 235.508 0)
			(layer "B.Fab")
			(hide yes)
			(effects
				(font
					(size 1 1)
					(thickness 0.15)
				)
				(justify mirror)
			)
		)
		(property "Voltage" ""
			(at 427.722 235.508 0)
			(layer "B.Fab")
			(hide yes)
			(effects
				(font
					(size 1 1)
					(thickness 0.15)
				)
				(justify mirror)
			)
		)
		(sheetname "/Ethernet/")
		(sheetfile "ethernet.kicad_sch")
		(attr smd)
		(fp_rect
			(start -0.925 0.47)
			(end 0.925 -0.47)
			(stroke
				(width 0.05)
				(type default)
			)
			(fill no)
			(layer "B.CrtYd")
		)
		(fp_line
			(start 0.504 0.25)
			(end 0.504 -0.248)
			(stroke
				(width 0.15)
				(type solid)
			)
			(layer "B.Fab")
		)
		(fp_line
			(start 0.504 -0.248)
			(end -0.494 -0.248)
			(stroke
				(width 0.15)
				(type solid)
			)
			(layer "B.Fab")
		)
		(fp_line
			(start -0.494 0.25)
			(end 0.504 0.25)
			(stroke
				(width 0.15)
				(type solid)
			)
			(layer "B.Fab")
		)
		(fp_line
			(start -0.494 -0.248)
			(end -0.494 0.25)
			(stroke
				(width 0.15)
				(type solid)
			)
			(layer "B.Fab")
		)
		(fp_text user "Author: Antmicro"
			(at -0.939 -3.399 0)
			(layer "B.Fab")
			(effects
				(font
					(size 0.7 0.7)
					(thickness 0.15)
				)
				(justify left bottom mirror)
			)
		)
		(fp_text user "${REFERENCE}"
			(at -0.939 -4.599 0)
			(layer "B.Fab")
			(effects
				(font
					(size 0.7 0.7)
					(thickness 0.15)
				)
				(justify left bottom mirror)
			)
		)
		(fp_text user "License: Apache-2.0"
			(at -0.939 -5.799 0)
			(layer "B.Fab")
			(effects
				(font
					(size 0.7 0.7)
					(thickness 0.15)
				)
				(justify left bottom mirror)
			)
		)
		(pad "1" smd roundrect
			(at -0.48 0 180)
			(size 0.59 0.64)
			(layers "B.Cu" "B.Mask" "B.Paste")
			(roundrect_rratio 0.25)
			(net 417 "GND")
			(pintype "passive")
		)
		(pad "2" smd roundrect
			(at 0.48 0 180)
			(size 0.59 0.64)
			(layers "B.Cu" "B.Mask" "B.Paste")
			(roundrect_rratio 0.25)
			(net 47 "+1V05")
			(pintype "passive")
		)
	)
	(footprint "antmicro-footprints:Fiducial_1mm_Mask2mm"
		(layer "B.Cu")
		(at 228.7 150.5 180)
		(descr "Circular Fiducial, 1mm bare copper, 3mm soldermask opening")
		(tags "fiducial")
		(property "Reference" "FD2"
			(at 0 1.4 0)
			(layer "B.SilkS")
			(hide yes)
			(effects
				(font
					(size 0.7 0.7)
					(thickness 0.15)
				)
				(justify left bottom mirror)
			)
		)
		(property "Value" "Fiducial_1mm_Mask2mm"
			(at 0 -2.2 0)
			(layer "B.Fab")
			(hide yes)
			(effects
				(font
					(size 0.7 0.7)
					(thickness 0.15)
				)
				(justify left bottom mirror)
			)
		)
		(property "Description" "Fiducial mask "
			(at 0 0 180)
			(layer "F.Fab")
			(hide yes)
			(effects
				(font
					(size 1.27 1.27)
					(thickness 0.15)
				)
			)
		)
		(property "Author" "Antmicro"
			(at 457.4 301 0)
			(layer "B.Fab")
			(hide yes)
			(effects
				(font
					(size 1 1)
					(thickness 0.15)
				)
				(justify mirror)
			)
		)
		(property "License" "Apache-2.0"
			(at 457.4 301 0)
			(layer "B.Fab")
			(hide yes)
			(effects
				(font
					(size 1 1)
					(thickness 0.15)
				)
				(justify mirror)
			)
		)
		(property "exclude_from_bom" ""
			(at 457.4 301 0)
			(layer "B.Fab")
			(hide yes)
			(effects
				(font
					(size 1 1)
					(thickness 0.15)
				)
				(justify mirror)
			)
		)
		(sheetfile "polarfire-som.kicad_sch")
		(attr board_only exclude_from_pos_files exclude_from_bom)
		(fp_circle
			(center 0 0)
			(end 1.24 0)
			(stroke
				(width 0.05)
				(type solid)
			)
			(fill no)
			(layer "B.CrtYd")
		)
		(fp_circle
			(center 0 0)
			(end 0.999 0)
			(stroke
				(width 0.15)
				(type solid)
			)
			(fill no)
			(layer "B.Fab")
		)
		(fp_text user "${REFERENCE}"
			(at -1.25 -4.603 0)
			(layer "B.Fab")
			(effects
				(font
					(size 0.7 0.7)
					(thickness 0.15)
				)
				(justify left bottom mirror)
			)
		)
		(fp_text user "Author: Antmicro"
			(at -1.25 -5.803 0)
			(layer "B.Fab")
			(effects
				(font
					(size 0.7 0.7)
					(thickness 0.15)
				)
				(justify left bottom mirror)
			)
		)
		(fp_text user "License: Apache-2.0"
			(at -1.25 -7.003 0)
			(layer "B.Fab")
			(effects
				(font
					(size 0.7 0.7)
					(thickness 0.15)
				)
				(justify left bottom mirror)
			)
		)
		(pad "" smd circle
			(at 0 0 180)
			(size 1 1)
			(layers "B.Cu" "B.Mask")
			(solder_mask_margin 0.5)
			(clearance 0.5)
		)
	)
	(footprint "antmicro-footprints:C_0402_1005Metric"
		(layer "B.Cu")
		(at 219.911 117.704)
		(descr "Capacitor SMD 0402")
		(tags "capacitor SMD 0402")
		(property "Reference" "C194"
			(at 6.539 4.446 0)
			(layer "B.SilkS")
			(effects
				(font
					(size 0.7 0.7)
					(thickness 0.15)
				)
				(justify right bottom mirror)
			)
		)
		(property "Value" "C_1u_0402"
			(at -1.022927 -2.155213 0)
			(layer "B.Fab")
			(hide yes)
			(effects
				(font
					(size 0.7 0.7)
					(thickness 0.15)
				)
				(justify right bottom mirror)
			)
		)
		(property "Datasheet" "https://product.tdk.com/en/search/capacitor/ceramic/mlcc/info?part_no=C1005X6S1A105K050BC"
			(at 0 0 0)
			(layer "F.Fab")
			(hide yes)
			(effects
				(font
					(size 1.27 1.27)
					(thickness 0.15)
				)
			)
		)
		(property "Description" "SMD Multilayer Ceramic Capacitor, 1 µF, 10 V, 0402 [1005 Metric], ± 10%, X6S, C"
			(at 0 0 0)
			(layer "F.Fab")
			(hide yes)
			(effects
				(font
					(size 1.27 1.27)
					(thickness 0.15)
				)
			)
		)
		(property "Author" "Antmicro"
			(at 0 0 0)
			(layer "B.Fab")
			(hide yes)
			(effects
				(font
					(size 1 1)
					(thickness 0.15)
				)
				(justify mirror)
			)
		)
		(property "Dielectric" ""
			(at 0 0 0)
			(layer "B.Fab")
			(hide yes)
			(effects
				(font
					(size 1 1)
					(thickness 0.15)
				)
				(justify mirror)
			)
		)
		(property "License" "Apache-2.0"
			(at 0 0 0)
			(layer "B.Fab")
			(hide yes)
			(effects
				(font
					(size 1 1)
					(thickness 0.15)
				)
				(justify mirror)
			)
		)
		(property "MPN" "C1005X6S1A105K050BC"
			(at 0 0 0)
			(layer "B.Fab")
			(hide yes)
			(effects
				(font
					(size 1 1)
					(thickness 0.15)
				)
				(justify mirror)
			)
		)
		(property "Manufacturer" "TDK"
			(at 0 0 0)
			(layer "B.Fab")
			(hide yes)
			(effects
				(font
					(size 1 1)
					(thickness 0.15)
				)
				(justify mirror)
			)
		)
		(property "Public" ""
			(at 0 0 0)
			(layer "B.Fab")
			(hide yes)
			(effects
				(font
					(size 1 1)
					(thickness 0.15)
				)
				(justify mirror)
			)
		)
		(property "Val" "1u"
			(at 0 0 0)
			(layer "B.Fab")
			(hide yes)
			(effects
				(font
					(size 1 1)
					(thickness 0.15)
				)
				(justify mirror)
			)
		)
		(property "Voltage" ""
			(at 0 0 0)
			(layer "B.Fab")
			(hide yes)
			(effects
				(font
					(size 1 1)
					(thickness 0.15)
				)
				(justify mirror)
			)
		)
		(sheetname "/Ethernet/")
		(sheetfile "ethernet.kicad_sch")
		(attr smd)
		(fp_rect
			(start -0.925 0.47)
			(end 0.925 -0.47)
			(stroke
				(width 0.05)
				(type default)
			)
			(fill no)
			(layer "B.CrtYd")
		)
		(fp_line
			(start -0.494 -0.248)
			(end -0.494 0.25)
			(stroke
				(width 0.15)
				(type solid)
			)
			(layer "B.Fab")
		)
		(fp_line
			(start -0.494 0.25)
			(end 0.504 0.25)
			(stroke
				(width 0.15)
				(type solid)
			)
			(layer "B.Fab")
		)
		(fp_line
			(start 0.504 -0.248)
			(end -0.494 -0.248)
			(stroke
				(width 0.15)
				(type solid)
			)
			(layer "B.Fab")
		)
		(fp_line
			(start 0.504 0.25)
			(end 0.504 -0.248)
			(stroke
				(width 0.15)
				(type solid)
			)
			(layer "B.Fab")
		)
		(fp_text user "Author: Antmicro"
			(at -0.939 -3.399 180)
			(layer "B.Fab")
			(effects
				(font
					(size 0.7 0.7)
					(thickness 0.15)
				)
				(justify left bottom mirror)
			)
		)
		(fp_text user "${REFERENCE}"
			(at -0.939 -4.599 180)
			(layer "B.Fab")
			(effects
				(font
					(size 0.7 0.7)
					(thickness 0.15)
				)
				(justify left bottom mirror)
			)
		)
		(fp_text user "License: Apache-2.0"
			(at -0.939 -5.799 180)
			(layer "B.Fab")
			(effects
				(font
					(size 0.7 0.7)
					(thickness 0.15)
				)
				(justify left bottom mirror)
			)
		)
		(pad "1" smd roundrect
			(at -0.48 0)
			(size 0.59 0.64)
			(layers "B.Cu" "B.Mask" "B.Paste")
			(roundrect_rratio 0.25)
			(net 417 "GND")
			(pintype "passive")
		)
		(pad "2" smd roundrect
			(at 0.48 0)
			(size 0.59 0.64)
			(layers "B.Cu" "B.Mask" "B.Paste")
			(roundrect_rratio 0.25)
			(net 418 "+2V5")
			(pintype "passive")
		)
	)
	(footprint "antmicro-footprints:C_0603_1608Metric"
		(layer "B.Cu")
		(at 191.7 126.88 -90)
		(descr "Capacitor SMD 0603")
		(tags "capacitor 0603")
		(property "Reference" "C21"
			(at -0.255 -1.5 90)
			(layer "B.SilkS")
			(effects
				(font
					(size 0.7 0.7)
					(thickness 0.15)
				)
				(justify left bottom mirror)
			)
		)
		(property "Value" "C_47u_0603"
			(at -1.42757 -1.770288 90)
			(layer "B.Fab")
			(hide yes)
			(effects
				(font
					(size 0.7 0.7)
					(thickness 0.15)
				)
				(justify left bottom mirror)
			)
		)
		(property "Datasheet" "https://www.murata.com/products/productdetail?partno=GRM188R60J476ME15%23"
			(at 0 0 270)
			(layer "F.Fab")
			(hide yes)
			(effects
				(font
					(size 1.27 1.27)
					(thickness 0.15)
				)
			)
		)
		(property "Description" "SMD Multilayer Ceramic Capacitor, 47 µF, 6.3 V, 0603 [1608 Metric], ± 20%, X5R, GRM Series"
			(at 0 0 270)
			(layer "F.Fab")
			(hide yes)
			(effects
				(font
					(size 1.27 1.27)
					(thickness 0.15)
				)
			)
		)
		(property "Author" "Antmicro"
			(at 64.82 318.58 0)
			(layer "B.Fab")
			(hide yes)
			(effects
				(font
					(size 1 1)
					(thickness 0.15)
				)
				(justify mirror)
			)
		)
		(property "Capacitance" "47u"
			(at 64.82 318.58 0)
			(layer "B.Fab")
			(hide yes)
			(effects
				(font
					(size 1 1)
					(thickness 0.15)
				)
				(justify mirror)
			)
		)
		(property "Dielectric" "X7R"
			(at 64.82 318.58 0)
			(layer "B.Fab")
			(hide yes)
			(effects
				(font
					(size 1 1)
					(thickness 0.15)
				)
				(justify mirror)
			)
		)
		(property "License" "Apache-2.0"
			(at 64.82 318.58 0)
			(layer "B.Fab")
			(hide yes)
			(effects
				(font
					(size 1 1)
					(thickness 0.15)
				)
				(justify mirror)
			)
		)
		(property "MPN" "GRM188R60J476ME15D"
			(at 64.82 318.58 0)
			(layer "B.Fab")
			(hide yes)
			(effects
				(font
					(size 1 1)
					(thickness 0.15)
				)
				(justify mirror)
			)
		)
		(property "Manufacturer" "Murata"
			(at 64.82 318.58 0)
			(layer "B.Fab")
			(hide yes)
			(effects
				(font
					(size 1 1)
					(thickness 0.15)
				)
				(justify mirror)
			)
		)
		(property "Public" ""
			(at 64.82 318.58 0)
			(layer "B.Fab")
			(hide yes)
			(effects
				(font
					(size 1 1)
					(thickness 0.15)
				)
				(justify mirror)
			)
		)
		(property "Val" "47u"
			(at 64.82 318.58 0)
			(layer "B.Fab")
			(hide yes)
			(effects
				(font
					(size 1 1)
					(thickness 0.15)
				)
				(justify mirror)
			)
		)
		(property "Voltage" "50V"
			(at 64.82 318.58 0)
			(layer "B.Fab")
			(hide yes)
			(effects
				(font
					(size 1 1)
					(thickness 0.15)
				)
				(justify mirror)
			)
		)
		(sheetname "/FPGA Supply/")
		(sheetfile "fpga-supply.kicad_sch")
		(attr smd)
		(fp_line
			(start -0.15 0.4)
			(end 0.15 0.4)
			(stroke
				(width 0.15)
				(type solid)
			)
			(layer "B.SilkS")
		)
		(fp_line
			(start -0.15 -0.4)
			(end 0.15 -0.4)
			(stroke
				(width 0.15)
				(type solid)
			)
			(layer "B.SilkS")
		)
		(fp_rect
			(start -1.25 0.65)
			(end 1.25 -0.65)
			(stroke
				(width 0.05)
				(type solid)
			)
			(fill no)
			(layer "B.CrtYd")
		)
		(fp_rect
			(start -0.8 0.4)
			(end 0.8 -0.4)
			(stroke
				(width 0.15)
				(type solid)
			)
			(fill no)
			(layer "B.Fab")
		)
		(fp_text user "Author: Antmicro"
			(at -1.682 -4.894 90)
			(layer "B.Fab")
			(effects
				(font
					(size 0.7 0.7)
					(thickness 0.15)
				)
				(justify left bottom mirror)
			)
		)
		(fp_text user "${REFERENCE}"
			(at -1.682 -3.895 90)
			(layer "B.Fab")
			(effects
				(font
					(size 0.7 0.7)
					(thickness 0.15)
				)
				(justify left bottom mirror)
			)
		)
		(fp_text user "License: Apache-2.0"
			(at -1.682 -5.895 90)
			(layer "B.Fab")
			(effects
				(font
					(size 0.7 0.7)
					(thickness 0.15)
				)
				(justify left bottom mirror)
			)
		)
		(pad "1" smd roundrect
			(at -0.7 0 270)
			(size 0.8 1)
			(layers "B.Cu" "B.Mask" "B.Paste")
			(roundrect_rratio 0.2)
			(net 417 "GND")
			(pintype "passive")
		)
		(pad "2" smd roundrect
			(at 0.7 0 270)
			(size 0.8 1)
			(layers "B.Cu" "B.Mask" "B.Paste")
			(roundrect_rratio 0.2)
			(net 2 "+1V1")
			(pintype "passive")
		)
	)
	(footprint "antmicro-footprints:C_0402_1005Metric"
		(layer "B.Cu")
		(at 198.94 132.79 90)
		(descr "Capacitor SMD 0402")
		(tags "capacitor SMD 0402")
		(property "Reference" "C50"
			(at 7.19 -9.615 270)
			(layer "B.SilkS")
			(effects
				(font
					(size 0.7 0.7)
					(thickness 0.15)
				)
				(justify left bottom mirror)
			)
		)
		(property "Value" "C_47n_0402"
			(at -1.022927 -2.155213 270)
			(layer "B.Fab")
			(hide yes)
			(effects
				(font
					(size 0.7 0.7)
					(thickness 0.15)
				)
				(justify left bottom mirror)
			)
		)
		(property "Datasheet" "https://www.murata.com/en-us/products/productdetail?partno=GRM155R61C473KA01%23"
			(at 0 0 90)
			(layer "F.Fab")
			(hide yes)
			(effects
				(font
					(size 1.27 1.27)
					(thickness 0.15)
				)
			)
		)
		(property "Description" "SMD Multilayer Ceramic Capacitor, 47000 pF, 16 V, 0402 [1005 Metric], ± 10%, X5R, MC"
			(at 0 0 90)
			(layer "F.Fab")
			(hide yes)
			(effects
				(font
					(size 1.27 1.27)
					(thickness 0.15)
				)
			)
		)
		(property "Author" "Antmicro"
			(at 331.73 -66.15 0)
			(layer "B.Fab")
			(hide yes)
			(effects
				(font
					(size 1 1)
					(thickness 0.15)
				)
				(justify mirror)
			)
		)
		(property "Dielectric" "X5R"
			(at 331.73 -66.15 0)
			(layer "B.Fab")
			(hide yes)
			(effects
				(font
					(size 1 1)
					(thickness 0.15)
				)
				(justify mirror)
			)
		)
		(property "License" "Apache-2.0"
			(at 331.73 -66.15 0)
			(layer "B.Fab")
			(hide yes)
			(effects
				(font
					(size 1 1)
					(thickness 0.15)
				)
				(justify mirror)
			)
		)
		(property "MPN" "GRM155R61C473KA01D"
			(at 331.73 -66.15 0)
			(layer "B.Fab")
			(hide yes)
			(effects
				(font
					(size 1 1)
					(thickness 0.15)
				)
				(justify mirror)
			)
		)
		(property "Manufacturer" "Murata"
			(at 331.73 -66.15 0)
			(layer "B.Fab")
			(hide yes)
			(effects
				(font
					(size 1 1)
					(thickness 0.15)
				)
				(justify mirror)
			)
		)
		(property "Public" ""
			(at 331.73 -66.15 0)
			(layer "B.Fab")
			(hide yes)
			(effects
				(font
					(size 1 1)
					(thickness 0.15)
				)
				(justify mirror)
			)
		)
		(property "Val" "47n"
			(at 331.73 -66.15 0)
			(layer "B.Fab")
			(hide yes)
			(effects
				(font
					(size 1 1)
					(thickness 0.15)
				)
				(justify mirror)
			)
		)
		(property "Voltage" "10V"
			(at 331.73 -66.15 0)
			(layer "B.Fab")
			(hide yes)
			(effects
				(font
					(size 1 1)
					(thickness 0.15)
				)
				(justify mirror)
			)
		)
		(sheetname "/FPGA Supply/")
		(sheetfile "fpga-supply.kicad_sch")
		(attr smd)
		(fp_rect
			(start -0.925 0.47)
			(end 0.925 -0.47)
			(stroke
				(width 0.05)
				(type default)
			)
			(fill no)
			(layer "B.CrtYd")
		)
		(fp_line
			(start 0.504 -0.248)
			(end -0.494 -0.248)
			(stroke
				(width 0.15)
				(type solid)
			)
			(layer "B.Fab")
		)
		(fp_line
			(start -0.494 -0.248)
			(end -0.494 0.25)
			(stroke
				(width 0.15)
				(type solid)
			)
			(layer "B.Fab")
		)
		(fp_line
			(start 0.504 0.25)
			(end 0.504 -0.248)
			(stroke
				(width 0.15)
				(type solid)
			)
			(layer "B.Fab")
		)
		(fp_line
			(start -0.494 0.25)
			(end 0.504 0.25)
			(stroke
				(width 0.15)
				(type solid)
			)
			(layer "B.Fab")
		)
		(fp_text user "${REFERENCE}"
			(at -0.939 -4.599 270)
			(layer "B.Fab")
			(effects
				(font
					(size 0.7 0.7)
					(thickness 0.15)
				)
				(justify left bottom mirror)
			)
		)
		(fp_text user "Author: Antmicro"
			(at -0.939 -3.399 270)
			(layer "B.Fab")
			(effects
				(font
					(size 0.7 0.7)
					(thickness 0.15)
				)
				(justify left bottom mirror)
			)
		)
		(fp_text user "License: Apache-2.0"
			(at -0.939 -5.799 270)
			(layer "B.Fab")
			(effects
				(font
					(size 0.7 0.7)
					(thickness 0.15)
				)
				(justify left bottom mirror)
			)
		)
		(pad "1" smd roundrect
			(at -0.48 0 90)
			(size 0.59 0.64)
			(layers "B.Cu" "B.Mask" "B.Paste")
			(roundrect_rratio 0.25)
			(net 417 "GND")
			(pintype "passive")
		)
		(pad "2" smd roundrect
			(at 0.48 0 90)
			(size 0.59 0.64)
			(layers "B.Cu" "B.Mask" "B.Paste")
			(roundrect_rratio 0.25)
			(net 47 "+1V05")
			(pintype "passive")
		)
	)
	(footprint "antmicro-footprints:R_0402_1005Metric"
		(layer "B.Cu")
		(at 213.861 116.704)
		(descr "Resistor SMD 0402")
		(tags "resistor SMD 0402")
		(property "Reference" "R92"
			(at -24.761 18.271 180)
			(layer "B.SilkS")
			(effects
				(font
					(size 0.7 0.7)
					(thickness 0.15)
				)
				(justify left bottom mirror)
			)
		)
		(property "Value" "R_4k7_0402"
			(at -1.011843 -1.772047 180)
			(layer "B.Fab")
			(hide yes)
			(effects
				(font
					(size 0.7 0.7)
					(thickness 0.15)
				)
				(justify left bottom mirror)
			)
		)
		(property "Datasheet" "https://www.bourns.com/docs/product-datasheets/cr.pdf"
			(at 0 0 0)
			(layer "F.Fab")
			(hide yes)
			(effects
				(font
					(size 1.27 1.27)
					(thickness 0.15)
				)
			)
		)
		(property "Description" "SMD Chip Resistor, 4.7 kohm, ± 1%, 62.5 mW, 0402 [1005 Metric], Thick Film, General Purpose"
			(at 0 0 0)
			(layer "F.Fab")
			(hide yes)
			(effects
				(font
					(size 1.27 1.27)
					(thickness 0.15)
				)
			)
		)
		(property "Author" "Antmicro"
			(at 0 0 0)
			(layer "B.Fab")
			(hide yes)
			(effects
				(font
					(size 1 1)
					(thickness 0.15)
				)
				(justify mirror)
			)
		)
		(property "License" "Apache-2.0"
			(at 0 0 0)
			(layer "B.Fab")
			(hide yes)
			(effects
				(font
					(size 1 1)
					(thickness 0.15)
				)
				(justify mirror)
			)
		)
		(property "MPN" "CR0402-FX-4701GLF"
			(at 0 0 0)
			(layer "B.Fab")
			(hide yes)
			(effects
				(font
					(size 1 1)
					(thickness 0.15)
				)
				(justify mirror)
			)
		)
		(property "Manufacturer" "Bourns"
			(at 0 0 0)
			(layer "B.Fab")
			(hide yes)
			(effects
				(font
					(size 1 1)
					(thickness 0.15)
				)
				(justify mirror)
			)
		)
		(property "Public" ""
			(at 0 0 0)
			(layer "B.Fab")
			(hide yes)
			(effects
				(font
					(size 1 1)
					(thickness 0.15)
				)
				(justify mirror)
			)
		)
		(property "Tolerance" "1%"
			(at 0 0 0)
			(layer "B.Fab")
			(hide yes)
			(effects
				(font
					(size 1 1)
					(thickness 0.15)
				)
				(justify mirror)
			)
		)
		(property "Val" "4k7"
			(at 0 0 0)
			(layer "B.Fab")
			(hide yes)
			(effects
				(font
					(size 1 1)
					(thickness 0.15)
				)
				(justify mirror)
			)
		)
		(sheetname "/Ethernet/")
		(sheetfile "ethernet.kicad_sch")
		(attr smd)
		(fp_rect
			(start -0.925 0.47)
			(end 0.925 -0.47)
			(stroke
				(width 0.05)
				(type default)
			)
			(fill no)
			(layer "B.CrtYd")
		)
		(fp_rect
			(start -0.5 0.25)
			(end 0.5 -0.25)
			(stroke
				(width 0.15)
				(type solid)
			)
			(fill no)
			(layer "B.Fab")
		)
		(fp_text user "${REFERENCE}"
			(at -0.95 -3.168 180)
			(layer "B.Fab")
			(effects
				(font
					(size 0.7 0.7)
					(thickness 0.15)
				)
				(justify left bottom mirror)
			)
		)
		(fp_text user "Author: Antmicro"
			(at -0.95 -4.169 180)
			(layer "B.Fab")
			(effects
				(font
					(size 0.7 0.7)
					(thickness 0.15)
				)
				(justify left bottom mirror)
			)
		)
		(fp_text user "License: Apache-2.0"
			(at -0.95 -5.169 180)
			(layer "B.Fab")
			(effects
				(font
					(size 0.7 0.7)
					(thickness 0.15)
				)
				(justify left bottom mirror)
			)
		)
		(pad "1" smd roundrect
			(at -0.48 0)
			(size 0.59 0.64)
			(layers "B.Cu" "B.Mask" "B.Paste")
			(roundrect_rratio 0.25)
			(net 227 "Net-(U11-GTX_CLK)")
			(pintype "passive")
		)
		(pad "2" smd roundrect
			(at 0.48 0)
			(size 0.59 0.64)
			(layers "B.Cu" "B.Mask" "B.Paste")
			(roundrect_rratio 0.25)
			(net 417 "GND")
			(pintype "passive")
		)
	)
	(footprint "antmicro-footprints:R_0402_1005Metric"
		(layer "B.Cu")
		(at 176.15 146.85 180)
		(descr "Resistor SMD 0402")
		(tags "resistor SMD 0402")
		(property "Reference" "R6"
			(at -0.3 -3.5 0)
			(layer "B.SilkS")
			(effects
				(font
					(size 0.7 0.7)
					(thickness 0.15)
				)
				(justify left bottom mirror)
			)
		)
		(property "Value" "R_10k_0402"
			(at -1.011843 -1.772047 0)
			(layer "B.Fab")
			(hide yes)
			(effects
				(font
					(size 0.7 0.7)
					(thickness 0.15)
				)
				(justify left bottom mirror)
			)
		)
		(property "Datasheet" "https://www.bourns.com/docs/product-datasheets/cr.pdf"
			(at 0 0 180)
			(layer "F.Fab")
			(hide yes)
			(effects
				(font
					(size 1.27 1.27)
					(thickness 0.15)
				)
			)
		)
		(property "Description" "SMD Chip Resistor, 10 kohm, ± 1%, 62.5 mW, 0402 [1005 Metric], Thick Film, General Purpose"
			(at 0 0 180)
			(layer "F.Fab")
			(hide yes)
			(effects
				(font
					(size 1.27 1.27)
					(thickness 0.15)
				)
			)
		)
		(property "Author" "Antmicro"
			(at 352.3 293.7 0)
			(layer "B.Fab")
			(hide yes)
			(effects
				(font
					(size 1 1)
					(thickness 0.15)
				)
				(justify mirror)
			)
		)
		(property "License" "Apache-2.0"
			(at 352.3 293.7 0)
			(layer "B.Fab")
			(hide yes)
			(effects
				(font
					(size 1 1)
					(thickness 0.15)
				)
				(justify mirror)
			)
		)
		(property "MPN" "CR0402-FX-1002GLF"
			(at 352.3 293.7 0)
			(layer "B.Fab")
			(hide yes)
			(effects
				(font
					(size 1 1)
					(thickness 0.15)
				)
				(justify mirror)
			)
		)
		(property "Manufacturer" "Bourns"
			(at 352.3 293.7 0)
			(layer "B.Fab")
			(hide yes)
			(effects
				(font
					(size 1 1)
					(thickness 0.15)
				)
				(justify mirror)
			)
		)
		(property "Public" ""
			(at 352.3 293.7 0)
			(layer "B.Fab")
			(hide yes)
			(effects
				(font
					(size 1 1)
					(thickness 0.15)
				)
				(justify mirror)
			)
		)
		(property "Tolerance" "1%"
			(at 352.3 293.7 0)
			(layer "B.Fab")
			(hide yes)
			(effects
				(font
					(size 1 1)
					(thickness 0.15)
				)
				(justify mirror)
			)
		)
		(property "Val" "10k"
			(at 352.3 293.7 0)
			(layer "B.Fab")
			(hide yes)
			(effects
				(font
					(size 1 1)
					(thickness 0.15)
				)
				(justify mirror)
			)
		)
		(sheetname "/Supply/")
		(sheetfile "supply.kicad_sch")
		(attr smd)
		(fp_rect
			(start -0.925 0.47)
			(end 0.925 -0.47)
			(stroke
				(width 0.05)
				(type default)
			)
			(fill no)
			(layer "B.CrtYd")
		)
		(fp_rect
			(start -0.5 0.25)
			(end 0.5 -0.25)
			(stroke
				(width 0.15)
				(type solid)
			)
			(fill no)
			(layer "B.Fab")
		)
		(fp_text user "License: Apache-2.0"
			(at -0.95 -5.169 0)
			(layer "B.Fab")
			(effects
				(font
					(size 0.7 0.7)
					(thickness 0.15)
				)
				(justify left bottom mirror)
			)
		)
		(fp_text user "Author: Antmicro"
			(at -0.95 -4.169 0)
			(layer "B.Fab")
			(effects
				(font
					(size 0.7 0.7)
					(thickness 0.15)
				)
				(justify left bottom mirror)
			)
		)
		(fp_text user "${REFERENCE}"
			(at -0.95 -3.168 0)
			(layer "B.Fab")
			(effects
				(font
					(size 0.7 0.7)
					(thickness 0.15)
				)
				(justify left bottom mirror)
			)
		)
		(pad "1" smd roundrect
			(at -0.48 0 180)
			(size 0.59 0.64)
			(layers "B.Cu" "B.Mask" "B.Paste")
			(roundrect_rratio 0.25)
			(net 263 "Net-(U6-~{PWRDN})")
			(pintype "passive")
		)
		(pad "2" smd roundrect
			(at 0.48 0 180)
			(size 0.59 0.64)
			(layers "B.Cu" "B.Mask" "B.Paste")
			(roundrect_rratio 0.25)
			(net 649 "VDD")
			(pintype "passive")
		)
	)
	(footprint "antmicro-footprints:C_0402_1005Metric"
		(layer "B.Cu")
		(at 216.329 117.56 90)
		(descr "Capacitor SMD 0402")
		(tags "capacitor SMD 0402")
		(property "Reference" "C117"
			(at -3.715 0.471 90)
			(layer "B.SilkS")
			(effects
				(font
					(size 0.7 0.7)
					(thickness 0.15)
				)
				(justify right bottom mirror)
			)
		)
		(property "Value" "C_100n_0402"
			(at -1.022927 -2.155213 90)
			(layer "B.Fab")
			(hide yes)
			(effects
				(font
					(size 0.7 0.7)
					(thickness 0.15)
				)
				(justify right bottom mirror)
			)
		)
		(property "Datasheet" "https://www.murata.com/products/productdetail?partno=GRM155R61H104KE14%23"
			(at 0 0 90)
			(layer "F.Fab")
			(hide yes)
			(effects
				(font
					(size 1.27 1.27)
					(thickness 0.15)
				)
			)
		)
		(property "Description" "SMD Multilayer Ceramic Capacitor, 0.1 µF, 50 V, 0402 [1005 Metric], ± 10%, X5R, GRM Series"
			(at 0 0 90)
			(layer "F.Fab")
			(hide yes)
			(effects
				(font
					(size 1.27 1.27)
					(thickness 0.15)
				)
			)
		)
		(property "Author" "Antmicro"
			(at 333.889 -98.769 0)
			(layer "B.Fab")
			(hide yes)
			(effects
				(font
					(size 1 1)
					(thickness 0.15)
				)
				(justify mirror)
			)
		)
		(property "Dielectric" "X5R"
			(at 333.889 -98.769 0)
			(layer "B.Fab")
			(hide yes)
			(effects
				(font
					(size 1 1)
					(thickness 0.15)
				)
				(justify mirror)
			)
		)
		(property "License" "Apache-2.0"
			(at 333.889 -98.769 0)
			(layer "B.Fab")
			(hide yes)
			(effects
				(font
					(size 1 1)
					(thickness 0.15)
				)
				(justify mirror)
			)
		)
		(property "MPN" "GRM155R61H104KE14D"
			(at 333.889 -98.769 0)
			(layer "B.Fab")
			(hide yes)
			(effects
				(font
					(size 1 1)
					(thickness 0.15)
				)
				(justify mirror)
			)
		)
		(property "Manufacturer" "Murata"
			(at 333.889 -98.769 0)
			(layer "B.Fab")
			(hide yes)
			(effects
				(font
					(size 1 1)
					(thickness 0.15)
				)
				(justify mirror)
			)
		)
		(property "Public" ""
			(at 333.889 -98.769 0)
			(layer "B.Fab")
			(hide yes)
			(effects
				(font
					(size 1 1)
					(thickness 0.15)
				)
				(justify mirror)
			)
		)
		(property "Val" "100n"
			(at 333.889 -98.769 0)
			(layer "B.Fab")
			(hide yes)
			(effects
				(font
					(size 1 1)
					(thickness 0.15)
				)
				(justify mirror)
			)
		)
		(property "Voltage" "50V"
			(at 333.889 -98.769 0)
			(layer "B.Fab")
			(hide yes)
			(effects
				(font
					(size 1 1)
					(thickness 0.15)
				)
				(justify mirror)
			)
		)
		(sheetname "/Ethernet/")
		(sheetfile "ethernet.kicad_sch")
		(attr smd)
		(fp_rect
			(start -0.925 0.47)
			(end 0.925 -0.47)
			(stroke
				(width 0.05)
				(type default)
			)
			(fill no)
			(layer "B.CrtYd")
		)
		(fp_line
			(start 0.504 -0.248)
			(end -0.494 -0.248)
			(stroke
				(width 0.15)
				(type solid)
			)
			(layer "B.Fab")
		)
		(fp_line
			(start -0.494 -0.248)
			(end -0.494 0.25)
			(stroke
				(width 0.15)
				(type solid)
			)
			(layer "B.Fab")
		)
		(fp_line
			(start 0.504 0.25)
			(end 0.504 -0.248)
			(stroke
				(width 0.15)
				(type solid)
			)
			(layer "B.Fab")
		)
		(fp_line
			(start -0.494 0.25)
			(end 0.504 0.25)
			(stroke
				(width 0.15)
				(type solid)
			)
			(layer "B.Fab")
		)
		(fp_text user "License: Apache-2.0"
			(at -0.939 -5.799 270)
			(layer "B.Fab")
			(effects
				(font
					(size 0.7 0.7)
					(thickness 0.15)
				)
				(justify left bottom mirror)
			)
		)
		(fp_text user "Author: Antmicro"
			(at -0.939 -3.399 270)
			(layer "B.Fab")
			(effects
				(font
					(size 0.7 0.7)
					(thickness 0.15)
				)
				(justify left bottom mirror)
			)
		)
		(fp_text user "${REFERENCE}"
			(at -0.939 -4.599 270)
			(layer "B.Fab")
			(effects
				(font
					(size 0.7 0.7)
					(thickness 0.15)
				)
				(justify left bottom mirror)
			)
		)
		(pad "1" smd roundrect
			(at -0.48 0 90)
			(size 0.59 0.64)
			(layers "B.Cu" "B.Mask" "B.Paste")
			(roundrect_rratio 0.25)
			(net 417 "GND")
			(pintype "passive")
		)
		(pad "2" smd roundrect
			(at 0.48 0 90)
			(size 0.59 0.64)
			(layers "B.Cu" "B.Mask" "B.Paste")
			(roundrect_rratio 0.25)
			(net 50 "+3V3")
			(pintype "passive")
		)
	)
	(footprint "antmicro-footprints:C_0402_1005Metric"
		(layer "B.Cu")
		(at 208.2 139.15)
		(descr "Capacitor SMD 0402")
		(tags "capacitor SMD 0402")
		(property "Reference" "C130"
			(at -1.47 1.7 0)
			(layer "B.SilkS")
			(effects
				(font
					(size 0.7 0.7)
					(thickness 0.15)
				)
				(justify right bottom mirror)
			)
		)
		(property "Value" "C_100n_0402"
			(at -1.022927 -2.155213 0)
			(layer "B.Fab")
			(hide yes)
			(effects
				(font
					(size 0.7 0.7)
					(thickness 0.15)
				)
				(justify right bottom mirror)
			)
		)
		(property "Datasheet" "https://www.murata.com/products/productdetail?partno=GRM155R61H104KE14%23"
			(at 0 0 0)
			(layer "F.Fab")
			(hide yes)
			(effects
				(font
					(size 1.27 1.27)
					(thickness 0.15)
				)
			)
		)
		(property "Description" "SMD Multilayer Ceramic Capacitor, 0.1 µF, 50 V, 0402 [1005 Metric], ± 10%, X5R, GRM Series"
			(at 0 0 0)
			(layer "F.Fab")
			(hide yes)
			(effects
				(font
					(size 1.27 1.27)
					(thickness 0.15)
				)
			)
		)
		(property "Author" "Antmicro"
			(at 0 0 0)
			(layer "B.Fab")
			(hide yes)
			(effects
				(font
					(size 1 1)
					(thickness 0.15)
				)
				(justify mirror)
			)
		)
		(property "Dielectric" "X5R"
			(at 0 0 0)
			(layer "B.Fab")
			(hide yes)
			(effects
				(font
					(size 1 1)
					(thickness 0.15)
				)
				(justify mirror)
			)
		)
		(property "License" "Apache-2.0"
			(at 0 0 0)
			(layer "B.Fab")
			(hide yes)
			(effects
				(font
					(size 1 1)
					(thickness 0.15)
				)
				(justify mirror)
			)
		)
		(property "MPN" "GRM155R61H104KE14D"
			(at 0 0 0)
			(layer "B.Fab")
			(hide yes)
			(effects
				(font
					(size 1 1)
					(thickness 0.15)
				)
				(justify mirror)
			)
		)
		(property "Manufacturer" "Murata"
			(at 0 0 0)
			(layer "B.Fab")
			(hide yes)
			(effects
				(font
					(size 1 1)
					(thickness 0.15)
				)
				(justify mirror)
			)
		)
		(property "Public" ""
			(at 0 0 0)
			(layer "B.Fab")
			(hide yes)
			(effects
				(font
					(size 1 1)
					(thickness 0.15)
				)
				(justify mirror)
			)
		)
		(property "Val" "100n"
			(at 0 0 0)
			(layer "B.Fab")
			(hide yes)
			(effects
				(font
					(size 1 1)
					(thickness 0.15)
				)
				(justify mirror)
			)
		)
		(property "Voltage" "50V"
			(at 0 0 0)
			(layer "B.Fab")
			(hide yes)
			(effects
				(font
					(size 1 1)
					(thickness 0.15)
				)
				(justify mirror)
			)
		)
		(sheetname "/FPGA GPIO/")
		(sheetfile "fpga-gpio.kicad_sch")
		(attr smd)
		(fp_rect
			(start -0.925 0.47)
			(end 0.925 -0.47)
			(stroke
				(width 0.05)
				(type default)
			)
			(fill no)
			(layer "B.CrtYd")
		)
		(fp_line
			(start -0.494 -0.248)
			(end -0.494 0.25)
			(stroke
				(width 0.15)
				(type solid)
			)
			(layer "B.Fab")
		)
		(fp_line
			(start -0.494 0.25)
			(end 0.504 0.25)
			(stroke
				(width 0.15)
				(type solid)
			)
			(layer "B.Fab")
		)
		(fp_line
			(start 0.504 -0.248)
			(end -0.494 -0.248)
			(stroke
				(width 0.15)
				(type solid)
			)
			(layer "B.Fab")
		)
		(fp_line
			(start 0.504 0.25)
			(end 0.504 -0.248)
			(stroke
				(width 0.15)
				(type solid)
			)
			(layer "B.Fab")
		)
		(fp_text user "Author: Antmicro"
			(at -0.939 -3.399 180)
			(layer "B.Fab")
			(effects
				(font
					(size 0.7 0.7)
					(thickness 0.15)
				)
				(justify left bottom mirror)
			)
		)
		(fp_text user "${REFERENCE}"
			(at -0.939 -4.599 180)
			(layer "B.Fab")
			(effects
				(font
					(size 0.7 0.7)
					(thickness 0.15)
				)
				(justify left bottom mirror)
			)
		)
		(fp_text user "License: Apache-2.0"
			(at -0.939 -5.799 180)
			(layer "B.Fab")
			(effects
				(font
					(size 0.7 0.7)
					(thickness 0.15)
				)
				(justify left bottom mirror)
			)
		)
		(pad "1" smd roundrect
			(at -0.48 0)
			(size 0.59 0.64)
			(layers "B.Cu" "B.Mask" "B.Paste")
			(roundrect_rratio 0.25)
			(net 649 "VDD")
			(pintype "passive")
		)
		(pad "2" smd roundrect
			(at 0.48 0)
			(size 0.59 0.64)
			(layers "B.Cu" "B.Mask" "B.Paste")
			(roundrect_rratio 0.25)
			(net 417 "GND")
			(pintype "passive")
		)
	)
	(footprint "antmicro-footprints:C_0402_1005Metric"
		(layer "B.Cu")
		(at 210.577 123.3972)
		(descr "Capacitor SMD 0402")
		(tags "capacitor SMD 0402")
		(property "Reference" "C259"
			(at -3.702 2.6528 0)
			(layer "B.SilkS")
			(effects
				(font
					(size 0.7 0.7)
					(thickness 0.15)
				)
				(justify right bottom mirror)
			)
		)
		(property "Value" "C_100n_0402"
			(at -1.022927 -2.155213 0)
			(layer "B.Fab")
			(hide yes)
			(effects
				(font
					(size 0.7 0.7)
					(thickness 0.15)
				)
				(justify right bottom mirror)
			)
		)
		(property "Datasheet" "https://www.murata.com/products/productdetail?partno=GRM155R61H104KE14%23"
			(at 0 0 0)
			(layer "F.Fab")
			(hide yes)
			(effects
				(font
					(size 1.27 1.27)
					(thickness 0.15)
				)
			)
		)
		(property "Description" "SMD Multilayer Ceramic Capacitor, 0.1 µF, 50 V, 0402 [1005 Metric], ± 10%, X5R, GRM Series"
			(at 0 0 0)
			(layer "F.Fab")
			(hide yes)
			(effects
				(font
					(size 1.27 1.27)
					(thickness 0.15)
				)
			)
		)
		(property "Author" "Antmicro"
			(at 0 0 0)
			(layer "B.Fab")
			(hide yes)
			(effects
				(font
					(size 1 1)
					(thickness 0.15)
				)
				(justify mirror)
			)
		)
		(property "Dielectric" "X5R"
			(at 0 0 0)
			(layer "B.Fab")
			(hide yes)
			(effects
				(font
					(size 1 1)
					(thickness 0.15)
				)
				(justify mirror)
			)
		)
		(property "License" "Apache-2.0"
			(at 0 0 0)
			(layer "B.Fab")
			(hide yes)
			(effects
				(font
					(size 1 1)
					(thickness 0.15)
				)
				(justify mirror)
			)
		)
		(property "MPN" "GRM155R61H104KE14D"
			(at 0 0 0)
			(layer "B.Fab")
			(hide yes)
			(effects
				(font
					(size 1 1)
					(thickness 0.15)
				)
				(justify mirror)
			)
		)
		(property "Manufacturer" "Murata"
			(at 0 0 0)
			(layer "B.Fab")
			(hide yes)
			(effects
				(font
					(size 1 1)
					(thickness 0.15)
				)
				(justify mirror)
			)
		)
		(property "Public" ""
			(at 0 0 0)
			(layer "B.Fab")
			(hide yes)
			(effects
				(font
					(size 1 1)
					(thickness 0.15)
				)
				(justify mirror)
			)
		)
		(property "Val" "100n"
			(at 0 0 0)
			(layer "B.Fab")
			(hide yes)
			(effects
				(font
					(size 1 1)
					(thickness 0.15)
				)
				(justify mirror)
			)
		)
		(property "Voltage" "50V"
			(at 0 0 0)
			(layer "B.Fab")
			(hide yes)
			(effects
				(font
					(size 1 1)
					(thickness 0.15)
				)
				(justify mirror)
			)
		)
		(sheetname "/Ethernet/")
		(sheetfile "ethernet.kicad_sch")
		(attr smd)
		(fp_rect
			(start -0.925 0.47)
			(end 0.925 -0.47)
			(stroke
				(width 0.05)
				(type default)
			)
			(fill no)
			(layer "B.CrtYd")
		)
		(fp_line
			(start -0.494 -0.248)
			(end -0.494 0.25)
			(stroke
				(width 0.15)
				(type solid)
			)
			(layer "B.Fab")
		)
		(fp_line
			(start -0.494 0.25)
			(end 0.504 0.25)
			(stroke
				(width 0.15)
				(type solid)
			)
			(layer "B.Fab")
		)
		(fp_line
			(start 0.504 -0.248)
			(end -0.494 -0.248)
			(stroke
				(width 0.15)
				(type solid)
			)
			(layer "B.Fab")
		)
		(fp_line
			(start 0.504 0.25)
			(end 0.504 -0.248)
			(stroke
				(width 0.15)
				(type solid)
			)
			(layer "B.Fab")
		)
		(fp_text user "${REFERENCE}"
			(at -0.939 -4.599 180)
			(layer "B.Fab")
			(effects
				(font
					(size 0.7 0.7)
					(thickness 0.15)
				)
				(justify left bottom mirror)
			)
		)
		(fp_text user "Author: Antmicro"
			(at -0.939 -3.399 180)
			(layer "B.Fab")
			(effects
				(font
					(size 0.7 0.7)
					(thickness 0.15)
				)
				(justify left bottom mirror)
			)
		)
		(fp_text user "License: Apache-2.0"
			(at -0.939 -5.799 180)
			(layer "B.Fab")
			(effects
				(font
					(size 0.7 0.7)
					(thickness 0.15)
				)
				(justify left bottom mirror)
			)
		)
		(pad "1" smd roundrect
			(at -0.48 0)
			(size 0.59 0.64)
			(layers "B.Cu" "B.Mask" "B.Paste")
			(roundrect_rratio 0.25)
			(net 42 "/Ethernet/SGMII.RX0_P")
			(pintype "passive")
		)
		(pad "2" smd roundrect
			(at 0.48 0)
			(size 0.59 0.64)
			(layers "B.Cu" "B.Mask" "B.Paste")
			(roundrect_rratio 0.25)
			(net 170 "/Ethernet/SGMII_SO_P")
			(pintype "passive")
		)
	)
	(footprint "antmicro-footprints:C_0402_1005Metric"
		(layer "B.Cu")
		(at 189.28 143.18 180)
		(descr "Capacitor SMD 0402")
		(tags "capacitor SMD 0402")
		(property "Reference" "C64"
			(at -1.195 0.53 0)
			(layer "B.SilkS")
			(effects
				(font
					(size 0.7 0.7)
					(thickness 0.15)
				)
				(justify left bottom mirror)
			)
		)
		(property "Value" "C_10n_0402"
			(at -1.022927 -2.155213 0)
			(layer "B.Fab")
			(hide yes)
			(effects
				(font
					(size 0.7 0.7)
					(thickness 0.15)
				)
				(justify left bottom mirror)
			)
		)
		(property "Datasheet" "https://www.murata.com/products/productdetail?partno=GRM155R71H103KA88%23"
			(at 0 0 180)
			(layer "F.Fab")
			(hide yes)
			(effects
				(font
					(size 1.27 1.27)
					(thickness 0.15)
				)
			)
		)
		(property "Description" "SMD Multilayer Ceramic Capacitor, 10000 pF, 50 V, 0402 [1005 Metric], ± 10%, X7R, GRM Series"
			(at 0 0 180)
			(layer "F.Fab")
			(hide yes)
			(effects
				(font
					(size 1.27 1.27)
					(thickness 0.15)
				)
			)
		)
		(property "Author" "Antmicro"
			(at 378.56 286.36 0)
			(layer "B.Fab")
			(hide yes)
			(effects
				(font
					(size 1 1)
					(thickness 0.15)
				)
				(justify mirror)
			)
		)
		(property "Dielectric" "X7R"
			(at 378.56 286.36 0)
			(layer "B.Fab")
			(hide yes)
			(effects
				(font
					(size 1 1)
					(thickness 0.15)
				)
				(justify mirror)
			)
		)
		(property "License" "Apache-2.0"
			(at 378.56 286.36 0)
			(layer "B.Fab")
			(hide yes)
			(effects
				(font
					(size 1 1)
					(thickness 0.15)
				)
				(justify mirror)
			)
		)
		(property "MPN" "GRM155R71H103KA88D"
			(at 378.56 286.36 0)
			(layer "B.Fab")
			(hide yes)
			(effects
				(font
					(size 1 1)
					(thickness 0.15)
				)
				(justify mirror)
			)
		)
		(property "Manufacturer" "Murata"
			(at 378.56 286.36 0)
			(layer "B.Fab")
			(hide yes)
			(effects
				(font
					(size 1 1)
					(thickness 0.15)
				)
				(justify mirror)
			)
		)
		(property "Public" ""
			(at 378.56 286.36 0)
			(layer "B.Fab")
			(hide yes)
			(effects
				(font
					(size 1 1)
					(thickness 0.15)
				)
				(justify mirror)
			)
		)
		(property "Val" "10n"
			(at 378.56 286.36 0)
			(layer "B.Fab")
			(hide yes)
			(effects
				(font
					(size 1 1)
					(thickness 0.15)
				)
				(justify mirror)
			)
		)
		(property "Voltage" "50V"
			(at 378.56 286.36 0)
			(layer "B.Fab")
			(hide yes)
			(effects
				(font
					(size 1 1)
					(thickness 0.15)
				)
				(justify mirror)
			)
		)
		(sheetname "/FPGA Supply/")
		(sheetfile "fpga-supply.kicad_sch")
		(attr smd)
		(fp_rect
			(start -0.925 0.47)
			(end 0.925 -0.47)
			(stroke
				(width 0.05)
				(type default)
			)
			(fill no)
			(layer "B.CrtYd")
		)
		(fp_line
			(start 0.504 0.25)
			(end 0.504 -0.248)
			(stroke
				(width 0.15)
				(type solid)
			)
			(layer "B.Fab")
		)
		(fp_line
			(start 0.504 -0.248)
			(end -0.494 -0.248)
			(stroke
				(width 0.15)
				(type solid)
			)
			(layer "B.Fab")
		)
		(fp_line
			(start -0.494 0.25)
			(end 0.504 0.25)
			(stroke
				(width 0.15)
				(type solid)
			)
			(layer "B.Fab")
		)
		(fp_line
			(start -0.494 -0.248)
			(end -0.494 0.25)
			(stroke
				(width 0.15)
				(type solid)
			)
			(layer "B.Fab")
		)
		(fp_text user "Author: Antmicro"
			(at -0.939 -3.399 0)
			(layer "B.Fab")
			(effects
				(font
					(size 0.7 0.7)
					(thickness 0.15)
				)
				(justify left bottom mirror)
			)
		)
		(fp_text user "License: Apache-2.0"
			(at -0.939 -5.799 0)
			(layer "B.Fab")
			(effects
				(font
					(size 0.7 0.7)
					(thickness 0.15)
				)
				(justify left bottom mirror)
			)
		)
		(fp_text user "${REFERENCE}"
			(at -0.939 -4.599 0)
			(layer "B.Fab")
			(effects
				(font
					(size 0.7 0.7)
					(thickness 0.15)
				)
				(justify left bottom mirror)
			)
		)
		(pad "1" smd roundrect
			(at -0.48 0 180)
			(size 0.59 0.64)
			(layers "B.Cu" "B.Mask" "B.Paste")
			(roundrect_rratio 0.25)
			(net 417 "GND")
			(pintype "passive")
		)
		(pad "2" smd roundrect
			(at 0.48 0 180)
			(size 0.59 0.64)
			(layers "B.Cu" "B.Mask" "B.Paste")
			(roundrect_rratio 0.25)
			(net 47 "+1V05")
			(pintype "passive")
		)
	)
	(footprint "antmicro-footprints:R_0402_1005Metric"
		(layer "B.Cu")
		(at 224.33 128.2 180)
		(descr "Resistor SMD 0402")
		(tags "resistor SMD 0402")
		(property "Reference" "R71"
			(at -1.62 0.45 0)
			(layer "B.SilkS")
			(effects
				(font
					(size 0.7 0.7)
					(thickness 0.15)
				)
				(justify left bottom mirror)
			)
		)
		(property "Value" "R_470R_0402"
			(at -1.011843 -1.772047 0)
			(layer "B.Fab")
			(hide yes)
			(effects
				(font
					(size 0.7 0.7)
					(thickness 0.15)
				)
				(justify left bottom mirror)
			)
		)
		(property "Datasheet" "https://www.bourns.com/docs/product-datasheets/cr.pdf"
			(at 0 0 180)
			(layer "F.Fab")
			(hide yes)
			(effects
				(font
					(size 1.27 1.27)
					(thickness 0.15)
				)
			)
		)
		(property "Description" "SMD Chip Resistor, 470 ohm, ± 1%, 62.5 mW, 0402 [1005 Metric], Thick Film, General Purpose"
			(at 0 0 180)
			(layer "F.Fab")
			(hide yes)
			(effects
				(font
					(size 1.27 1.27)
					(thickness 0.15)
				)
			)
		)
		(property "Author" "Antmicro"
			(at 448.66 256.4 0)
			(layer "B.Fab")
			(hide yes)
			(effects
				(font
					(size 1 1)
					(thickness 0.15)
				)
				(justify mirror)
			)
		)
		(property "License" "Apache-2.0"
			(at 448.66 256.4 0)
			(layer "B.Fab")
			(hide yes)
			(effects
				(font
					(size 1 1)
					(thickness 0.15)
				)
				(justify mirror)
			)
		)
		(property "MPN" "CR0402-FX-4700GLF"
			(at 448.66 256.4 0)
			(layer "B.Fab")
			(hide yes)
			(effects
				(font
					(size 1 1)
					(thickness 0.15)
				)
				(justify mirror)
			)
		)
		(property "Manufacturer" "Bourns"
			(at 448.66 256.4 0)
			(layer "B.Fab")
			(hide yes)
			(effects
				(font
					(size 1 1)
					(thickness 0.15)
				)
				(justify mirror)
			)
		)
		(property "Public" ""
			(at 448.66 256.4 0)
			(layer "B.Fab")
			(hide yes)
			(effects
				(font
					(size 1 1)
					(thickness 0.15)
				)
				(justify mirror)
			)
		)
		(property "Tolerance" "1%"
			(at 448.66 256.4 0)
			(layer "B.Fab")
			(hide yes)
			(effects
				(font
					(size 1 1)
					(thickness 0.15)
				)
				(justify mirror)
			)
		)
		(property "Val" "470R"
			(at 448.66 256.4 0)
			(layer "B.Fab")
			(hide yes)
			(effects
				(font
					(size 1 1)
					(thickness 0.15)
				)
				(justify mirror)
			)
		)
		(sheetname "/FPGA GPIO/")
		(sheetfile "fpga-gpio.kicad_sch")
		(attr smd)
		(fp_rect
			(start -0.925 0.47)
			(end 0.925 -0.47)
			(stroke
				(width 0.05)
				(type default)
			)
			(fill no)
			(layer "B.CrtYd")
		)
		(fp_rect
			(start -0.5 0.25)
			(end 0.5 -0.25)
			(stroke
				(width 0.15)
				(type solid)
			)
			(fill no)
			(layer "B.Fab")
		)
		(fp_text user "License: Apache-2.0"
			(at -0.95 -5.169 0)
			(layer "B.Fab")
			(effects
				(font
					(size 0.7 0.7)
					(thickness 0.15)
				)
				(justify left bottom mirror)
			)
		)
		(fp_text user "Author: Antmicro"
			(at -0.95 -4.169 0)
			(layer "B.Fab")
			(effects
				(font
					(size 0.7 0.7)
					(thickness 0.15)
				)
				(justify left bottom mirror)
			)
		)
		(fp_text user "${REFERENCE}"
			(at -0.95 -3.168 0)
			(layer "B.Fab")
			(effects
				(font
					(size 0.7 0.7)
					(thickness 0.15)
				)
				(justify left bottom mirror)
			)
		)
		(pad "1" smd roundrect
			(at -0.48 0 180)
			(size 0.59 0.64)
			(layers "B.Cu" "B.Mask" "B.Paste")
			(roundrect_rratio 0.25)
			(net 541 "Net-(Q7-D)")
			(pintype "passive")
		)
		(pad "2" smd roundrect
			(at 0.48 0 180)
			(size 0.59 0.64)
			(layers "B.Cu" "B.Mask" "B.Paste")
			(roundrect_rratio 0.25)
			(net 538 "Net-(D6-C_{G})")
			(pintype "passive")
		)
	)
	(footprint "antmicro-footprints:C_0402_1005Metric"
		(layer "B.Cu")
		(at 177.65 147.35 90)
		(descr "Capacitor SMD 0402")
		(tags "capacitor SMD 0402")
		(property "Reference" "C84"
			(at -3.29 1.39 90)
			(layer "B.SilkS")
			(effects
				(font
					(size 0.7 0.7)
					(thickness 0.15)
				)
				(justify right bottom mirror)
			)
		)
		(property "Value" "C_100n_0402"
			(at -1.022927 -2.155213 90)
			(layer "B.Fab")
			(hide yes)
			(effects
				(font
					(size 0.7 0.7)
					(thickness 0.15)
				)
				(justify right bottom mirror)
			)
		)
		(property "Datasheet" "https://www.murata.com/products/productdetail?partno=GRM155R61H104KE14%23"
			(at 0 0 90)
			(layer "F.Fab")
			(hide yes)
			(effects
				(font
					(size 1.27 1.27)
					(thickness 0.15)
				)
			)
		)
		(property "Description" "SMD Multilayer Ceramic Capacitor, 0.1 µF, 50 V, 0402 [1005 Metric], ± 10%, X5R, GRM Series"
			(at 0 0 90)
			(layer "F.Fab")
			(hide yes)
			(effects
				(font
					(size 1.27 1.27)
					(thickness 0.15)
				)
			)
		)
		(property "Author" "Antmicro"
			(at 325 -30.3 0)
			(layer "B.Fab")
			(hide yes)
			(effects
				(font
					(size 1 1)
					(thickness 0.15)
				)
				(justify mirror)
			)
		)
		(property "Dielectric" "X5R"
			(at 325 -30.3 0)
			(layer "B.Fab")
			(hide yes)
			(effects
				(font
					(size 1 1)
					(thickness 0.15)
				)
				(justify mirror)
			)
		)
		(property "License" "Apache-2.0"
			(at 325 -30.3 0)
			(layer "B.Fab")
			(hide yes)
			(effects
				(font
					(size 1 1)
					(thickness 0.15)
				)
				(justify mirror)
			)
		)
		(property "MPN" "GRM155R61H104KE14D"
			(at 325 -30.3 0)
			(layer "B.Fab")
			(hide yes)
			(effects
				(font
					(size 1 1)
					(thickness 0.15)
				)
				(justify mirror)
			)
		)
		(property "Manufacturer" "Murata"
			(at 325 -30.3 0)
			(layer "B.Fab")
			(hide yes)
			(effects
				(font
					(size 1 1)
					(thickness 0.15)
				)
				(justify mirror)
			)
		)
		(property "Public" ""
			(at 325 -30.3 0)
			(layer "B.Fab")
			(hide yes)
			(effects
				(font
					(size 1 1)
					(thickness 0.15)
				)
				(justify mirror)
			)
		)
		(property "Val" "100n"
			(at 325 -30.3 0)
			(layer "B.Fab")
			(hide yes)
			(effects
				(font
					(size 1 1)
					(thickness 0.15)
				)
				(justify mirror)
			)
		)
		(property "Voltage" "50V"
			(at 325 -30.3 0)
			(layer "B.Fab")
			(hide yes)
			(effects
				(font
					(size 1 1)
					(thickness 0.15)
				)
				(justify mirror)
			)
		)
		(sheetname "/Supply/")
		(sheetfile "supply.kicad_sch")
		(attr smd)
		(fp_rect
			(start -0.925 0.47)
			(end 0.925 -0.47)
			(stroke
				(width 0.05)
				(type default)
			)
			(fill no)
			(layer "B.CrtYd")
		)
		(fp_line
			(start 0.504 -0.248)
			(end -0.494 -0.248)
			(stroke
				(width 0.15)
				(type solid)
			)
			(layer "B.Fab")
		)
		(fp_line
			(start -0.494 -0.248)
			(end -0.494 0.25)
			(stroke
				(width 0.15)
				(type solid)
			)
			(layer "B.Fab")
		)
		(fp_line
			(start 0.504 0.25)
			(end 0.504 -0.248)
			(stroke
				(width 0.15)
				(type solid)
			)
			(layer "B.Fab")
		)
		(fp_line
			(start -0.494 0.25)
			(end 0.504 0.25)
			(stroke
				(width 0.15)
				(type solid)
			)
			(layer "B.Fab")
		)
		(fp_text user "${REFERENCE}"
			(at -0.939 -4.599 270)
			(layer "B.Fab")
			(effects
				(font
					(size 0.7 0.7)
					(thickness 0.15)
				)
				(justify left bottom mirror)
			)
		)
		(fp_text user "License: Apache-2.0"
			(at -0.939 -5.799 270)
			(layer "B.Fab")
			(effects
				(font
					(size 0.7 0.7)
					(thickness 0.15)
				)
				(justify left bottom mirror)
			)
		)
		(fp_text user "Author: Antmicro"
			(at -0.939 -3.399 270)
			(layer "B.Fab")
			(effects
				(font
					(size 0.7 0.7)
					(thickness 0.15)
				)
				(justify left bottom mirror)
			)
		)
		(pad "1" smd roundrect
			(at -0.48 0 90)
			(size 0.59 0.64)
			(layers "B.Cu" "B.Mask" "B.Paste")
			(roundrect_rratio 0.25)
			(net 417 "GND")
			(pintype "passive")
		)
		(pad "2" smd roundrect
			(at 0.48 0 90)
			(size 0.59 0.64)
			(layers "B.Cu" "B.Mask" "B.Paste")
			(roundrect_rratio 0.25)
			(net 50 "+3V3")
			(pintype "passive")
		)
	)
	(footprint "antmicro-footprints:TP_SMD_0.75mm"
		(layer "B.Cu")
		(at 186.125 149.525 180)
		(property "Reference" "TP21"
			(at -1.175 -1.325 180)
			(layer "B.SilkS")
			(hide yes)
			(effects
				(font
					(size 0.7 0.7)
					(thickness 0.15)
				)
				(justify left bottom mirror)
			)
		)
		(property "Value" "TP_0.75mm_SMD"
			(at 0 -1.2 0)
			(layer "B.Fab")
			(hide yes)
			(effects
				(font
					(size 0.7 0.7)
					(thickness 0.15)
				)
				(justify left bottom mirror)
			)
		)
		(property "Description" "SMT test point"
			(at 0 0 0)
			(layer "B.Fab")
			(hide yes)
			(effects
				(font
					(size 1.27 1.27)
					(thickness 0.15)
				)
				(justify mirror)
			)
		)
		(property "MPN" ""
			(at 0 0 0)
			(unlocked yes)
			(layer "B.Fab")
			(hide yes)
			(effects
				(font
					(size 1 1)
					(thickness 0.15)
				)
				(justify mirror)
			)
		)
		(property "Manufacturer" ""
			(at 0 0 0)
			(unlocked yes)
			(layer "B.Fab")
			(hide yes)
			(effects
				(font
					(size 1 1)
					(thickness 0.15)
				)
				(justify mirror)
			)
		)
		(property "Author" "Antmicro"
			(at 0 0 0)
			(unlocked yes)
			(layer "B.Fab")
			(hide yes)
			(effects
				(font
					(size 1 1)
					(thickness 0.15)
				)
				(justify mirror)
			)
		)
		(property "License" "Apache-2.0"
			(at 0 0 0)
			(unlocked yes)
			(layer "B.Fab")
			(hide yes)
			(effects
				(font
					(size 1 1)
					(thickness 0.15)
				)
				(justify mirror)
			)
		)
		(property "Public" "False"
			(at 0 0 0)
			(unlocked yes)
			(layer "B.Fab")
			(hide yes)
			(effects
				(font
					(size 1 1)
					(thickness 0.15)
				)
				(justify mirror)
			)
		)
		(sheetname "/Supply/")
		(sheetfile "supply.kicad_sch")
		(attr exclude_from_pos_files exclude_from_bom)
		(fp_circle
			(center 0 0)
			(end 0.475 0)
			(stroke
				(width 0.05)
				(type default)
			)
			(fill no)
			(layer "B.CrtYd")
		)
		(fp_text user "Author: Antmicro"
			(at -0.4 -3.901 0)
			(layer "B.Fab")
			(effects
				(font
					(size 0.7 0.7)
					(thickness 0.15)
				)
				(justify left bottom mirror)
			)
		)
		(fp_text user "License: Apache-2.0"
			(at -0.4 -5.101 0)
			(layer "B.Fab")
			(effects
				(font
					(size 0.7 0.7)
					(thickness 0.15)
				)
				(justify left bottom mirror)
			)
		)
		(fp_text user "${REFERENCE}"
			(at -0.4 -2.7 0)
			(layer "B.Fab")
			(effects
				(font
					(size 0.7 0.7)
					(thickness 0.15)
				)
				(justify left bottom mirror)
			)
		)
		(pad "1" smd circle
			(at 0 0 180)
			(size 0.75 0.75)
			(layers "B.Cu" "B.Mask")
			(net 633 "Net-(U7-OUT4)")
			(pinfunction "1")
			(pintype "passive")
		)
	)
	(footprint "antmicro-footprints:C_0402_1005Metric"
		(layer "B.Cu")
		(at 175.28 126.8655 -90)
		(descr "Capacitor SMD 0402")
		(tags "capacitor SMD 0402")
		(property "Reference" "C145"
			(at 0.3945 -2.39 135)
			(layer "B.SilkS")
			(effects
				(font
					(size 0.7 0.7)
					(thickness 0.15)
				)
				(justify left bottom mirror)
			)
		)
		(property "Value" "C_1u_0402"
			(at -1.022927 -2.155213 90)
			(layer "B.Fab")
			(hide yes)
			(effects
				(font
					(size 0.7 0.7)
					(thickness 0.15)
				)
				(justify left bottom mirror)
			)
		)
		(property "Datasheet" "https://product.tdk.com/en/search/capacitor/ceramic/mlcc/info?part_no=C1005X6S1A105K050BC"
			(at 0 0 270)
			(layer "F.Fab")
			(hide yes)
			(effects
				(font
					(size 1.27 1.27)
					(thickness 0.15)
				)
			)
		)
		(property "Description" "SMD Multilayer Ceramic Capacitor, 1 µF, 10 V, 0402 [1005 Metric], ± 10%, X6S, C"
			(at 0 0 270)
			(layer "F.Fab")
			(hide yes)
			(effects
				(font
					(size 1.27 1.27)
					(thickness 0.15)
				)
			)
		)
		(property "Author" "Antmicro"
			(at 48.4145 302.1455 0)
			(layer "B.Fab")
			(hide yes)
			(effects
				(font
					(size 1 1)
					(thickness 0.15)
				)
				(justify mirror)
			)
		)
		(property "Dielectric" "X5R"
			(at 48.4145 302.1455 0)
			(layer "B.Fab")
			(hide yes)
			(effects
				(font
					(size 1 1)
					(thickness 0.15)
				)
				(justify mirror)
			)
		)
		(property "License" "Apache-2.0"
			(at 48.4145 302.1455 0)
			(layer "B.Fab")
			(hide yes)
			(effects
				(font
					(size 1 1)
					(thickness 0.15)
				)
				(justify mirror)
			)
		)
		(property "MPN" "C1005X6S1A105K050BC"
			(at 48.4145 302.1455 0)
			(layer "B.Fab")
			(hide yes)
			(effects
				(font
					(size 1 1)
					(thickness 0.15)
				)
				(justify mirror)
			)
		)
		(property "Manufacturer" "TDK"
			(at 48.4145 302.1455 0)
			(layer "B.Fab")
			(hide yes)
			(effects
				(font
					(size 1 1)
					(thickness 0.15)
				)
				(justify mirror)
			)
		)
		(property "Public" ""
			(at 48.4145 302.1455 0)
			(layer "B.Fab")
			(hide yes)
			(effects
				(font
					(size 1 1)
					(thickness 0.15)
				)
				(justify mirror)
			)
		)
		(property "Val" "1u"
			(at 48.4145 302.1455 0)
			(layer "B.Fab")
			(hide yes)
			(effects
				(font
					(size 1 1)
					(thickness 0.15)
				)
				(justify mirror)
			)
		)
		(property "Voltage" "16V"
			(at 48.4145 302.1455 0)
			(layer "B.Fab")
			(hide yes)
			(effects
				(font
					(size 1 1)
					(thickness 0.15)
				)
				(justify mirror)
			)
		)
		(sheetname "/LPDDR4/")
		(sheetfile "lpddr.kicad_sch")
		(attr smd)
		(fp_rect
			(start -0.925 0.47)
			(end 0.925 -0.47)
			(stroke
				(width 0.05)
				(type default)
			)
			(fill no)
			(layer "B.CrtYd")
		)
		(fp_line
			(start -0.494 0.25)
			(end 0.504 0.25)
			(stroke
				(width 0.15)
				(type solid)
			)
			(layer "B.Fab")
		)
		(fp_line
			(start 0.504 0.25)
			(end 0.504 -0.248)
			(stroke
				(width 0.15)
				(type solid)
			)
			(layer "B.Fab")
		)
		(fp_line
			(start -0.494 -0.248)
			(end -0.494 0.25)
			(stroke
				(width 0.15)
				(type solid)
			)
			(layer "B.Fab")
		)
		(fp_line
			(start 0.504 -0.248)
			(end -0.494 -0.248)
			(stroke
				(width 0.15)
				(type solid)
			)
			(layer "B.Fab")
		)
		(fp_text user "${REFERENCE}"
			(at -0.939 -4.599 90)
			(layer "B.Fab")
			(effects
				(font
					(size 0.7 0.7)
					(thickness 0.15)
				)
				(justify left bottom mirror)
			)
		)
		(fp_text user "License: Apache-2.0"
			(at -0.939 -5.799 90)
			(layer "B.Fab")
			(effects
				(font
					(size 0.7 0.7)
					(thickness 0.15)
				)
				(justify left bottom mirror)
			)
		)
		(fp_text user "Author: Antmicro"
			(at -0.939 -3.399 90)
			(layer "B.Fab")
			(effects
				(font
					(size 0.7 0.7)
					(thickness 0.15)
				)
				(justify left bottom mirror)
			)
		)
		(pad "1" smd roundrect
			(at -0.48 0 270)
			(size 0.59 0.64)
			(layers "B.Cu" "B.Mask" "B.Paste")
			(roundrect_rratio 0.25)
			(net 417 "GND")
			(pintype "passive")
		)
		(pad "2" smd roundrect
			(at 0.48 0 270)
			(size 0.59 0.64)
			(layers "B.Cu" "B.Mask" "B.Paste")
			(roundrect_rratio 0.25)
			(net 2 "+1V1")
			(pintype "passive")
		)
	)
	(footprint "antmicro-footprints:FB_0402_1005Metric"
		(layer "B.Cu")
		(at 192.92 145.3 180)
		(descr "Ferrite Bead SMD 0402")
		(tags "ferrite bead SMD 0402")
		(property "Reference" "FB4"
			(at -1.13 0.547484 0)
			(layer "B.SilkS")
			(effects
				(font
					(size 0.7 0.7)
					(thickness 0.15)
				)
				(justify left bottom mirror)
			)
		)
		(property "Value" "FB_120Z_1.2A_TDK-MPZ_0402"
			(at 0 -1.4 0)
			(layer "B.Fab")
			(hide yes)
			(effects
				(font
					(size 0.7 0.7)
					(thickness 0.15)
				)
				(justify left bottom mirror)
			)
		)
		(property "Datasheet" "https://product.tdk.com/en/search/emc/emc/beads/info?part_no=MPZ1005S121CT000"
			(at 0 0 180)
			(layer "F.Fab")
			(hide yes)
			(effects
				(font
					(size 1.27 1.27)
					(thickness 0.15)
				)
			)
		)
		(property "Description" "Ferrite Bead, 0402 [1005 Metric], 120 ohm, 1.2A, MPZ, 0.06 ohm, ± 25%, DC Power line"
			(at 0 0 180)
			(layer "F.Fab")
			(hide yes)
			(effects
				(font
					(size 1.27 1.27)
					(thickness 0.15)
				)
			)
		)
		(property "Author" "Antmicro"
			(at 385.84 290.6 0)
			(layer "B.Fab")
			(hide yes)
			(effects
				(font
					(size 1 1)
					(thickness 0.15)
				)
				(justify mirror)
			)
		)
		(property "Current" ""
			(at 385.84 290.6 0)
			(layer "B.Fab")
			(hide yes)
			(effects
				(font
					(size 1 1)
					(thickness 0.15)
				)
				(justify mirror)
			)
		)
		(property "License" "Apache-2.0"
			(at 385.84 290.6 0)
			(layer "B.Fab")
			(hide yes)
			(effects
				(font
					(size 1 1)
					(thickness 0.15)
				)
				(justify mirror)
			)
		)
		(property "MPN" "MPZ1005S121CT000"
			(at 385.84 290.6 0)
			(layer "B.Fab")
			(hide yes)
			(effects
				(font
					(size 1 1)
					(thickness 0.15)
				)
				(justify mirror)
			)
		)
		(property "Manufacturer" "TDK"
			(at 385.84 290.6 0)
			(layer "B.Fab")
			(hide yes)
			(effects
				(font
					(size 1 1)
					(thickness 0.15)
				)
				(justify mirror)
			)
		)
		(property "Public" ""
			(at 385.84 290.6 0)
			(layer "B.Fab")
			(hide yes)
			(effects
				(font
					(size 1 1)
					(thickness 0.15)
				)
				(justify mirror)
			)
		)
		(property "Val" "120Z/1.2A"
			(at 385.84 290.6 0)
			(layer "B.Fab")
			(hide yes)
			(effects
				(font
					(size 1 1)
					(thickness 0.15)
				)
				(justify mirror)
			)
		)
		(sheetname "/HDMI/")
		(sheetfile "hdmi.kicad_sch")
		(attr smd)
		(fp_rect
			(start -0.925 0.47)
			(end 0.925 -0.47)
			(stroke
				(width 0.05)
				(type default)
			)
			(fill no)
			(layer "B.CrtYd")
		)
		(fp_rect
			(start -0.5 0.25)
			(end 0.5 -0.25)
			(stroke
				(width 0.15)
				(type solid)
			)
			(fill no)
			(layer "B.Fab")
		)
		(fp_text user "License: Apache-2.0"
			(at -0.95 -5.169 0)
			(layer "B.Fab")
			(effects
				(font
					(size 0.7 0.7)
					(thickness 0.15)
				)
				(justify left bottom mirror)
			)
		)
		(fp_text user "Author: Antmicro"
			(at -0.95 -4.169 0)
			(layer "B.Fab")
			(effects
				(font
					(size 0.7 0.7)
					(thickness 0.15)
				)
				(justify left bottom mirror)
			)
		)
		(fp_text user "${REFERENCE}"
			(at -0.95 -3.168 0)
			(layer "B.Fab")
			(effects
				(font
					(size 0.7 0.7)
					(thickness 0.15)
				)
				(justify left bottom mirror)
			)
		)
		(pad "1" smd roundrect
			(at -0.48 0 180)
			(size 0.59 0.64)
			(layers "B.Cu" "B.Mask" "B.Paste")
			(roundrect_rratio 0.25)
			(net 553 "/HDMI/HDMI_3V3")
			(pintype "passive")
		)
		(pad "2" smd roundrect
			(at 0.48 0 180)
			(size 0.59 0.64)
			(layers "B.Cu" "B.Mask" "B.Paste")
			(roundrect_rratio 0.25)
			(net 50 "+3V3")
			(pintype "passive")
		)
	)
	(footprint "antmicro-footprints:C_0402_1005Metric"
		(layer "B.Cu")
		(at 204.51 140.67 90)
		(descr "Capacitor SMD 0402")
		(tags "capacitor SMD 0402")
		(property "Reference" "C62"
			(at -1.42 1.46 270)
			(layer "B.SilkS")
			(effects
				(font
					(size 0.7 0.7)
					(thickness 0.15)
				)
				(justify right bottom mirror)
			)
		)
		(property "Value" "C_100n_0402"
			(at -1.022927 -2.155213 90)
			(layer "B.Fab")
			(hide yes)
			(effects
				(font
					(size 0.7 0.7)
					(thickness 0.15)
				)
				(justify right bottom mirror)
			)
		)
		(property "Datasheet" "https://www.murata.com/products/productdetail?partno=GRM155R61H104KE14%23"
			(at 0 0 90)
			(layer "F.Fab")
			(hide yes)
			(effects
				(font
					(size 1.27 1.27)
					(thickness 0.15)
				)
			)
		)
		(property "Description" "SMD Multilayer Ceramic Capacitor, 0.1 µF, 50 V, 0402 [1005 Metric], ± 10%, X5R, GRM Series"
			(at 0 0 90)
			(layer "F.Fab")
			(hide yes)
			(effects
				(font
					(size 1.27 1.27)
					(thickness 0.15)
				)
			)
		)
		(property "Author" "Antmicro"
			(at 345.18 -63.84 0)
			(layer "B.Fab")
			(hide yes)
			(effects
				(font
					(size 1 1)
					(thickness 0.15)
				)
				(justify mirror)
			)
		)
		(property "Dielectric" "X5R"
			(at 345.18 -63.84 0)
			(layer "B.Fab")
			(hide yes)
			(effects
				(font
					(size 1 1)
					(thickness 0.15)
				)
				(justify mirror)
			)
		)
		(property "License" "Apache-2.0"
			(at 345.18 -63.84 0)
			(layer "B.Fab")
			(hide yes)
			(effects
				(font
					(size 1 1)
					(thickness 0.15)
				)
				(justify mirror)
			)
		)
		(property "MPN" "GRM155R61H104KE14D"
			(at 345.18 -63.84 0)
			(layer "B.Fab")
			(hide yes)
			(effects
				(font
					(size 1 1)
					(thickness 0.15)
				)
				(justify mirror)
			)
		)
		(property "Manufacturer" "Murata"
			(at 345.18 -63.84 0)
			(layer "B.Fab")
			(hide yes)
			(effects
				(font
					(size 1 1)
					(thickness 0.15)
				)
				(justify mirror)
			)
		)
		(property "Public" ""
			(at 345.18 -63.84 0)
			(layer "B.Fab")
			(hide yes)
			(effects
				(font
					(size 1 1)
					(thickness 0.15)
				)
				(justify mirror)
			)
		)
		(property "Val" "100n"
			(at 345.18 -63.84 0)
			(layer "B.Fab")
			(hide yes)
			(effects
				(font
					(size 1 1)
					(thickness 0.15)
				)
				(justify mirror)
			)
		)
		(property "Voltage" "50V"
			(at 345.18 -63.84 0)
			(layer "B.Fab")
			(hide yes)
			(effects
				(font
					(size 1 1)
					(thickness 0.15)
				)
				(justify mirror)
			)
		)
		(sheetname "/FPGA Supply/")
		(sheetfile "fpga-supply.kicad_sch")
		(attr smd)
		(fp_rect
			(start -0.925 0.47)
			(end 0.925 -0.47)
			(stroke
				(width 0.05)
				(type default)
			)
			(fill no)
			(layer "B.CrtYd")
		)
		(fp_line
			(start 0.504 -0.248)
			(end -0.494 -0.248)
			(stroke
				(width 0.15)
				(type solid)
			)
			(layer "B.Fab")
		)
		(fp_line
			(start -0.494 -0.248)
			(end -0.494 0.25)
			(stroke
				(width 0.15)
				(type solid)
			)
			(layer "B.Fab")
		)
		(fp_line
			(start 0.504 0.25)
			(end 0.504 -0.248)
			(stroke
				(width 0.15)
				(type solid)
			)
			(layer "B.Fab")
		)
		(fp_line
			(start -0.494 0.25)
			(end 0.504 0.25)
			(stroke
				(width 0.15)
				(type solid)
			)
			(layer "B.Fab")
		)
		(fp_text user "Author: Antmicro"
			(at -0.939 -3.399 270)
			(layer "B.Fab")
			(effects
				(font
					(size 0.7 0.7)
					(thickness 0.15)
				)
				(justify left bottom mirror)
			)
		)
		(fp_text user "${REFERENCE}"
			(at -0.939 -4.599 270)
			(layer "B.Fab")
			(effects
				(font
					(size 0.7 0.7)
					(thickness 0.15)
				)
				(justify left bottom mirror)
			)
		)
		(fp_text user "License: Apache-2.0"
			(at -0.939 -5.799 270)
			(layer "B.Fab")
			(effects
				(font
					(size 0.7 0.7)
					(thickness 0.15)
				)
				(justify left bottom mirror)
			)
		)
		(pad "1" smd roundrect
			(at -0.48 0 90)
			(size 0.59 0.64)
			(layers "B.Cu" "B.Mask" "B.Paste")
			(roundrect_rratio 0.25)
			(net 417 "GND")
			(pintype "passive")
		)
		(pad "2" smd roundrect
			(at 0.48 0 90)
			(size 0.59 0.64)
			(layers "B.Cu" "B.Mask" "B.Paste")
			(roundrect_rratio 0.25)
			(net 649 "VDD")
			(pintype "passive")
		)
	)
	(footprint "antmicro-footprints:C_0402_1005Metric"
		(layer "B.Cu")
		(at 222.9 147.295 90)
		(descr "Capacitor SMD 0402")
		(tags "capacitor SMD 0402")
		(property "Reference" "C283"
			(at -3.725 0.87 90)
			(layer "B.SilkS")
			(effects
				(font
					(size 0.7 0.7)
					(thickness 0.15)
				)
				(justify right bottom mirror)
			)
		)
		(property "Value" "C_10u_0402"
			(at -1.022927 -2.155213 90)
			(layer "B.Fab")
			(hide yes)
			(effects
				(font
					(size 0.7 0.7)
					(thickness 0.15)
				)
				(justify right bottom mirror)
			)
		)
		(property "Datasheet" "https://www.yageo.com/en/Chart/Download/pdf/CC0402MRX5R5BB106"
			(at 0 0 90)
			(layer "F.Fab")
			(hide yes)
			(effects
				(font
					(size 1.27 1.27)
					(thickness 0.15)
				)
			)
		)
		(property "Description" "SMD Multilayer Ceramic Capacitor, 10 µF, 6.3 V, 0402 [1005 Metric], ± 20%, X5R, CC Series"
			(at 0 0 90)
			(layer "F.Fab")
			(hide yes)
			(effects
				(font
					(size 1.27 1.27)
					(thickness 0.15)
				)
			)
		)
		(property "Author" "Antmicro"
			(at 370.195 -75.605 0)
			(layer "B.Fab")
			(hide yes)
			(effects
				(font
					(size 1 1)
					(thickness 0.15)
				)
				(justify mirror)
			)
		)
		(property "Dielectric" ""
			(at 370.195 -75.605 0)
			(layer "B.Fab")
			(hide yes)
			(effects
				(font
					(size 1 1)
					(thickness 0.15)
				)
				(justify mirror)
			)
		)
		(property "License" "Apache-2.0"
			(at 370.195 -75.605 0)
			(layer "B.Fab")
			(hide yes)
			(effects
				(font
					(size 1 1)
					(thickness 0.15)
				)
				(justify mirror)
			)
		)
		(property "MPN" "CC0402MRX5R5BB106"
			(at 370.195 -75.605 0)
			(layer "B.Fab")
			(hide yes)
			(effects
				(font
					(size 1 1)
					(thickness 0.15)
				)
				(justify mirror)
			)
		)
		(property "Manufacturer" "YAGEO"
			(at 370.195 -75.605 0)
			(layer "B.Fab")
			(hide yes)
			(effects
				(font
					(size 1 1)
					(thickness 0.15)
				)
				(justify mirror)
			)
		)
		(property "Public" ""
			(at 370.195 -75.605 0)
			(layer "B.Fab")
			(hide yes)
			(effects
				(font
					(size 1 1)
					(thickness 0.15)
				)
				(justify mirror)
			)
		)
		(property "Val" "10u"
			(at 370.195 -75.605 0)
			(layer "B.Fab")
			(hide yes)
			(effects
				(font
					(size 1 1)
					(thickness 0.15)
				)
				(justify mirror)
			)
		)
		(property "Voltage" ""
			(at 370.195 -75.605 0)
			(layer "B.Fab")
			(hide yes)
			(effects
				(font
					(size 1 1)
					(thickness 0.15)
				)
				(justify mirror)
			)
		)
		(sheetname "/WiFi_Bluetooth/")
		(sheetfile "wifi_bt.kicad_sch")
		(attr smd)
		(fp_rect
			(start -0.925 0.47)
			(end 0.925 -0.47)
			(stroke
				(width 0.05)
				(type default)
			)
			(fill no)
			(layer "B.CrtYd")
		)
		(fp_line
			(start 0.504 -0.248)
			(end -0.494 -0.248)
			(stroke
				(width 0.15)
				(type solid)
			)
			(layer "B.Fab")
		)
		(fp_line
			(start -0.494 -0.248)
			(end -0.494 0.25)
			(stroke
				(width 0.15)
				(type solid)
			)
			(layer "B.Fab")
		)
		(fp_line
			(start 0.504 0.25)
			(end 0.504 -0.248)
			(stroke
				(width 0.15)
				(type solid)
			)
			(layer "B.Fab")
		)
		(fp_line
			(start -0.494 0.25)
			(end 0.504 0.25)
			(stroke
				(width 0.15)
				(type solid)
			)
			(layer "B.Fab")
		)
		(fp_text user "${REFERENCE}"
			(at -0.939 -4.599 270)
			(layer "B.Fab")
			(effects
				(font
					(size 0.7 0.7)
					(thickness 0.15)
				)
				(justify left bottom mirror)
			)
		)
		(fp_text user "License: Apache-2.0"
			(at -0.939 -5.799 270)
			(layer "B.Fab")
			(effects
				(font
					(size 0.7 0.7)
					(thickness 0.15)
				)
				(justify left bottom mirror)
			)
		)
		(fp_text user "Author: Antmicro"
			(at -0.939 -3.399 270)
			(layer "B.Fab")
			(effects
				(font
					(size 0.7 0.7)
					(thickness 0.15)
				)
				(justify left bottom mirror)
			)
		)
		(pad "1" smd roundrect
			(at -0.48 0 90)
			(size 0.59 0.64)
			(layers "B.Cu" "B.Mask" "B.Paste")
			(roundrect_rratio 0.25)
			(net 417 "GND")
			(pintype "passive")
		)
		(pad "2" smd roundrect
			(at 0.48 0 90)
			(size 0.59 0.64)
			(layers "B.Cu" "B.Mask" "B.Paste")
			(roundrect_rratio 0.25)
			(net 50 "+3V3")
			(pintype "passive")
		)
	)
	(footprint "antmicro-footprints:R_Array_4x0201_Panasonic_EXB18V"
		(layer "B.Cu")
		(at 196.75 121.65 -90)
		(property "Reference" "R24"
			(at 1.15 -1.625 90)
			(layer "B.SilkS")
			(effects
				(font
					(size 0.7 0.7)
					(thickness 0.15)
				)
				(justify right bottom mirror)
			)
		)
		(property "Value" "R_4x0R_0201_array"
			(at -1.1 -1.8 90)
			(layer "B.Fab")
			(hide yes)
			(effects
				(font
					(size 0.7 0.7)
					(thickness 0.15)
				)
				(justify left bottom mirror)
			)
		)
		(property "Datasheet" "http://industrial.panasonic.com/cdbs/www-data/pdf/AOC0000/AOC0000C14.pdf"
			(at 0 0 270)
			(layer "F.Fab")
			(hide yes)
			(effects
				(font
					(size 1.27 1.27)
					(thickness 0.15)
				)
			)
		)
		(property "Description" "Zero Ohm Network Resistor, Jumper, 0201 [0603 Metric], Thick Film, Isolated, Flat, 4 Resistors"
			(at 0 0 270)
			(layer "F.Fab")
			(hide yes)
			(effects
				(font
					(size 1.27 1.27)
					(thickness 0.15)
				)
			)
		)
		(property "Author" "Antmicro"
			(at 75.1 318.4 0)
			(layer "B.Fab")
			(hide yes)
			(effects
				(font
					(size 1 1)
					(thickness 0.15)
				)
				(justify mirror)
			)
		)
		(property "License" "Apache-2.0"
			(at 75.1 318.4 0)
			(layer "B.Fab")
			(hide yes)
			(effects
				(font
					(size 1 1)
					(thickness 0.15)
				)
				(justify mirror)
			)
		)
		(property "MPN" "EXB-18VR000X"
			(at 75.1 318.4 0)
			(layer "B.Fab")
			(hide yes)
			(effects
				(font
					(size 1 1)
					(thickness 0.15)
				)
				(justify mirror)
			)
		)
		(property "Manufacturer" "Panasonic"
			(at 75.1 318.4 0)
			(layer "B.Fab")
			(hide yes)
			(effects
				(font
					(size 1 1)
					(thickness 0.15)
				)
				(justify mirror)
			)
		)
		(property "Val" "4x0R_0201"
			(at 75.1 318.4 0)
			(layer "B.Fab")
			(hide yes)
			(effects
				(font
					(size 1 1)
					(thickness 0.15)
				)
				(justify mirror)
			)
		)
		(sheetname "/FPGA MSSIO/")
		(sheetfile "fpga-mssio.kicad_sch")
		(attr smd)
		(fp_line
			(start -0.8 0.45)
			(end -0.8 -0.45)
			(stroke
				(width 0.12)
				(type solid)
			)
			(layer "B.SilkS")
		)
		(fp_line
			(start 0.8 0.45)
			(end 0.8 -0.45)
			(stroke
				(width 0.12)
				(type solid)
			)
			(layer "B.SilkS")
		)
		(fp_rect
			(start -0.898 0.66)
			(end 0.898 -0.65)
			(stroke
				(width 0.05)
				(type solid)
			)
			(fill no)
			(layer "B.CrtYd")
		)
		(fp_text user "License: Apache-2.0"
			(at -1.051 -6 90)
			(layer "B.Fab")
			(effects
				(font
					(size 0.7 0.7)
					(thickness 0.15)
				)
				(justify left bottom mirror)
			)
		)
		(fp_text user "${REFERENCE}"
			(at -1.051 -3.2 90)
			(layer "B.Fab")
			(effects
				(font
					(size 0.7 0.7)
					(thickness 0.15)
				)
				(justify left bottom mirror)
			)
		)
		(fp_text user "Author: Antmicro"
			(at -1.051 -4.599 90)
			(layer "B.Fab")
			(effects
				(font
					(size 0.7 0.7)
					(thickness 0.15)
				)
				(justify left bottom mirror)
			)
		)
		(pad "1" smd roundrect
			(at -0.6 -0.298 270)
			(size 0.2 0.4)
			(layers "B.Cu" "B.Mask" "B.Paste")
			(roundrect_rratio 0.25)
			(net 264 "/FPGA MSSIO/EMMC.CLK")
			(pinfunction "R1.1")
			(pintype "passive")
		)
		(pad "2" smd roundrect
			(at -0.202 -0.298 270)
			(size 0.2 0.4)
			(layers "B.Cu" "B.Mask" "B.Paste")
			(roundrect_rratio 0.25)
			(net 391 "/FPGA MSSIO/EMMC.CMD")
			(pinfunction "R2.1")
			(pintype "passive")
		)
		(pad "3" smd roundrect
			(at 0.2 -0.298 270)
			(size 0.2 0.4)
			(layers "B.Cu" "B.Mask" "B.Paste")
			(roundrect_rratio 0.25)
			(net 390 "/FPGA MSSIO/EMMC.STRB")
			(pinfunction "R3.1")
			(pintype "passive")
		)
		(pad "4" smd roundrect
			(at 0.598 -0.298 270)
			(size 0.2 0.4)
			(layers "B.Cu" "B.Mask" "B.Paste")
			(roundrect_rratio 0.25)
			(net 630 "unconnected-(R24-R4.1-Pad4)")
			(pinfunction "R4.1")
			(pintype "passive+no_connect")
		)
		(pad "5" smd roundrect
			(at 0.598 0.3 270)
			(size 0.2 0.4)
			(layers "B.Cu" "B.Mask" "B.Paste")
			(roundrect_rratio 0.25)
			(net 631 "unconnected-(R24-R4.2-Pad5)")
			(pinfunction "R4.2")
			(pintype "passive+no_connect")
		)
		(pad "6" smd roundrect
			(at 0.2 0.3 270)
			(size 0.2 0.4)
			(layers "B.Cu" "B.Mask" "B.Paste")
			(roundrect_rratio 0.25)
			(net 624 "/FPGA MSSIO/MEM.STRB")
			(pinfunction "R3.2")
			(pintype "passive")
		)
		(pad "7" smd roundrect
			(at -0.202 0.3 270)
			(size 0.2 0.4)
			(layers "B.Cu" "B.Mask" "B.Paste")
			(roundrect_rratio 0.25)
			(net 625 "/FPGA MSSIO/MEM.CMD")
			(pinfunction "R2.2")
			(pintype "passive")
		)
		(pad "8" smd roundrect
			(at -0.6 0.3 270)
			(size 0.2 0.4)
			(layers "B.Cu" "B.Mask" "B.Paste")
			(roundrect_rratio 0.25)
			(net 265 "/FPGA MSSIO/MEM.CLK")
			(pinfunction "R1.2")
			(pintype "passive")
		)
	)
	(footprint "antmicro-footprints:C_0402_1005Metric"
		(layer "B.Cu")
		(at 182.4 136.775 180)
		(descr "Capacitor SMD 0402")
		(tags "capacitor SMD 0402")
		(property "Reference" "C128"
			(at -1.92 0.425 180)
			(layer "B.SilkS")
			(effects
				(font
					(size 0.7 0.7)
					(thickness 0.15)
				)
				(justify left bottom mirror)
			)
		)
		(property "Value" "C_1u_0402"
			(at -1.022927 -2.155213 0)
			(layer "B.Fab")
			(hide yes)
			(effects
				(font
					(size 0.7 0.7)
					(thickness 0.15)
				)
				(justify left bottom mirror)
			)
		)
		(property "Datasheet" "https://product.tdk.com/en/search/capacitor/ceramic/mlcc/info?part_no=C1005X6S1A105K050BC"
			(at 0 0 180)
			(layer "F.Fab")
			(hide yes)
			(effects
				(font
					(size 1.27 1.27)
					(thickness 0.15)
				)
			)
		)
		(property "Description" "SMD Multilayer Ceramic Capacitor, 1 µF, 10 V, 0402 [1005 Metric], ± 10%, X6S, C"
			(at 0 0 180)
			(layer "F.Fab")
			(hide yes)
			(effects
				(font
					(size 1.27 1.27)
					(thickness 0.15)
				)
			)
		)
		(property "Author" "Antmicro"
			(at 364.8 273.55 0)
			(layer "B.Fab")
			(hide yes)
			(effects
				(font
					(size 1 1)
					(thickness 0.15)
				)
				(justify mirror)
			)
		)
		(property "Dielectric" "X5R"
			(at 364.8 273.55 0)
			(layer "B.Fab")
			(hide yes)
			(effects
				(font
					(size 1 1)
					(thickness 0.15)
				)
				(justify mirror)
			)
		)
		(property "License" "Apache-2.0"
			(at 364.8 273.55 0)
			(layer "B.Fab")
			(hide yes)
			(effects
				(font
					(size 1 1)
					(thickness 0.15)
				)
				(justify mirror)
			)
		)
		(property "MPN" "C1005X6S1A105K050BC"
			(at 364.8 273.55 0)
			(layer "B.Fab")
			(hide yes)
			(effects
				(font
					(size 1 1)
					(thickness 0.15)
				)
				(justify mirror)
			)
		)
		(property "Manufacturer" "TDK"
			(at 364.8 273.55 0)
			(layer "B.Fab")
			(hide yes)
			(effects
				(font
					(size 1 1)
					(thickness 0.15)
				)
				(justify mirror)
			)
		)
		(property "Public" ""
			(at 364.8 273.55 0)
			(layer "B.Fab")
			(hide yes)
			(effects
				(font
					(size 1 1)
					(thickness 0.15)
				)
				(justify mirror)
			)
		)
		(property "Val" "1u"
			(at 364.8 273.55 0)
			(layer "B.Fab")
			(hide yes)
			(effects
				(font
					(size 1 1)
					(thickness 0.15)
				)
				(justify mirror)
			)
		)
		(property "Voltage" "16V"
			(at 364.8 273.55 0)
			(layer "B.Fab")
			(hide yes)
			(effects
				(font
					(size 1 1)
					(thickness 0.15)
				)
				(justify mirror)
			)
		)
		(sheetname "/LPDDR4/")
		(sheetfile "lpddr.kicad_sch")
		(attr smd)
		(fp_rect
			(start -0.925 0.47)
			(end 0.925 -0.47)
			(stroke
				(width 0.05)
				(type default)
			)
			(fill no)
			(layer "B.CrtYd")
		)
		(fp_line
			(start 0.504 0.25)
			(end 0.504 -0.248)
			(stroke
				(width 0.15)
				(type solid)
			)
			(layer "B.Fab")
		)
		(fp_line
			(start 0.504 -0.248)
			(end -0.494 -0.248)
			(stroke
				(width 0.15)
				(type solid)
			)
			(layer "B.Fab")
		)
		(fp_line
			(start -0.494 0.25)
			(end 0.504 0.25)
			(stroke
				(width 0.15)
				(type solid)
			)
			(layer "B.Fab")
		)
		(fp_line
			(start -0.494 -0.248)
			(end -0.494 0.25)
			(stroke
				(width 0.15)
				(type solid)
			)
			(layer "B.Fab")
		)
		(fp_text user "Author: Antmicro"
			(at -0.939 -3.399 0)
			(layer "B.Fab")
			(effects
				(font
					(size 0.7 0.7)
					(thickness 0.15)
				)
				(justify left bottom mirror)
			)
		)
		(fp_text user "License: Apache-2.0"
			(at -0.939 -5.799 0)
			(layer "B.Fab")
			(effects
				(font
					(size 0.7 0.7)
					(thickness 0.15)
				)
				(justify left bottom mirror)
			)
		)
		(fp_text user "${REFERENCE}"
			(at -0.939 -4.599 0)
			(layer "B.Fab")
			(effects
				(font
					(size 0.7 0.7)
					(thickness 0.15)
				)
				(justify left bottom mirror)
			)
		)
		(pad "1" smd roundrect
			(at -0.48 0 180)
			(size 0.59 0.64)
			(layers "B.Cu" "B.Mask" "B.Paste")
			(roundrect_rratio 0.25)
			(net 417 "GND")
			(pintype "passive")
		)
		(pad "2" smd roundrect
			(at 0.48 0 180)
			(size 0.59 0.64)
			(layers "B.Cu" "B.Mask" "B.Paste")
			(roundrect_rratio 0.25)
			(net 2 "+1V1")
			(pintype "passive")
		)
	)
	(footprint "antmicro-footprints:R_0402_1005Metric"
		(layer "B.Cu")
		(at 210.1925 127.347)
		(descr "Resistor SMD 0402")
		(tags "resistor SMD 0402")
		(property "Reference" "R33"
			(at -0.8425 0.628 180)
			(layer "B.SilkS")
			(effects
				(font
					(size 0.7 0.7)
					(thickness 0.15)
				)
				(justify left bottom mirror)
			)
		)
		(property "Value" "R_49k9_0402"
			(at -1.011843 -1.772047 180)
			(layer "B.Fab")
			(hide yes)
			(effects
				(font
					(size 0.7 0.7)
					(thickness 0.15)
				)
				(justify left bottom mirror)
			)
		)
		(property "Datasheet" "https://www.bourns.com/docs/product-datasheets/cr.pdf"
			(at 0 0 0)
			(layer "F.Fab")
			(hide yes)
			(effects
				(font
					(size 1.27 1.27)
					(thickness 0.15)
				)
			)
		)
		(property "Description" "SMD Chip Resistor, 49.9 kohm, ± 1%, 63 mW, 0402 [1005 Metric], Thick Film, General Purpose"
			(at 0 0 0)
			(layer "F.Fab")
			(hide yes)
			(effects
				(font
					(size 1.27 1.27)
					(thickness 0.15)
				)
			)
		)
		(property "Author" "Antmicro"
			(at 0 0 0)
			(layer "B.Fab")
			(hide yes)
			(effects
				(font
					(size 1 1)
					(thickness 0.15)
				)
				(justify mirror)
			)
		)
		(property "License" "Apache-2.0"
			(at 0 0 0)
			(layer "B.Fab")
			(hide yes)
			(effects
				(font
					(size 1 1)
					(thickness 0.15)
				)
				(justify mirror)
			)
		)
		(property "MPN" "CR0402-FX-4992GLF"
			(at 0 0 0)
			(layer "B.Fab")
			(hide yes)
			(effects
				(font
					(size 1 1)
					(thickness 0.15)
				)
				(justify mirror)
			)
		)
		(property "Manufacturer" "Bourns"
			(at 0 0 0)
			(layer "B.Fab")
			(hide yes)
			(effects
				(font
					(size 1 1)
					(thickness 0.15)
				)
				(justify mirror)
			)
		)
		(property "Public" ""
			(at 0 0 0)
			(layer "B.Fab")
			(hide yes)
			(effects
				(font
					(size 1 1)
					(thickness 0.15)
				)
				(justify mirror)
			)
		)
		(property "Tolerance" "1%"
			(at 0 0 0)
			(layer "B.Fab")
			(hide yes)
			(effects
				(font
					(size 1 1)
					(thickness 0.15)
				)
				(justify mirror)
			)
		)
		(property "Val" "49k9"
			(at 0 0 0)
			(layer "B.Fab")
			(hide yes)
			(effects
				(font
					(size 1 1)
					(thickness 0.15)
				)
				(justify mirror)
			)
		)
		(sheetname "/Memory/")
		(sheetfile "memory.kicad_sch")
		(attr smd)
		(fp_rect
			(start -0.925 0.47)
			(end 0.925 -0.47)
			(stroke
				(width 0.05)
				(type default)
			)
			(fill no)
			(layer "B.CrtYd")
		)
		(fp_rect
			(start -0.5 0.25)
			(end 0.5 -0.25)
			(stroke
				(width 0.15)
				(type solid)
			)
			(fill no)
			(layer "B.Fab")
		)
		(fp_text user "License: Apache-2.0"
			(at -0.95 -5.169 180)
			(layer "B.Fab")
			(effects
				(font
					(size 0.7 0.7)
					(thickness 0.15)
				)
				(justify left bottom mirror)
			)
		)
		(fp_text user "${REFERENCE}"
			(at -0.95 -3.168 180)
			(layer "B.Fab")
			(effects
				(font
					(size 0.7 0.7)
					(thickness 0.15)
				)
				(justify left bottom mirror)
			)
		)
		(fp_text user "Author: Antmicro"
			(at -0.95 -4.169 180)
			(layer "B.Fab")
			(effects
				(font
					(size 0.7 0.7)
					(thickness 0.15)
				)
				(justify left bottom mirror)
			)
		)
		(pad "1" smd roundrect
			(at -0.48 0)
			(size 0.59 0.64)
			(layers "B.Cu" "B.Mask" "B.Paste")
			(roundrect_rratio 0.25)
			(net 213 "/FPGA MSSIO/EMMC.DAT5")
			(pintype "passive")
		)
		(pad "2" smd roundrect
			(at 0.48 0)
			(size 0.59 0.64)
			(layers "B.Cu" "B.Mask" "B.Paste")
			(roundrect_rratio 0.25)
			(net 137 "SD_VDD")
			(pintype "passive")
		)
	)
	(footprint "antmicro-footprints:R_0402_1005Metric"
		(layer "B.Cu")
		(at 193.95 123.25 180)
		(descr "Resistor SMD 0402")
		(tags "resistor SMD 0402")
		(property "Reference" "R75"
			(at -1.1 1.6 0)
			(layer "B.SilkS")
			(effects
				(font
					(size 0.7 0.7)
					(thickness 0.15)
				)
				(justify left bottom mirror)
			)
		)
		(property "Value" "R_1k_0402"
			(at -1.011843 -1.772047 0)
			(layer "B.Fab")
			(hide yes)
			(effects
				(font
					(size 0.7 0.7)
					(thickness 0.15)
				)
				(justify left bottom mirror)
			)
		)
		(property "Datasheet" "https://www.bourns.com/docs/product-datasheets/cr.pdf"
			(at 0 0 180)
			(layer "F.Fab")
			(hide yes)
			(effects
				(font
					(size 1.27 1.27)
					(thickness 0.15)
				)
			)
		)
		(property "Description" "SMD Chip Resistor, 1 kohm, ± 1%, 63 mW, 0402 [1005 Metric], Thick Film, General Purpose"
			(at 0 0 180)
			(layer "F.Fab")
			(hide yes)
			(effects
				(font
					(size 1.27 1.27)
					(thickness 0.15)
				)
			)
		)
		(property "Author" "Antmicro"
			(at 387.9 246.5 0)
			(layer "B.Fab")
			(hide yes)
			(effects
				(font
					(size 1 1)
					(thickness 0.15)
				)
				(justify mirror)
			)
		)
		(property "License" "Apache-2.0"
			(at 387.9 246.5 0)
			(layer "B.Fab")
			(hide yes)
			(effects
				(font
					(size 1 1)
					(thickness 0.15)
				)
				(justify mirror)
			)
		)
		(property "MPN" "CR0402-FX-1001GLF"
			(at 387.9 246.5 0)
			(layer "B.Fab")
			(hide yes)
			(effects
				(font
					(size 1 1)
					(thickness 0.15)
				)
				(justify mirror)
			)
		)
		(property "Manufacturer" "Bourns"
			(at 387.9 246.5 0)
			(layer "B.Fab")
			(hide yes)
			(effects
				(font
					(size 1 1)
					(thickness 0.15)
				)
				(justify mirror)
			)
		)
		(property "Public" ""
			(at 387.9 246.5 0)
			(layer "B.Fab")
			(hide yes)
			(effects
				(font
					(size 1 1)
					(thickness 0.15)
				)
				(justify mirror)
			)
		)
		(property "Tolerance" "1%"
			(at 387.9 246.5 0)
			(layer "B.Fab")
			(hide yes)
			(effects
				(font
					(size 1 1)
					(thickness 0.15)
				)
				(justify mirror)
			)
		)
		(property "Val" "1k"
			(at 387.9 246.5 0)
			(layer "B.Fab")
			(hide yes)
			(effects
				(font
					(size 1 1)
					(thickness 0.15)
				)
				(justify mirror)
			)
		)
		(sheetname "/FPGA MSS/")
		(sheetfile "fpga-mss.kicad_sch")
		(attr smd)
		(fp_rect
			(start -0.925 0.47)
			(end 0.925 -0.47)
			(stroke
				(width 0.05)
				(type default)
			)
			(fill no)
			(layer "B.CrtYd")
		)
		(fp_rect
			(start -0.5 0.25)
			(end 0.5 -0.25)
			(stroke
				(width 0.15)
				(type solid)
			)
			(fill no)
			(layer "B.Fab")
		)
		(fp_text user "${REFERENCE}"
			(at -0.95 -3.168 0)
			(layer "B.Fab")
			(effects
				(font
					(size 0.7 0.7)
					(thickness 0.15)
				)
				(justify left bottom mirror)
			)
		)
		(fp_text user "License: Apache-2.0"
			(at -0.95 -5.169 0)
			(layer "B.Fab")
			(effects
				(font
					(size 0.7 0.7)
					(thickness 0.15)
				)
				(justify left bottom mirror)
			)
		)
		(fp_text user "Author: Antmicro"
			(at -0.95 -4.169 0)
			(layer "B.Fab")
			(effects
				(font
					(size 0.7 0.7)
					(thickness 0.15)
				)
				(justify left bottom mirror)
			)
		)
		(pad "1" smd roundrect
			(at -0.48 0 180)
			(size 0.59 0.64)
			(layers "B.Cu" "B.Mask" "B.Paste")
			(roundrect_rratio 0.25)
			(net 417 "GND")
			(pintype "passive")
		)
		(pad "2" smd roundrect
			(at 0.48 0 180)
			(size 0.59 0.64)
			(layers "B.Cu" "B.Mask" "B.Paste")
			(roundrect_rratio 0.25)
			(net 270 "Net-(U1G-MSS_DDR_VREF_IN)")
			(pintype "passive")
		)
	)
	(footprint "antmicro-footprints:XSON-8_1x1.95mm_P0.5mm"
		(layer "B.Cu")
		(at 221.04 141.62)
		(property "Reference" "U27"
			(at -1.23 2.17 0)
			(layer "B.SilkS")
			(effects
				(font
					(size 0.7 0.7)
					(thickness 0.15)
				)
				(justify right bottom mirror)
			)
		)
		(property "Value" "NTS0102_XSON"
			(at 0 -2.2 0)
			(layer "B.Fab")
			(hide yes)
			(effects
				(font
					(size 0.7 0.7)
					(thickness 0.15)
				)
				(justify right bottom mirror)
			)
		)
		(property "Datasheet" "http://www.farnell.com/datasheets/1760723.pdf"
			(at 0 0 0)
			(layer "F.Fab")
			(hide yes)
			(effects
				(font
					(size 1.27 1.27)
					(thickness 0.15)
				)
			)
		)
		(property "Description" "Transceiver, 1.65 V to 3.6 V, XSON-8"
			(at 0 0 0)
			(layer "F.Fab")
			(hide yes)
			(effects
				(font
					(size 1.27 1.27)
					(thickness 0.15)
				)
			)
		)
		(property "Author" "Antmicro"
			(at 0 0 0)
			(layer "B.Fab")
			(hide yes)
			(effects
				(font
					(size 1 1)
					(thickness 0.15)
				)
				(justify mirror)
			)
		)
		(property "License" "Apache-2.0"
			(at 0 0 0)
			(layer "B.Fab")
			(hide yes)
			(effects
				(font
					(size 1 1)
					(thickness 0.15)
				)
				(justify mirror)
			)
		)
		(property "MPN" "NTS0102GT"
			(at 0 0 0)
			(layer "B.Fab")
			(hide yes)
			(effects
				(font
					(size 1 1)
					(thickness 0.15)
				)
				(justify mirror)
			)
		)
		(property "Manufacturer" "NXP"
			(at 0 0 0)
			(layer "B.Fab")
			(hide yes)
			(effects
				(font
					(size 1 1)
					(thickness 0.15)
				)
				(justify mirror)
			)
		)
		(sheetname "/FPGA GPIO/")
		(sheetfile "fpga-gpio.kicad_sch")
		(attr smd)
		(fp_line
			(start -0.5 1.1)
			(end 0.5 1.1)
			(stroke
				(width 0.15)
				(type solid)
			)
			(layer "B.SilkS")
		)
		(fp_line
			(start 0.5 -1.1)
			(end -0.5 -1.1)
			(stroke
				(width 0.15)
				(type solid)
			)
			(layer "B.SilkS")
		)
		(fp_circle
			(center -0.75 1.1)
			(end -0.701 1.1)
			(stroke
				(width 0.15)
				(type solid)
			)
			(fill no)
			(layer "B.SilkS")
		)
		(fp_rect
			(start -0.8 1.2)
			(end 0.8 -1.2)
			(stroke
				(width 0.05)
				(type solid)
			)
			(fill no)
			(layer "B.CrtYd")
		)
		(fp_line
			(start -0.5305 -1)
			(end -0.5305 1.001)
			(stroke
				(width 0.15)
				(type solid)
			)
			(layer "B.Fab")
		)
		(fp_line
			(start -0.5305 1.001)
			(end 0.5305 1.001)
			(stroke
				(width 0.15)
				(type solid)
			)
			(layer "B.Fab")
		)
		(fp_line
			(start 0.5305 -1)
			(end -0.5305 -1)
			(stroke
				(width 0.15)
				(type solid)
			)
			(layer "B.Fab")
		)
		(fp_line
			(start 0.5305 1.001)
			(end 0.5305 -1)
			(stroke
				(width 0.15)
				(type solid)
			)
			(layer "B.Fab")
		)
		(fp_text user "${REFERENCE}"
			(at -0.527 -5.905 180)
			(layer "B.Fab")
			(effects
				(font
					(size 0.7 0.7)
					(thickness 0.15)
				)
				(justify left bottom mirror)
			)
		)
		(fp_text user "License: Apache-2.0"
			(at -0.527 -8.306 180)
			(layer "B.Fab")
			(effects
				(font
					(size 0.7 0.7)
					(thickness 0.15)
				)
				(justify left bottom mirror)
			)
		)
		(fp_text user "Author: Antmicro"
			(at -0.527 -7.105 180)
			(layer "B.Fab")
			(effects
				(font
					(size 0.7 0.7)
					(thickness 0.15)
				)
				(justify left bottom mirror)
			)
		)
		(pad "1" smd roundrect
			(at -0.45 0.75 180)
			(size 0.6 0.3)
			(layers "B.Cu" "B.Mask" "B.Paste")
			(roundrect_rratio 0.25)
			(net 128 "/FPGA GPIO/WiFi.DAT3")
			(pinfunction "B_{2}")
			(pintype "bidirectional")
		)
		(pad "2" smd roundrect
			(at -0.45 0.25 180)
			(size 0.6 0.25)
			(layers "B.Cu" "B.Mask" "B.Paste")
			(roundrect_rratio 0.25)
			(net 417 "GND")
			(pinfunction "GND")
			(pintype "power_in")
		)
		(pad "3" smd roundrect
			(at -0.45 -0.25 180)
			(size 0.6 0.25)
			(layers "B.Cu" "B.Mask" "B.Paste")
			(roundrect_rratio 0.25)
			(net 649 "VDD")
			(pinfunction "VCC_{A}")
			(pintype "power_in")
		)
		(pad "4" smd roundrect
			(at -0.45 -0.75 180)
			(size 0.6 0.3)
			(layers "B.Cu" "B.Mask" "B.Paste")
			(roundrect_rratio 0.25)
			(net 351 "/FPGA GPIO/WiFi_DATA_3")
			(pinfunction "A_{2}")
			(pintype "bidirectional")
		)
		(pad "5" smd roundrect
			(at 0.45 -0.75 180)
			(size 0.6 0.3)
			(layers "B.Cu" "B.Mask" "B.Paste")
			(roundrect_rratio 0.25)
			(net 374 "/FPGA GPIO/WiFi_DATA_0")
			(pinfunction "A_{1}")
			(pintype "bidirectional")
		)
		(pad "6" smd roundrect
			(at 0.45 -0.25 180)
			(size 0.6 0.25)
			(layers "B.Cu" "B.Mask" "B.Paste")
			(roundrect_rratio 0.25)
			(net 649 "VDD")
			(pinfunction "OE")
			(pintype "input")
		)
		(pad "7" smd roundrect
			(at 0.45 0.25 180)
			(size 0.6 0.25)
			(layers "B.Cu" "B.Mask" "B.Paste")
			(roundrect_rratio 0.25)
			(net 50 "+3V3")
			(pinfunction "VCC_{B}")
			(pintype "power_in")
		)
		(pad "8" smd roundrect
			(at 0.45 0.75 180)
			(size 0.6 0.3)
			(layers "B.Cu" "B.Mask" "B.Paste")
			(roundrect_rratio 0.25)
			(net 240 "/FPGA GPIO/WiFi.DAT0")
			(pinfunction "B_{1}")
			(pintype "bidirectional")
		)
	)
	(footprint "antmicro-footprints:C_0402_1005Metric"
		(layer "B.Cu")
		(at 208.1 146.475 180)
		(descr "Capacitor SMD 0402")
		(tags "capacitor SMD 0402")
		(property "Reference" "C196"
			(at 4.9 18.375 0)
			(layer "B.SilkS")
			(effects
				(font
					(size 0.7 0.7)
					(thickness 0.15)
				)
				(justify left bottom mirror)
			)
		)
		(property "Value" "C_10u_10V_0402"
			(at -1.022927 -2.155213 0)
			(layer "B.Fab")
			(hide yes)
			(effects
				(font
					(size 0.7 0.7)
					(thickness 0.15)
				)
				(justify left bottom mirror)
			)
		)
		(property "Datasheet" "https://www.murata.com/products/productdetail?partno=GRM155R61A106ME11%23"
			(at 0 0 180)
			(layer "F.Fab")
			(hide yes)
			(effects
				(font
					(size 1.27 1.27)
					(thickness 0.15)
				)
			)
		)
		(property "Description" "Multilayer Ceramic Capacitors MLCC - SMD/SMT 10 uF 10 VDC 20% 0402 X5R"
			(at 0 0 180)
			(layer "F.Fab")
			(hide yes)
			(effects
				(font
					(size 1.27 1.27)
					(thickness 0.15)
				)
			)
		)
		(property "Author" "Antmicro"
			(at 416.2 292.95 0)
			(layer "B.Fab")
			(hide yes)
			(effects
				(font
					(size 1 1)
					(thickness 0.15)
				)
				(justify mirror)
			)
		)
		(property "Dielectric" "X5R"
			(at 416.2 292.95 0)
			(layer "B.Fab")
			(hide yes)
			(effects
				(font
					(size 1 1)
					(thickness 0.15)
				)
				(justify mirror)
			)
		)
		(property "License" "Apache-2.0"
			(at 416.2 292.95 0)
			(layer "B.Fab")
			(hide yes)
			(effects
				(font
					(size 1 1)
					(thickness 0.15)
				)
				(justify mirror)
			)
		)
		(property "MPN" "GRM155R61A106ME11D"
			(at 416.2 292.95 0)
			(layer "B.Fab")
			(hide yes)
			(effects
				(font
					(size 1 1)
					(thickness 0.15)
				)
				(justify mirror)
			)
		)
		(property "Manufacturer" "Murata"
			(at 416.2 292.95 0)
			(layer "B.Fab")
			(hide yes)
			(effects
				(font
					(size 1 1)
					(thickness 0.15)
				)
				(justify mirror)
			)
		)
		(property "Public" ""
			(at 416.2 292.95 0)
			(layer "B.Fab")
			(hide yes)
			(effects
				(font
					(size 1 1)
					(thickness 0.15)
				)
				(justify mirror)
			)
		)
		(property "Val" "10u"
			(at 416.2 292.95 0)
			(layer "B.Fab")
			(hide yes)
			(effects
				(font
					(size 1 1)
					(thickness 0.15)
				)
				(justify mirror)
			)
		)
		(property "Voltage" "10V"
			(at 416.2 292.95 0)
			(layer "B.Fab")
			(hide yes)
			(effects
				(font
					(size 1 1)
					(thickness 0.15)
				)
				(justify mirror)
			)
		)
		(sheetname "/MIPI CrossLink/")
		(sheetfile "crosslink.kicad_sch")
		(attr smd)
		(fp_rect
			(start -0.925 0.47)
			(end 0.925 -0.47)
			(stroke
				(width 0.05)
				(type default)
			)
			(fill no)
			(layer "B.CrtYd")
		)
		(fp_line
			(start 0.504 0.25)
			(end 0.504 -0.248)
			(stroke
				(width 0.15)
				(type solid)
			)
			(layer "B.Fab")
		)
		(fp_line
			(start 0.504 -0.248)
			(end -0.494 -0.248)
			(stroke
				(width 0.15)
				(type solid)
			)
			(layer "B.Fab")
		)
		(fp_line
			(start -0.494 0.25)
			(end 0.504 0.25)
			(stroke
				(width 0.15)
				(type solid)
			)
			(layer "B.Fab")
		)
		(fp_line
			(start -0.494 -0.248)
			(end -0.494 0.25)
			(stroke
				(width 0.15)
				(type solid)
			)
			(layer "B.Fab")
		)
		(fp_text user "${REFERENCE}"
			(at -0.939 -4.599 0)
			(layer "B.Fab")
			(effects
				(font
					(size 0.7 0.7)
					(thickness 0.15)
				)
				(justify left bottom mirror)
			)
		)
		(fp_text user "Author: Antmicro"
			(at -0.939 -3.399 0)
			(layer "B.Fab")
			(effects
				(font
					(size 0.7 0.7)
					(thickness 0.15)
				)
				(justify left bottom mirror)
			)
		)
		(fp_text user "License: Apache-2.0"
			(at -0.939 -5.799 0)
			(layer "B.Fab")
			(effects
				(font
					(size 0.7 0.7)
					(thickness 0.15)
				)
				(justify left bottom mirror)
			)
		)
		(pad "1" smd roundrect
			(at -0.48 0 180)
			(size 0.59 0.64)
			(layers "B.Cu" "B.Mask" "B.Paste")
			(roundrect_rratio 0.25)
			(net 417 "GND")
			(pintype "passive")
		)
		(pad "2" smd roundrect
			(at 0.48 0 180)
			(size 0.59 0.64)
			(layers "B.Cu" "B.Mask" "B.Paste")
			(roundrect_rratio 0.25)
			(net 183 "/MIPI CrossLink/CL_VCCIO0")
			(pintype "passive")
		)
	)
	(footprint "antmicro-footprints:C_0402_1005Metric"
		(layer "B.Cu")
		(at 197.299 127.19 -90)
		(descr "Capacitor SMD 0402")
		(tags "capacitor SMD 0402")
		(property "Reference" "C6"
			(at -1.14 -1.351 90)
			(layer "B.SilkS")
			(effects
				(font
					(size 0.7 0.7)
					(thickness 0.15)
				)
				(justify left bottom mirror)
			)
		)
		(property "Value" "C_100n_0402"
			(at -1.022927 -2.155213 90)
			(layer "B.Fab")
			(hide yes)
			(effects
				(font
					(size 0.7 0.7)
					(thickness 0.15)
				)
				(justify left bottom mirror)
			)
		)
		(property "Datasheet" "https://www.murata.com/products/productdetail?partno=GRM155R61H104KE14%23"
			(at 0 0 270)
			(layer "F.Fab")
			(hide yes)
			(effects
				(font
					(size 1.27 1.27)
					(thickness 0.15)
				)
			)
		)
		(property "Description" "SMD Multilayer Ceramic Capacitor, 0.1 µF, 50 V, 0402 [1005 Metric], ± 10%, X5R, GRM Series"
			(at 0 0 270)
			(layer "F.Fab")
			(hide yes)
			(effects
				(font
					(size 1.27 1.27)
					(thickness 0.15)
				)
			)
		)
		(property "Author" "Antmicro"
			(at 70.109 324.489 0)
			(layer "B.Fab")
			(hide yes)
			(effects
				(font
					(size 1 1)
					(thickness 0.15)
				)
				(justify mirror)
			)
		)
		(property "Dielectric" "X5R"
			(at 70.109 324.489 0)
			(layer "B.Fab")
			(hide yes)
			(effects
				(font
					(size 1 1)
					(thickness 0.15)
				)
				(justify mirror)
			)
		)
		(property "License" "Apache-2.0"
			(at 70.109 324.489 0)
			(layer "B.Fab")
			(hide yes)
			(effects
				(font
					(size 1 1)
					(thickness 0.15)
				)
				(justify mirror)
			)
		)
		(property "MPN" "GRM155R61H104KE14D"
			(at 70.109 324.489 0)
			(layer "B.Fab")
			(hide yes)
			(effects
				(font
					(size 1 1)
					(thickness 0.15)
				)
				(justify mirror)
			)
		)
		(property "Manufacturer" "Murata"
			(at 70.109 324.489 0)
			(layer "B.Fab")
			(hide yes)
			(effects
				(font
					(size 1 1)
					(thickness 0.15)
				)
				(justify mirror)
			)
		)
		(property "Public" ""
			(at 70.109 324.489 0)
			(layer "B.Fab")
			(hide yes)
			(effects
				(font
					(size 1 1)
					(thickness 0.15)
				)
				(justify mirror)
			)
		)
		(property "Val" "100n"
			(at 70.109 324.489 0)
			(layer "B.Fab")
			(hide yes)
			(effects
				(font
					(size 1 1)
					(thickness 0.15)
				)
				(justify mirror)
			)
		)
		(property "Voltage" "50V"
			(at 70.109 324.489 0)
			(layer "B.Fab")
			(hide yes)
			(effects
				(font
					(size 1 1)
					(thickness 0.15)
				)
				(justify mirror)
			)
		)
		(sheetname "/FPGA Supply/")
		(sheetfile "fpga-supply.kicad_sch")
		(attr smd)
		(fp_rect
			(start -0.925 0.47)
			(end 0.925 -0.47)
			(stroke
				(width 0.05)
				(type default)
			)
			(fill no)
			(layer "B.CrtYd")
		)
		(fp_line
			(start -0.494 0.25)
			(end 0.504 0.25)
			(stroke
				(width 0.15)
				(type solid)
			)
			(layer "B.Fab")
		)
		(fp_line
			(start 0.504 0.25)
			(end 0.504 -0.248)
			(stroke
				(width 0.15)
				(type solid)
			)
			(layer "B.Fab")
		)
		(fp_line
			(start -0.494 -0.248)
			(end -0.494 0.25)
			(stroke
				(width 0.15)
				(type solid)
			)
			(layer "B.Fab")
		)
		(fp_line
			(start 0.504 -0.248)
			(end -0.494 -0.248)
			(stroke
				(width 0.15)
				(type solid)
			)
			(layer "B.Fab")
		)
		(fp_text user "Author: Antmicro"
			(at -0.939 -3.399 90)
			(layer "B.Fab")
			(effects
				(font
					(size 0.7 0.7)
					(thickness 0.15)
				)
				(justify left bottom mirror)
			)
		)
		(fp_text user "${REFERENCE}"
			(at -0.939 -4.599 90)
			(layer "B.Fab")
			(effects
				(font
					(size 0.7 0.7)
					(thickness 0.15)
				)
				(justify left bottom mirror)
			)
		)
		(fp_text user "License: Apache-2.0"
			(at -0.939 -5.799 90)
			(layer "B.Fab")
			(effects
				(font
					(size 0.7 0.7)
					(thickness 0.15)
				)
				(justify left bottom mirror)
			)
		)
		(pad "1" smd roundrect
			(at -0.48 0 270)
			(size 0.59 0.64)
			(layers "B.Cu" "B.Mask" "B.Paste")
			(roundrect_rratio 0.25)
			(net 417 "GND")
			(pintype "passive")
		)
		(pad "2" smd roundrect
			(at 0.48 0 270)
			(size 0.59 0.64)
			(layers "B.Cu" "B.Mask" "B.Paste")
			(roundrect_rratio 0.25)
			(net 50 "+3V3")
			(pintype "passive")
		)
	)
	(footprint "antmicro-footprints:C_0402_1005Metric"
		(layer "B.Cu")
		(at 205 145.9 -90)
		(descr "Capacitor SMD 0402")
		(tags "capacitor SMD 0402")
		(property "Reference" "C198"
			(at -1.85 -1.5 90)
			(layer "B.SilkS")
			(effects
				(font
					(size 0.7 0.7)
					(thickness 0.15)
				)
				(justify left bottom mirror)
			)
		)
		(property "Value" "C_100n_0402"
			(at -1.022927 -2.155213 90)
			(layer "B.Fab")
			(hide yes)
			(effects
				(font
					(size 0.7 0.7)
					(thickness 0.15)
				)
				(justify left bottom mirror)
			)
		)
		(property "Datasheet" "https://www.murata.com/products/productdetail?partno=GRM155R61H104KE14%23"
			(at 0 0 270)
			(layer "F.Fab")
			(hide yes)
			(effects
				(font
					(size 1.27 1.27)
					(thickness 0.15)
				)
			)
		)
		(property "Description" "SMD Multilayer Ceramic Capacitor, 0.1 µF, 50 V, 0402 [1005 Metric], ± 10%, X5R, GRM Series"
			(at 0 0 270)
			(layer "F.Fab")
			(hide yes)
			(effects
				(font
					(size 1.27 1.27)
					(thickness 0.15)
				)
			)
		)
		(property "Author" "Antmicro"
			(at 59.1 350.9 0)
			(layer "B.Fab")
			(hide yes)
			(effects
				(font
					(size 1 1)
					(thickness 0.15)
				)
				(justify mirror)
			)
		)
		(property "Dielectric" "X5R"
			(at 59.1 350.9 0)
			(layer "B.Fab")
			(hide yes)
			(effects
				(font
					(size 1 1)
					(thickness 0.15)
				)
				(justify mirror)
			)
		)
		(property "License" "Apache-2.0"
			(at 59.1 350.9 0)
			(layer "B.Fab")
			(hide yes)
			(effects
				(font
					(size 1 1)
					(thickness 0.15)
				)
				(justify mirror)
			)
		)
		(property "MPN" "GRM155R61H104KE14D"
			(at 59.1 350.9 0)
			(layer "B.Fab")
			(hide yes)
			(effects
				(font
					(size 1 1)
					(thickness 0.15)
				)
				(justify mirror)
			)
		)
		(property "Manufacturer" "Murata"
			(at 59.1 350.9 0)
			(layer "B.Fab")
			(hide yes)
			(effects
				(font
					(size 1 1)
					(thickness 0.15)
				)
				(justify mirror)
			)
		)
		(property "Public" ""
			(at 59.1 350.9 0)
			(layer "B.Fab")
			(hide yes)
			(effects
				(font
					(size 1 1)
					(thickness 0.15)
				)
				(justify mirror)
			)
		)
		(property "Val" "100n"
			(at 59.1 350.9 0)
			(layer "B.Fab")
			(hide yes)
			(effects
				(font
					(size 1 1)
					(thickness 0.15)
				)
				(justify mirror)
			)
		)
		(property "Voltage" "50V"
			(at 59.1 350.9 0)
			(layer "B.Fab")
			(hide yes)
			(effects
				(font
					(size 1 1)
					(thickness 0.15)
				)
				(justify mirror)
			)
		)
		(sheetname "/MIPI CrossLink/")
		(sheetfile "crosslink.kicad_sch")
		(attr smd)
		(fp_rect
			(start -0.925 0.47)
			(end 0.925 -0.47)
			(stroke
				(width 0.05)
				(type default)
			)
			(fill no)
			(layer "B.CrtYd")
		)
		(fp_line
			(start -0.494 0.25)
			(end 0.504 0.25)
			(stroke
				(width 0.15)
				(type solid)
			)
			(layer "B.Fab")
		)
		(fp_line
			(start 0.504 0.25)
			(end 0.504 -0.248)
			(stroke
				(width 0.15)
				(type solid)
			)
			(layer "B.Fab")
		)
		(fp_line
			(start -0.494 -0.248)
			(end -0.494 0.25)
			(stroke
				(width 0.15)
				(type solid)
			)
			(layer "B.Fab")
		)
		(fp_line
			(start 0.504 -0.248)
			(end -0.494 -0.248)
			(stroke
				(width 0.15)
				(type solid)
			)
			(layer "B.Fab")
		)
		(fp_text user "Author: Antmicro"
			(at -0.939 -3.399 90)
			(layer "B.Fab")
			(effects
				(font
					(size 0.7 0.7)
					(thickness 0.15)
				)
				(justify left bottom mirror)
			)
		)
		(fp_text user "License: Apache-2.0"
			(at -0.939 -5.799 90)
			(layer "B.Fab")
			(effects
				(font
					(size 0.7 0.7)
					(thickness 0.15)
				)
				(justify left bottom mirror)
			)
		)
		(fp_text user "${REFERENCE}"
			(at -0.939 -4.599 90)
			(layer "B.Fab")
			(effects
				(font
					(size 0.7 0.7)
					(thickness 0.15)
				)
				(justify left bottom mirror)
			)
		)
		(pad "1" smd roundrect
			(at -0.48 0 270)
			(size 0.59 0.64)
			(layers "B.Cu" "B.Mask" "B.Paste")
			(roundrect_rratio 0.25)
			(net 417 "GND")
			(pintype "passive")
		)
		(pad "2" smd roundrect
			(at 0.48 0 270)
			(size 0.59 0.64)
			(layers "B.Cu" "B.Mask" "B.Paste")
			(roundrect_rratio 0.25)
			(net 183 "/MIPI CrossLink/CL_VCCIO0")
			(pintype "passive")
		)
	)
	(footprint "antmicro-footprints:C_0402_1005Metric"
		(layer "B.Cu")
		(at 215.361 123.254 -90)
		(descr "Capacitor SMD 0402")
		(tags "capacitor SMD 0402")
		(property "Reference" "C191"
			(at 1.886 -0.659 90)
			(layer "B.SilkS")
			(effects
				(font
					(size 0.7 0.7)
					(thickness 0.15)
				)
				(justify left bottom mirror)
			)
		)
		(property "Value" "C_100n_0402"
			(at -1.022927 -2.155213 90)
			(layer "B.Fab")
			(hide yes)
			(effects
				(font
					(size 0.7 0.7)
					(thickness 0.15)
				)
				(justify left bottom mirror)
			)
		)
		(property "Datasheet" "https://www.murata.com/products/productdetail?partno=GRM155R61H104KE14%23"
			(at 0 0 270)
			(layer "F.Fab")
			(hide yes)
			(effects
				(font
					(size 1.27 1.27)
					(thickness 0.15)
				)
			)
		)
		(property "Description" "SMD Multilayer Ceramic Capacitor, 0.1 µF, 50 V, 0402 [1005 Metric], ± 10%, X5R, GRM Series"
			(at 0 0 270)
			(layer "F.Fab")
			(hide yes)
			(effects
				(font
					(size 1.27 1.27)
					(thickness 0.15)
				)
			)
		)
		(property "Author" "Antmicro"
			(at 92.107 338.615 0)
			(layer "B.Fab")
			(hide yes)
			(effects
				(font
					(size 1 1)
					(thickness 0.15)
				)
				(justify mirror)
			)
		)
		(property "Dielectric" "X5R"
			(at 92.107 338.615 0)
			(layer "B.Fab")
			(hide yes)
			(effects
				(font
					(size 1 1)
					(thickness 0.15)
				)
				(justify mirror)
			)
		)
		(property "License" "Apache-2.0"
			(at 92.107 338.615 0)
			(layer "B.Fab")
			(hide yes)
			(effects
				(font
					(size 1 1)
					(thickness 0.15)
				)
				(justify mirror)
			)
		)
		(property "MPN" "GRM155R61H104KE14D"
			(at 92.107 338.615 0)
			(layer "B.Fab")
			(hide yes)
			(effects
				(font
					(size 1 1)
					(thickness 0.15)
				)
				(justify mirror)
			)
		)
		(property "Manufacturer" "Murata"
			(at 92.107 338.615 0)
			(layer "B.Fab")
			(hide yes)
			(effects
				(font
					(size 1 1)
					(thickness 0.15)
				)
				(justify mirror)
			)
		)
		(property "Public" ""
			(at 92.107 338.615 0)
			(layer "B.Fab")
			(hide yes)
			(effects
				(font
					(size 1 1)
					(thickness 0.15)
				)
				(justify mirror)
			)
		)
		(property "Val" "100n"
			(at 92.107 338.615 0)
			(layer "B.Fab")
			(hide yes)
			(effects
				(font
					(size 1 1)
					(thickness 0.15)
				)
				(justify mirror)
			)
		)
		(property "Voltage" "50V"
			(at 92.107 338.615 0)
			(layer "B.Fab")
			(hide yes)
			(effects
				(font
					(size 1 1)
					(thickness 0.15)
				)
				(justify mirror)
			)
		)
		(sheetname "/Ethernet/")
		(sheetfile "ethernet.kicad_sch")
		(attr smd)
		(fp_rect
			(start -0.925 0.47)
			(end 0.925 -0.47)
			(stroke
				(width 0.05)
				(type default)
			)
			(fill no)
			(layer "B.CrtYd")
		)
		(fp_line
			(start -0.494 0.25)
			(end 0.504 0.25)
			(stroke
				(width 0.15)
				(type solid)
			)
			(layer "B.Fab")
		)
		(fp_line
			(start 0.504 0.25)
			(end 0.504 -0.248)
			(stroke
				(width 0.15)
				(type solid)
			)
			(layer "B.Fab")
		)
		(fp_line
			(start -0.494 -0.248)
			(end -0.494 0.25)
			(stroke
				(width 0.15)
				(type solid)
			)
			(layer "B.Fab")
		)
		(fp_line
			(start 0.504 -0.248)
			(end -0.494 -0.248)
			(stroke
				(width 0.15)
				(type solid)
			)
			(layer "B.Fab")
		)
		(fp_text user "${REFERENCE}"
			(at -0.939 -4.599 90)
			(layer "B.Fab")
			(effects
				(font
					(size 0.7 0.7)
					(thickness 0.15)
				)
				(justify left bottom mirror)
			)
		)
		(fp_text user "License: Apache-2.0"
			(at -0.939 -5.799 90)
			(layer "B.Fab")
			(effects
				(font
					(size 0.7 0.7)
					(thickness 0.15)
				)
				(justify left bottom mirror)
			)
		)
		(fp_text user "Author: Antmicro"
			(at -0.939 -3.399 90)
			(layer "B.Fab")
			(effects
				(font
					(size 0.7 0.7)
					(thickness 0.15)
				)
				(justify left bottom mirror)
			)
		)
		(pad "1" smd roundrect
			(at -0.48 0 270)
			(size 0.59 0.64)
			(layers "B.Cu" "B.Mask" "B.Paste")
			(roundrect_rratio 0.25)
			(net 417 "GND")
			(pintype "passive")
		)
		(pad "2" smd roundrect
			(at 0.48 0 270)
			(size 0.59 0.64)
			(layers "B.Cu" "B.Mask" "B.Paste")
			(roundrect_rratio 0.25)
			(net 50 "+3V3")
			(pintype "passive")
		)
	)
	(footprint "antmicro-footprints:SOT-583"
		(layer "B.Cu")
		(at 219.3505 132.989 -90)
		(property "Reference" "U4"
			(at -1.089 -1.9495 180)
			(layer "B.SilkS")
			(effects
				(font
					(size 0.7 0.7)
					(thickness 0.15)
				)
				(justify left bottom mirror)
			)
		)
		(property "Value" "TPS2117DRLR"
			(at 0 -2.3 90)
			(layer "B.Fab")
			(hide yes)
			(effects
				(font
					(size 0.7 0.7)
					(thickness 0.15)
				)
				(justify left bottom mirror)
			)
		)
		(property "Datasheet" "https://www.ti.com/lit/ds/symlink/tps2117.pdf"
			(at 0 0 270)
			(layer "F.Fab")
			(hide yes)
			(effects
				(font
					(size 1.27 1.27)
					(thickness 0.15)
				)
			)
		)
		(property "Description" "TPS2117 1.6-V to 5.5-V, 4-A Low IQ Power Mux With Manual and Priority Switchover"
			(at 0 0 270)
			(layer "F.Fab")
			(hide yes)
			(effects
				(font
					(size 1.27 1.27)
					(thickness 0.15)
				)
			)
		)
		(property "Author" "Antmicro"
			(at 86.3615 352.3395 0)
			(layer "B.Fab")
			(hide yes)
			(effects
				(font
					(size 1 1)
					(thickness 0.15)
				)
				(justify mirror)
			)
		)
		(property "License" "Apache-2.0"
			(at 86.3615 352.3395 0)
			(layer "B.Fab")
			(hide yes)
			(effects
				(font
					(size 1 1)
					(thickness 0.15)
				)
				(justify mirror)
			)
		)
		(property "MPN" "TPS2117DRLR"
			(at 86.3615 352.3395 0)
			(layer "B.Fab")
			(hide yes)
			(effects
				(font
					(size 1 1)
					(thickness 0.15)
				)
				(justify mirror)
			)
		)
		(property "Manufacturer" "Texas Instruments"
			(at 86.3615 352.3395 0)
			(layer "B.Fab")
			(hide yes)
			(effects
				(font
					(size 1 1)
					(thickness 0.15)
				)
				(justify mirror)
			)
		)
		(property ki_fp_filters "DRL0008A-MFG")
		(sheetname "/Supply/")
		(sheetfile "supply.kicad_sch")
		(attr smd)
		(fp_line
			(start -0.65 1.15)
			(end 0.65 1.15)
			(stroke
				(width 0.15)
				(type solid)
			)
			(layer "B.SilkS")
		)
		(fp_line
			(start -0.651 -1.15)
			(end 0.651 -1.15)
			(stroke
				(width 0.15)
				(type solid)
			)
			(layer "B.SilkS")
		)
		(fp_circle
			(center -0.9 1.1)
			(end -0.85 1.05)
			(stroke
				(width 0.15)
				(type solid)
			)
			(fill yes)
			(layer "B.SilkS")
		)
		(fp_rect
			(start -1.15 1.3)
			(end 1.15 -1.3)
			(stroke
				(width 0.05)
				(type solid)
			)
			(fill no)
			(layer "B.CrtYd")
		)
		(fp_line
			(start -0.651 1.1005)
			(end 0.651 1.1005)
			(stroke
				(width 0.15)
				(type solid)
			)
			(layer "B.Fab")
		)
		(fp_line
			(start -0.651 -1.1005)
			(end -0.651 1.1005)
			(stroke
				(width 0.15)
				(type solid)
			)
			(layer "B.Fab")
		)
		(fp_line
			(start -0.651 -1.1005)
			(end 0.651 -1.1005)
			(stroke
				(width 0.15)
				(type solid)
			)
			(layer "B.Fab")
		)
		(fp_line
			(start 0.651 -1.1005)
			(end 0.651 1.1005)
			(stroke
				(width 0.15)
				(type solid)
			)
			(layer "B.Fab")
		)
		(fp_text user "License: Apache-2.0"
			(at -0.06 -6.025 90)
			(layer "B.Fab")
			(effects
				(font
					(size 0.7 0.7)
					(thickness 0.15)
				)
				(justify left bottom mirror)
			)
		)
		(fp_text user "Author: Antmicro"
			(at -0.06 -5.025 90)
			(layer "B.Fab")
			(effects
				(font
					(size 0.7 0.7)
					(thickness 0.15)
				)
				(justify left bottom mirror)
			)
		)
		(fp_text user "${REFERENCE}"
			(at -0.06 -4.025 90)
			(layer "B.Fab")
			(effects
				(font
					(size 0.7 0.7)
					(thickness 0.15)
				)
				(justify left bottom mirror)
			)
		)
		(pad "1" smd roundrect
			(at -0.739 0.7495 270)
			(size 0.670001 0.299999)
			(layers "B.Cu" "B.Mask" "B.Paste")
			(roundrect_rratio 0.25)
			(net 417 "GND")
			(pinfunction "GND")
			(pintype "power_in")
		)
		(pad "2" smd roundrect
			(at -0.739 0.2505 270)
			(size 0.670001 0.299999)
			(layers "B.Cu" "B.Mask" "B.Paste")
			(roundrect_rratio 0.25)
			(net 296 "Net-(R10-Pad2)")
			(pinfunction "VOUT")
			(pintype "power_out")
		)
		(pad "3" smd roundrect
			(at -0.739 -0.2495 270)
			(size 0.670001 0.299999)
			(layers "B.Cu" "B.Mask" "B.Paste")
			(roundrect_rratio 0.25)
			(net 50 "+3V3")
			(pinfunction "VIN1")
			(pintype "power_in")
		)
		(pad "4" smd roundrect
			(at -0.739 -0.7495 270)
			(size 0.670001 0.299999)
			(layers "B.Cu" "B.Mask" "B.Paste")
			(roundrect_rratio 0.25)
			(net 186 "/Supply/PR")
			(pinfunction "PR1")
			(pintype "input")
		)
		(pad "5" smd roundrect
			(at 0.74 -0.7495 270)
			(size 0.670001 0.299999)
			(layers "B.Cu" "B.Mask" "B.Paste")
			(roundrect_rratio 0.25)
			(net 50 "+3V3")
			(pinfunction "MODE")
			(pintype "input")
		)
		(pad "6" smd roundrect
			(at 0.74 -0.2495 270)
			(size 0.670001 0.299999)
			(layers "B.Cu" "B.Mask" "B.Paste")
			(roundrect_rratio 0.25)
			(net 48 "+1V8")
			(pinfunction "VIN2")
			(pintype "power_in")
		)
		(pad "7" smd roundrect
			(at 0.74 0.2505 270)
			(size 0.670001 0.299999)
			(layers "B.Cu" "B.Mask" "B.Paste")
			(roundrect_rratio 0.25)
			(net 296 "Net-(R10-Pad2)")
			(pinfunction "VOUT")
			(pintype "passive")
		)
		(pad "8" smd roundrect
			(at 0.74 0.7495 270)
			(size 0.670001 0.299999)
			(layers "B.Cu" "B.Mask" "B.Paste")
			(roundrect_rratio 0.25)
			(net 334 "VREF_FLAG")
			(pinfunction "ST")
			(pintype "output")
		)
	)
	(footprint "antmicro-footprints:C_0402_1005Metric"
		(layer "B.Cu")
		(at 175.25 130.776 90)
		(descr "Capacitor SMD 0402")
		(tags "capacitor SMD 0402")
		(property "Reference" "C127"
			(at 2.246 1.38 90)
			(layer "B.SilkS")
			(effects
				(font
					(size 0.7 0.7)
					(thickness 0.15)
				)
				(justify left bottom mirror)
			)
		)
		(property "Value" "C_1u_0402"
			(at -1.022927 -2.155213 270)
			(layer "B.Fab")
			(hide yes)
			(effects
				(font
					(size 0.7 0.7)
					(thickness 0.15)
				)
				(justify left bottom mirror)
			)
		)
		(property "Datasheet" "https://product.tdk.com/en/search/capacitor/ceramic/mlcc/info?part_no=C1005X6S1A105K050BC"
			(at 0 0 90)
			(layer "F.Fab")
			(hide yes)
			(effects
				(font
					(size 1.27 1.27)
					(thickness 0.15)
				)
			)
		)
		(property "Description" "SMD Multilayer Ceramic Capacitor, 1 µF, 10 V, 0402 [1005 Metric], ± 10%, X6S, C"
			(at 0 0 90)
			(layer "F.Fab")
			(hide yes)
			(effects
				(font
					(size 1.27 1.27)
					(thickness 0.15)
				)
			)
		)
		(property "Author" "Antmicro"
			(at 306.026 -44.474 0)
			(layer "B.Fab")
			(hide yes)
			(effects
				(font
					(size 1 1)
					(thickness 0.15)
				)
				(justify mirror)
			)
		)
		(property "Dielectric" "X5R"
			(at 306.026 -44.474 0)
			(layer "B.Fab")
			(hide yes)
			(effects
				(font
					(size 1 1)
					(thickness 0.15)
				)
				(justify mirror)
			)
		)
		(property "License" "Apache-2.0"
			(at 306.026 -44.474 0)
			(layer "B.Fab")
			(hide yes)
			(effects
				(font
					(size 1 1)
					(thickness 0.15)
				)
				(justify mirror)
			)
		)
		(property "MPN" "C1005X6S1A105K050BC"
			(at 306.026 -44.474 0)
			(layer "B.Fab")
			(hide yes)
			(effects
				(font
					(size 1 1)
					(thickness 0.15)
				)
				(justify mirror)
			)
		)
		(property "Manufacturer" "TDK"
			(at 306.026 -44.474 0)
			(layer "B.Fab")
			(hide yes)
			(effects
				(font
					(size 1 1)
					(thickness 0.15)
				)
				(justify mirror)
			)
		)
		(property "Public" ""
			(at 306.026 -44.474 0)
			(layer "B.Fab")
			(hide yes)
			(effects
				(font
					(size 1 1)
					(thickness 0.15)
				)
				(justify mirror)
			)
		)
		(property "Val" "1u"
			(at 306.026 -44.474 0)
			(layer "B.Fab")
			(hide yes)
			(effects
				(font
					(size 1 1)
					(thickness 0.15)
				)
				(justify mirror)
			)
		)
		(property "Voltage" "16V"
			(at 306.026 -44.474 0)
			(layer "B.Fab")
			(hide yes)
			(effects
				(font
					(size 1 1)
					(thickness 0.15)
				)
				(justify mirror)
			)
		)
		(sheetname "/LPDDR4/")
		(sheetfile "lpddr.kicad_sch")
		(attr smd)
		(fp_rect
			(start -0.925 0.47)
			(end 0.925 -0.47)
			(stroke
				(width 0.05)
				(type default)
			)
			(fill no)
			(layer "B.CrtYd")
		)
		(fp_line
			(start 0.504 -0.248)
			(end -0.494 -0.248)
			(stroke
				(width 0.15)
				(type solid)
			)
			(layer "B.Fab")
		)
		(fp_line
			(start -0.494 -0.248)
			(end -0.494 0.25)
			(stroke
				(width 0.15)
				(type solid)
			)
			(layer "B.Fab")
		)
		(fp_line
			(start 0.504 0.25)
			(end 0.504 -0.248)
			(stroke
				(width 0.15)
				(type solid)
			)
			(layer "B.Fab")
		)
		(fp_line
			(start -0.494 0.25)
			(end 0.504 0.25)
			(stroke
				(width 0.15)
				(type solid)
			)
			(layer "B.Fab")
		)
		(fp_text user "${REFERENCE}"
			(at -0.939 -4.599 270)
			(layer "B.Fab")
			(effects
				(font
					(size 0.7 0.7)
					(thickness 0.15)
				)
				(justify left bottom mirror)
			)
		)
		(fp_text user "License: Apache-2.0"
			(at -0.939 -5.799 270)
			(layer "B.Fab")
			(effects
				(font
					(size 0.7 0.7)
					(thickness 0.15)
				)
				(justify left bottom mirror)
			)
		)
		(fp_text user "Author: Antmicro"
			(at -0.939 -3.399 270)
			(layer "B.Fab")
			(effects
				(font
					(size 0.7 0.7)
					(thickness 0.15)
				)
				(justify left bottom mirror)
			)
		)
		(pad "1" smd roundrect
			(at -0.48 0 90)
			(size 0.59 0.64)
			(layers "B.Cu" "B.Mask" "B.Paste")
			(roundrect_rratio 0.25)
			(net 417 "GND")
			(pintype "passive")
		)
		(pad "2" smd roundrect
			(at 0.48 0 90)
			(size 0.59 0.64)
			(layers "B.Cu" "B.Mask" "B.Paste")
			(roundrect_rratio 0.25)
			(net 2 "+1V1")
			(pintype "passive")
		)
	)
	(footprint "antmicro-footprints:C_0402_1005Metric"
		(layer "B.Cu")
		(at 210.9 144.65 90)
		(descr "Capacitor SMD 0402")
		(tags "capacitor SMD 0402")
		(property "Reference" "C177"
			(at 2.075 -0.325 90)
			(layer "B.SilkS")
			(effects
				(font
					(size 0.7 0.7)
					(thickness 0.15)
				)
				(justify right bottom mirror)
			)
		)
		(property "Value" "C_100n_0402"
			(at -1.022927 -2.155213 90)
			(layer "B.Fab")
			(hide yes)
			(effects
				(font
					(size 0.7 0.7)
					(thickness 0.15)
				)
				(justify right bottom mirror)
			)
		)
		(property "Datasheet" "https://www.murata.com/products/productdetail?partno=GRM155R61H104KE14%23"
			(at 0 0 90)
			(layer "F.Fab")
			(hide yes)
			(effects
				(font
					(size 1.27 1.27)
					(thickness 0.15)
				)
			)
		)
		(property "Description" "SMD Multilayer Ceramic Capacitor, 0.1 µF, 50 V, 0402 [1005 Metric], ± 10%, X5R, GRM Series"
			(at 0 0 90)
			(layer "F.Fab")
			(hide yes)
			(effects
				(font
					(size 1.27 1.27)
					(thickness 0.15)
				)
			)
		)
		(property "Author" "Antmicro"
			(at 355.55 -66.25 0)
			(layer "B.Fab")
			(hide yes)
			(effects
				(font
					(size 1 1)
					(thickness 0.15)
				)
				(justify mirror)
			)
		)
		(property "Dielectric" "X5R"
			(at 355.55 -66.25 0)
			(layer "B.Fab")
			(hide yes)
			(effects
				(font
					(size 1 1)
					(thickness 0.15)
				)
				(justify mirror)
			)
		)
		(property "License" "Apache-2.0"
			(at 355.55 -66.25 0)
			(layer "B.Fab")
			(hide yes)
			(effects
				(font
					(size 1 1)
					(thickness 0.15)
				)
				(justify mirror)
			)
		)
		(property "MPN" "GRM155R61H104KE14D"
			(at 355.55 -66.25 0)
			(layer "B.Fab")
			(hide yes)
			(effects
				(font
					(size 1 1)
					(thickness 0.15)
				)
				(justify mirror)
			)
		)
		(property "Manufacturer" "Murata"
			(at 355.55 -66.25 0)
			(layer "B.Fab")
			(hide yes)
			(effects
				(font
					(size 1 1)
					(thickness 0.15)
				)
				(justify mirror)
			)
		)
		(property "Public" ""
			(at 355.55 -66.25 0)
			(layer "B.Fab")
			(hide yes)
			(effects
				(font
					(size 1 1)
					(thickness 0.15)
				)
				(justify mirror)
			)
		)
		(property "Val" "100n"
			(at 355.55 -66.25 0)
			(layer "B.Fab")
			(hide yes)
			(effects
				(font
					(size 1 1)
					(thickness 0.15)
				)
				(justify mirror)
			)
		)
		(property "Voltage" "50V"
			(at 355.55 -66.25 0)
			(layer "B.Fab")
			(hide yes)
			(effects
				(font
					(size 1 1)
					(thickness 0.15)
				)
				(justify mirror)
			)
		)
		(sheetname "/USB/")
		(sheetfile "usb.kicad_sch")
		(attr smd)
		(fp_rect
			(start -0.925 0.47)
			(end 0.925 -0.47)
			(stroke
				(width 0.05)
				(type default)
			)
			(fill no)
			(layer "B.CrtYd")
		)
		(fp_line
			(start 0.504 -0.248)
			(end -0.494 -0.248)
			(stroke
				(width 0.15)
				(type solid)
			)
			(layer "B.Fab")
		)
		(fp_line
			(start -0.494 -0.248)
			(end -0.494 0.25)
			(stroke
				(width 0.15)
				(type solid)
			)
			(layer "B.Fab")
		)
		(fp_line
			(start 0.504 0.25)
			(end 0.504 -0.248)
			(stroke
				(width 0.15)
				(type solid)
			)
			(layer "B.Fab")
		)
		(fp_line
			(start -0.494 0.25)
			(end 0.504 0.25)
			(stroke
				(width 0.15)
				(type solid)
			)
			(layer "B.Fab")
		)
		(fp_text user "Author: Antmicro"
			(at -0.939 -3.399 270)
			(layer "B.Fab")
			(effects
				(font
					(size 0.7 0.7)
					(thickness 0.15)
				)
				(justify left bottom mirror)
			)
		)
		(fp_text user "${REFERENCE}"
			(at -0.939 -4.599 270)
			(layer "B.Fab")
			(effects
				(font
					(size 0.7 0.7)
					(thickness 0.15)
				)
				(justify left bottom mirror)
			)
		)
		(fp_text user "License: Apache-2.0"
			(at -0.939 -5.799 270)
			(layer "B.Fab")
			(effects
				(font
					(size 0.7 0.7)
					(thickness 0.15)
				)
				(justify left bottom mirror)
			)
		)
		(pad "1" smd roundrect
			(at -0.48 0 90)
			(size 0.59 0.64)
			(layers "B.Cu" "B.Mask" "B.Paste")
			(roundrect_rratio 0.25)
			(net 417 "GND")
			(pintype "passive")
		)
		(pad "2" smd roundrect
			(at 0.48 0 90)
			(size 0.59 0.64)
			(layers "B.Cu" "B.Mask" "B.Paste")
			(roundrect_rratio 0.25)
			(net 50 "+3V3")
			(pintype "passive")
		)
	)
	(footprint "antmicro-footprints:L_0603_1608Metric"
		(layer "B.Cu")
		(at 219.2 146.945)
		(property "Reference" "L6"
			(at 6.175 -8.33 0)
			(layer "B.SilkS")
			(effects
				(font
					(size 0.7 0.7)
					(thickness 0.15)
				)
				(justify right bottom mirror)
			)
		)
		(property "Value" "L_2u2_1.2A_0603"
			(at 0 -2 0)
			(layer "B.Fab")
			(hide yes)
			(effects
				(font
					(size 0.7 0.7)
					(thickness 0.15)
				)
				(justify right bottom mirror)
			)
		)
		(property "Datasheet" "https://www.mouser.com/datasheet/2/3/AOTA_B160808S-3224144.pdf"
			(at 0 0 0)
			(layer "F.Fab")
			(hide yes)
			(effects
				(font
					(size 1.27 1.27)
					(thickness 0.15)
				)
			)
		)
		(property "Description" "Wirewound Inductor, 2.2 µH, 240 mOhm, 40 MHz, 1.2 A, 0603 [1608 Metric]"
			(at 0 0 0)
			(layer "F.Fab")
			(hide yes)
			(effects
				(font
					(size 1.27 1.27)
					(thickness 0.15)
				)
			)
		)
		(property "Author" "Antmicro"
			(at 0 0 0)
			(layer "B.Fab")
			(hide yes)
			(effects
				(font
					(size 1 1)
					(thickness 0.15)
				)
				(justify mirror)
			)
		)
		(property "IMax" "1.2 A"
			(at 0 0 0)
			(layer "B.Fab")
			(hide yes)
			(effects
				(font
					(size 1 1)
					(thickness 0.15)
				)
				(justify mirror)
			)
		)
		(property "ISat" "1.3 A"
			(at 0 0 0)
			(layer "B.Fab")
			(hide yes)
			(effects
				(font
					(size 1 1)
					(thickness 0.15)
				)
				(justify mirror)
			)
		)
		(property "License" "Apache-2.0"
			(at 0 0 0)
			(layer "B.Fab")
			(hide yes)
			(effects
				(font
					(size 1 1)
					(thickness 0.15)
				)
				(justify mirror)
			)
		)
		(property "MPN" "AOTA-B160808S2R2MT "
			(at 0 0 0)
			(layer "B.Fab")
			(hide yes)
			(effects
				(font
					(size 1 1)
					(thickness 0.15)
				)
				(justify mirror)
			)
		)
		(property "Manufacturer" "Abracon"
			(at 0 0 0)
			(layer "B.Fab")
			(hide yes)
			(effects
				(font
					(size 1 1)
					(thickness 0.15)
				)
				(justify mirror)
			)
		)
		(property "Public" ""
			(at 0 0 0)
			(layer "B.Fab")
			(hide yes)
			(effects
				(font
					(size 1 1)
					(thickness 0.15)
				)
				(justify mirror)
			)
		)
		(property "Size" "1.6 x 0.8 x 0.8"
			(at 0 0 0)
			(layer "B.Fab")
			(hide yes)
			(effects
				(font
					(size 1 1)
					(thickness 0.15)
				)
				(justify mirror)
			)
		)
		(property "Val" "2u2/1.2A"
			(at 0 0 0)
			(layer "B.Fab")
			(hide yes)
			(effects
				(font
					(size 1 1)
					(thickness 0.15)
				)
				(justify mirror)
			)
		)
		(sheetname "/WiFi_Bluetooth/")
		(sheetfile "wifi_bt.kicad_sch")
		(attr smd)
		(fp_line
			(start -0.15 -0.4)
			(end 0.15 -0.4)
			(stroke
				(width 0.15)
				(type solid)
			)
			(layer "B.SilkS")
		)
		(fp_line
			(start -0.15 0.4)
			(end 0.15 0.4)
			(stroke
				(width 0.15)
				(type solid)
			)
			(layer "B.SilkS")
		)
		(fp_rect
			(start -1.25 0.65)
			(end 1.25 -0.65)
			(stroke
				(width 0.05)
				(type solid)
			)
			(fill no)
			(layer "B.CrtYd")
		)
		(fp_rect
			(start -0.8 0.4)
			(end 0.8 -0.4)
			(stroke
				(width 0.1)
				(type solid)
			)
			(fill no)
			(layer "B.Fab")
		)
		(fp_text user "License: Apache-2.0"
			(at -1.9 -5.75 180)
			(layer "B.Fab")
			(effects
				(font
					(size 0.7 0.7)
					(thickness 0.15)
				)
				(justify left bottom mirror)
			)
		)
		(fp_text user "${REFERENCE}"
			(at -1.9 -3.1 180)
			(layer "B.Fab")
			(effects
				(font
					(size 0.7 0.7)
					(thickness 0.15)
				)
				(justify left bottom mirror)
			)
		)
		(fp_text user "Author: Antmicro"
			(at -1.9 -4.4 180)
			(layer "B.Fab")
			(effects
				(font
					(size 0.7 0.7)
					(thickness 0.15)
				)
				(justify left bottom mirror)
			)
		)
		(pad "1" smd roundrect
			(at -0.7 0)
			(size 0.8 1)
			(layers "B.Cu" "B.Mask" "B.Paste")
			(roundrect_rratio 0.2)
			(net 151 "Net-(U26A-VIN_LDO)")
			(pintype "passive")
		)
		(pad "2" smd roundrect
			(at 0.7 0)
			(size 0.8 1)
			(layers "B.Cu" "B.Mask" "B.Paste")
			(roundrect_rratio 0.2)
			(net 220 "Net-(U26A-SR_VLX)")
			(pintype "passive")
		)
	)
	(footprint "antmicro-footprints:R_0402_1005Metric"
		(layer "B.Cu")
		(at 216.37 147.58 180)
		(descr "Resistor SMD 0402")
		(tags "resistor SMD 0402")
		(property "Reference" "R100"
			(at -2.9 -3.93 0)
			(layer "B.SilkS")
			(effects
				(font
					(size 0.7 0.7)
					(thickness 0.15)
				)
				(justify left bottom mirror)
			)
		)
		(property "Value" "R_100k_0402"
			(at -1.011843 -1.772047 0)
			(layer "B.Fab")
			(hide yes)
			(effects
				(font
					(size 0.7 0.7)
					(thickness 0.15)
				)
				(justify left bottom mirror)
			)
		)
		(property "Datasheet" "https://www.bourns.com/docs/product-datasheets/cr.pdf"
			(at 0 0 180)
			(layer "F.Fab")
			(hide yes)
			(effects
				(font
					(size 1.27 1.27)
					(thickness 0.15)
				)
			)
		)
		(property "Description" "SMD Chip Resistor, 100 kohm, ± 1%, 62.5 mW, 0402 [1005 Metric], Thick Film, General Purpose"
			(at 0 0 180)
			(layer "F.Fab")
			(hide yes)
			(effects
				(font
					(size 1.27 1.27)
					(thickness 0.15)
				)
			)
		)
		(property "Author" "Antmicro"
			(at 432.74 295.16 0)
			(layer "B.Fab")
			(hide yes)
			(effects
				(font
					(size 1 1)
					(thickness 0.15)
				)
				(justify mirror)
			)
		)
		(property "License" "Apache-2.0"
			(at 432.74 295.16 0)
			(layer "B.Fab")
			(hide yes)
			(effects
				(font
					(size 1 1)
					(thickness 0.15)
				)
				(justify mirror)
			)
		)
		(property "MPN" "CR0402-FX-1003GLF"
			(at 432.74 295.16 0)
			(layer "B.Fab")
			(hide yes)
			(effects
				(font
					(size 1 1)
					(thickness 0.15)
				)
				(justify mirror)
			)
		)
		(property "Manufacturer" "Bourns"
			(at 432.74 295.16 0)
			(layer "B.Fab")
			(hide yes)
			(effects
				(font
					(size 1 1)
					(thickness 0.15)
				)
				(justify mirror)
			)
		)
		(property "Public" ""
			(at 432.74 295.16 0)
			(layer "B.Fab")
			(hide yes)
			(effects
				(font
					(size 1 1)
					(thickness 0.15)
				)
				(justify mirror)
			)
		)
		(property "Tolerance" "1%"
			(at 432.74 295.16 0)
			(layer "B.Fab")
			(hide yes)
			(effects
				(font
					(size 1 1)
					(thickness 0.15)
				)
				(justify mirror)
			)
		)
		(property "Val" "100k"
			(at 432.74 295.16 0)
			(layer "B.Fab")
			(hide yes)
			(effects
				(font
					(size 1 1)
					(thickness 0.15)
				)
				(justify mirror)
			)
		)
		(sheetname "/USB/")
		(sheetfile "usb.kicad_sch")
		(attr smd)
		(fp_rect
			(start -0.925 0.47)
			(end 0.925 -0.47)
			(stroke
				(width 0.05)
				(type default)
			)
			(fill no)
			(layer "B.CrtYd")
		)
		(fp_rect
			(start -0.5 0.25)
			(end 0.5 -0.25)
			(stroke
				(width 0.15)
				(type solid)
			)
			(fill no)
			(layer "B.Fab")
		)
		(fp_text user "Author: Antmicro"
			(at -0.95 -4.169 0)
			(layer "B.Fab")
			(effects
				(font
					(size 0.7 0.7)
					(thickness 0.15)
				)
				(justify left bottom mirror)
			)
		)
		(fp_text user "${REFERENCE}"
			(at -0.95 -3.168 0)
			(layer "B.Fab")
			(effects
				(font
					(size 0.7 0.7)
					(thickness 0.15)
				)
				(justify left bottom mirror)
			)
		)
		(fp_text user "License: Apache-2.0"
			(at -0.95 -5.169 0)
			(layer "B.Fab")
			(effects
				(font
					(size 0.7 0.7)
					(thickness 0.15)
				)
				(justify left bottom mirror)
			)
		)
		(pad "1" smd roundrect
			(at -0.48 0 180)
			(size 0.59 0.64)
			(layers "B.Cu" "B.Mask" "B.Paste")
			(roundrect_rratio 0.25)
			(net 318 "Net-(U28-SUSP_IND)")
			(pintype "passive")
		)
		(pad "2" smd roundrect
			(at 0.48 0 180)
			(size 0.59 0.64)
			(layers "B.Cu" "B.Mask" "B.Paste")
			(roundrect_rratio 0.25)
			(net 50 "+3V3")
			(pintype "passive")
		)
	)
	(footprint "antmicro-footprints:R_0402_1005Metric"
		(layer "B.Cu")
		(at 181.9 154.25 90)
		(descr "Resistor SMD 0402")
		(tags "resistor SMD 0402")
		(property "Reference" "R68"
			(at -0.95 -4.75 315)
			(layer "B.SilkS")
			(effects
				(font
					(size 0.7 0.7)
					(thickness 0.15)
				)
				(justify left bottom mirror)
			)
		)
		(property "Value" "R_590R_0402"
			(at -1.011843 -1.772047 270)
			(layer "B.Fab")
			(hide yes)
			(effects
				(font
					(size 0.7 0.7)
					(thickness 0.15)
				)
				(justify left bottom mirror)
			)
		)
		(property "Datasheet" "https://www.bourns.com/docs/product-datasheets/cr.pdf"
			(at 0 0 90)
			(layer "F.Fab")
			(hide yes)
			(effects
				(font
					(size 1.27 1.27)
					(thickness 0.15)
				)
			)
		)
		(property "Description" "SMD Chip Resistor, 590 ohm, ± 1%, 100 mW, 0402 [1005 Metric], Thick Film, Precision"
			(at 0 0 90)
			(layer "F.Fab")
			(hide yes)
			(effects
				(font
					(size 1.27 1.27)
					(thickness 0.15)
				)
			)
		)
		(property "Author" "Antmicro"
			(at 336.15 -27.65 0)
			(layer "B.Fab")
			(hide yes)
			(effects
				(font
					(size 1 1)
					(thickness 0.15)
				)
				(justify mirror)
			)
		)
		(property "License" "Apache-2.0"
			(at 336.15 -27.65 0)
			(layer "B.Fab")
			(hide yes)
			(effects
				(font
					(size 1 1)
					(thickness 0.15)
				)
				(justify mirror)
			)
		)
		(property "MPN" "CR0402-FX-5900GLF"
			(at 336.15 -27.65 0)
			(layer "B.Fab")
			(hide yes)
			(effects
				(font
					(size 1 1)
					(thickness 0.15)
				)
				(justify mirror)
			)
		)
		(property "Manufacturer" "Bourns"
			(at 336.15 -27.65 0)
			(layer "B.Fab")
			(hide yes)
			(effects
				(font
					(size 1 1)
					(thickness 0.15)
				)
				(justify mirror)
			)
		)
		(property "Public" ""
			(at 336.15 -27.65 0)
			(layer "B.Fab")
			(hide yes)
			(effects
				(font
					(size 1 1)
					(thickness 0.15)
				)
				(justify mirror)
			)
		)
		(property "Tolerance" "1%"
			(at 336.15 -27.65 0)
			(layer "B.Fab")
			(hide yes)
			(effects
				(font
					(size 1 1)
					(thickness 0.15)
				)
				(justify mirror)
			)
		)
		(property "Val" "590R"
			(at 336.15 -27.65 0)
			(layer "B.Fab")
			(hide yes)
			(effects
				(font
					(size 1 1)
					(thickness 0.15)
				)
				(justify mirror)
			)
		)
		(sheetname "/Supply/")
		(sheetfile "supply.kicad_sch")
		(attr smd)
		(fp_rect
			(start -0.925 0.47)
			(end 0.925 -0.47)
			(stroke
				(width 0.05)
				(type default)
			)
			(fill no)
			(layer "B.CrtYd")
		)
		(fp_rect
			(start -0.5 0.25)
			(end 0.5 -0.25)
			(stroke
				(width 0.15)
				(type solid)
			)
			(fill no)
			(layer "B.Fab")
		)
		(fp_text user "License: Apache-2.0"
			(at -0.95 -5.169 270)
			(layer "B.Fab")
			(effects
				(font
					(size 0.7 0.7)
					(thickness 0.15)
				)
				(justify left bottom mirror)
			)
		)
		(fp_text user "${REFERENCE}"
			(at -0.95 -3.168 270)
			(layer "B.Fab")
			(effects
				(font
					(size 0.7 0.7)
					(thickness 0.15)
				)
				(justify left bottom mirror)
			)
		)
		(fp_text user "Author: Antmicro"
			(at -0.95 -4.169 270)
			(layer "B.Fab")
			(effects
				(font
					(size 0.7 0.7)
					(thickness 0.15)
				)
				(justify left bottom mirror)
			)
		)
		(pad "1" smd roundrect
			(at -0.48 0 90)
			(size 0.59 0.64)
			(layers "B.Cu" "B.Mask" "B.Paste")
			(roundrect_rratio 0.25)
			(net 650 "Net-(D5-A)")
			(pintype "passive")
		)
		(pad "2" smd roundrect
			(at 0.48 0 90)
			(size 0.59 0.64)
			(layers "B.Cu" "B.Mask" "B.Paste")
			(roundrect_rratio 0.25)
			(net 90 "+5V")
			(pintype "passive")
		)
	)
	(footprint "antmicro-footprints:R_0402_1005Metric"
		(layer "B.Cu")
		(at 211.6425 126.812 -90)
		(descr "Resistor SMD 0402")
		(tags "resistor SMD 0402")
		(property "Reference" "R38"
			(at 0.688 -0.3825 90)
			(layer "B.SilkS")
			(effects
				(font
					(size 0.7 0.7)
					(thickness 0.15)
				)
				(justify left bottom mirror)
			)
		)
		(property "Value" "R_49k9_0402"
			(at -1.011843 -1.772047 90)
			(layer "B.Fab")
			(hide yes)
			(effects
				(font
					(size 0.7 0.7)
					(thickness 0.15)
				)
				(justify left bottom mirror)
			)
		)
		(property "Datasheet" "https://www.bourns.com/docs/product-datasheets/cr.pdf"
			(at 0 0 270)
			(layer "F.Fab")
			(hide yes)
			(effects
				(font
					(size 1.27 1.27)
					(thickness 0.15)
				)
			)
		)
		(property "Description" "SMD Chip Resistor, 49.9 kohm, ± 1%, 63 mW, 0402 [1005 Metric], Thick Film, General Purpose"
			(at 0 0 270)
			(layer "F.Fab")
			(hide yes)
			(effects
				(font
					(size 1.27 1.27)
					(thickness 0.15)
				)
			)
		)
		(property "Author" "Antmicro"
			(at 84.8305 338.4545 0)
			(layer "B.Fab")
			(hide yes)
			(effects
				(font
					(size 1 1)
					(thickness 0.15)
				)
				(justify mirror)
			)
		)
		(property "License" "Apache-2.0"
			(at 84.8305 338.4545 0)
			(layer "B.Fab")
			(hide yes)
			(effects
				(font
					(size 1 1)
					(thickness 0.15)
				)
				(justify mirror)
			)
		)
		(property "MPN" "CR0402-FX-4992GLF"
			(at 84.8305 338.4545 0)
			(layer "B.Fab")
			(hide yes)
			(effects
				(font
					(size 1 1)
					(thickness 0.15)
				)
				(justify mirror)
			)
		)
		(property "Manufacturer" "Bourns"
			(at 84.8305 338.4545 0)
			(layer "B.Fab")
			(hide yes)
			(effects
				(font
					(size 1 1)
					(thickness 0.15)
				)
				(justify mirror)
			)
		)
		(property "Public" ""
			(at 84.8305 338.4545 0)
			(layer "B.Fab")
			(hide yes)
			(effects
				(font
					(size 1 1)
					(thickness 0.15)
				)
				(justify mirror)
			)
		)
		(property "Tolerance" "1%"
			(at 84.8305 338.4545 0)
			(layer "B.Fab")
			(hide yes)
			(effects
				(font
					(size 1 1)
					(thickness 0.15)
				)
				(justify mirror)
			)
		)
		(property "Val" "49k9"
			(at 84.8305 338.4545 0)
			(layer "B.Fab")
			(hide yes)
			(effects
				(font
					(size 1 1)
					(thickness 0.15)
				)
				(justify mirror)
			)
		)
		(sheetname "/Memory/")
		(sheetfile "memory.kicad_sch")
		(attr smd)
		(fp_rect
			(start -0.925 0.47)
			(end 0.925 -0.47)
			(stroke
				(width 0.05)
				(type default)
			)
			(fill no)
			(layer "B.CrtYd")
		)
		(fp_rect
			(start -0.5 0.25)
			(end 0.5 -0.25)
			(stroke
				(width 0.15)
				(type solid)
			)
			(fill no)
			(layer "B.Fab")
		)
		(fp_text user "Author: Antmicro"
			(at -0.95 -4.169 90)
			(layer "B.Fab")
			(effects
				(font
					(size 0.7 0.7)
					(thickness 0.15)
				)
				(justify left bottom mirror)
			)
		)
		(fp_text user "License: Apache-2.0"
			(at -0.95 -5.169 90)
			(layer "B.Fab")
			(effects
				(font
					(size 0.7 0.7)
					(thickness 0.15)
				)
				(justify left bottom mirror)
			)
		)
		(fp_text user "${REFERENCE}"
			(at -0.95 -3.168 90)
			(layer "B.Fab")
			(effects
				(font
					(size 0.7 0.7)
					(thickness 0.15)
				)
				(justify left bottom mirror)
			)
		)
		(pad "1" smd roundrect
			(at -0.48 0 270)
			(size 0.59 0.64)
			(layers "B.Cu" "B.Mask" "B.Paste")
			(roundrect_rratio 0.25)
			(net 208 "/FPGA MSSIO/EMMC.DAT0")
			(pintype "passive")
		)
		(pad "2" smd roundrect
			(at 0.48 0 270)
			(size 0.59 0.64)
			(layers "B.Cu" "B.Mask" "B.Paste")
			(roundrect_rratio 0.25)
			(net 137 "SD_VDD")
			(pintype "passive")
		)
	)
	(footprint "antmicro-footprints:R_0402_1005Metric"
		(layer "B.Cu")
		(at 218.975 137.775 180)
		(descr "Resistor SMD 0402")
		(tags "resistor SMD 0402")
		(property "Reference" "R50"
			(at 0.75 -0.475 0)
			(layer "B.SilkS")
			(effects
				(font
					(size 0.7 0.7)
					(thickness 0.15)
				)
				(justify left bottom mirror)
			)
		)
		(property "Value" "R_0R_0402"
			(at -1.011843 -1.772047 0)
			(layer "B.Fab")
			(hide yes)
			(effects
				(font
					(size 0.7 0.7)
					(thickness 0.15)
				)
				(justify left bottom mirror)
			)
		)
		(property "Datasheet" "https://industrial.panasonic.com/cdbs/www-data/pdf/RDA0000/AOA0000C301.pdf"
			(at 0 0 180)
			(layer "F.Fab")
			(hide yes)
			(effects
				(font
					(size 1.27 1.27)
					(thickness 0.15)
				)
			)
		)
		(property "Description" "SMD Chip Resistor, Jumper, 0 ohm, 100 mW, 0402 [1005 Metric], Thick Film, General Purpose"
			(at 0 0 180)
			(layer "F.Fab")
			(hide yes)
			(effects
				(font
					(size 1.27 1.27)
					(thickness 0.15)
				)
			)
		)
		(property "Author" "Antmicro"
			(at 437.95 275.55 0)
			(layer "B.Fab")
			(hide yes)
			(effects
				(font
					(size 1 1)
					(thickness 0.15)
				)
				(justify mirror)
			)
		)
		(property "Current" "1A"
			(at 437.95 275.55 0)
			(layer "B.Fab")
			(hide yes)
			(effects
				(font
					(size 1 1)
					(thickness 0.15)
				)
				(justify mirror)
			)
		)
		(property "License" "Apache-2.0"
			(at 437.95 275.55 0)
			(layer "B.Fab")
			(hide yes)
			(effects
				(font
					(size 1 1)
					(thickness 0.15)
				)
				(justify mirror)
			)
		)
		(property "MPN" "ERJ2GE0R00X"
			(at 437.95 275.55 0)
			(layer "B.Fab")
			(hide yes)
			(effects
				(font
					(size 1 1)
					(thickness 0.15)
				)
				(justify mirror)
			)
		)
		(property "Manufacturer" "Panasonic"
			(at 437.95 275.55 0)
			(layer "B.Fab")
			(hide yes)
			(effects
				(font
					(size 1 1)
					(thickness 0.15)
				)
				(justify mirror)
			)
		)
		(property "Public" ""
			(at 437.95 275.55 0)
			(layer "B.Fab")
			(hide yes)
			(effects
				(font
					(size 1 1)
					(thickness 0.15)
				)
				(justify mirror)
			)
		)
		(property "Tolerance" "~"
			(at 437.95 275.55 0)
			(layer "B.Fab")
			(hide yes)
			(effects
				(font
					(size 1 1)
					(thickness 0.15)
				)
				(justify mirror)
			)
		)
		(property "Val" "0R"
			(at 437.95 275.55 0)
			(layer "B.Fab")
			(hide yes)
			(effects
				(font
					(size 1 1)
					(thickness 0.15)
				)
				(justify mirror)
			)
		)
		(sheetname "/Memory/")
		(sheetfile "memory.kicad_sch")
		(attr smd)
		(fp_rect
			(start -0.925 0.47)
			(end 0.925 -0.47)
			(stroke
				(width 0.05)
				(type default)
			)
			(fill no)
			(layer "B.CrtYd")
		)
		(fp_rect
			(start -0.5 0.25)
			(end 0.5 -0.25)
			(stroke
				(width 0.15)
				(type solid)
			)
			(fill no)
			(layer "B.Fab")
		)
		(fp_text user "License: Apache-2.0"
			(at -0.95 -5.169 0)
			(layer "B.Fab")
			(effects
				(font
					(size 0.7 0.7)
					(thickness 0.15)
				)
				(justify left bottom mirror)
			)
		)
		(fp_text user "Author: Antmicro"
			(at -0.95 -4.169 0)
			(layer "B.Fab")
			(effects
				(font
					(size 0.7 0.7)
					(thickness 0.15)
				)
				(justify left bottom mirror)
			)
		)
		(fp_text user "${REFERENCE}"
			(at -0.95 -3.168 0)
			(layer "B.Fab")
			(effects
				(font
					(size 0.7 0.7)
					(thickness 0.15)
				)
				(justify left bottom mirror)
			)
		)
		(pad "1" smd roundrect
			(at -0.48 0 180)
			(size 0.59 0.64)
			(layers "B.Cu" "B.Mask" "B.Paste")
			(roundrect_rratio 0.25)
			(net 516 "Net-(R50-Pad1)")
			(pintype "passive")
		)
		(pad "2" smd roundrect
			(at 0.48 0 180)
			(size 0.59 0.64)
			(layers "B.Cu" "B.Mask" "B.Paste")
			(roundrect_rratio 0.25)
			(net 137 "SD_VDD")
			(pintype "passive")
		)
	)
	(footprint "antmicro-footprints:R_0402_1005Metric"
		(layer "B.Cu")
		(at 210.2 128.35)
		(descr "Resistor SMD 0402")
		(tags "resistor SMD 0402")
		(property "Reference" "R31"
			(at -0.8425 0.628 180)
			(layer "B.SilkS")
			(effects
				(font
					(size 0.7 0.7)
					(thickness 0.15)
				)
				(justify left bottom mirror)
			)
		)
		(property "Value" "R_49k9_0402"
			(at -1.011843 -1.772047 180)
			(layer "B.Fab")
			(hide yes)
			(effects
				(font
					(size 0.7 0.7)
					(thickness 0.15)
				)
				(justify left bottom mirror)
			)
		)
		(property "Datasheet" "https://www.bourns.com/docs/product-datasheets/cr.pdf"
			(at 0 0 0)
			(layer "F.Fab")
			(hide yes)
			(effects
				(font
					(size 1.27 1.27)
					(thickness 0.15)
				)
			)
		)
		(property "Description" "SMD Chip Resistor, 49.9 kohm, ± 1%, 63 mW, 0402 [1005 Metric], Thick Film, General Purpose"
			(at 0 0 0)
			(layer "F.Fab")
			(hide yes)
			(effects
				(font
					(size 1.27 1.27)
					(thickness 0.15)
				)
			)
		)
		(property "Author" "Antmicro"
			(at 0 0 0)
			(layer "B.Fab")
			(hide yes)
			(effects
				(font
					(size 1 1)
					(thickness 0.15)
				)
				(justify mirror)
			)
		)
		(property "License" "Apache-2.0"
			(at 0 0 0)
			(layer "B.Fab")
			(hide yes)
			(effects
				(font
					(size 1 1)
					(thickness 0.15)
				)
				(justify mirror)
			)
		)
		(property "MPN" "CR0402-FX-4992GLF"
			(at 0 0 0)
			(layer "B.Fab")
			(hide yes)
			(effects
				(font
					(size 1 1)
					(thickness 0.15)
				)
				(justify mirror)
			)
		)
		(property "Manufacturer" "Bourns"
			(at 0 0 0)
			(layer "B.Fab")
			(hide yes)
			(effects
				(font
					(size 1 1)
					(thickness 0.15)
				)
				(justify mirror)
			)
		)
		(property "Public" ""
			(at 0 0 0)
			(layer "B.Fab")
			(hide yes)
			(effects
				(font
					(size 1 1)
					(thickness 0.15)
				)
				(justify mirror)
			)
		)
		(property "Tolerance" "1%"
			(at 0 0 0)
			(layer "B.Fab")
			(hide yes)
			(effects
				(font
					(size 1 1)
					(thickness 0.15)
				)
				(justify mirror)
			)
		)
		(property "Val" "49k9"
			(at 0 0 0)
			(layer "B.Fab")
			(hide yes)
			(effects
				(font
					(size 1 1)
					(thickness 0.15)
				)
				(justify mirror)
			)
		)
		(sheetname "/Memory/")
		(sheetfile "memory.kicad_sch")
		(attr smd)
		(fp_rect
			(start -0.925 0.47)
			(end 0.925 -0.47)
			(stroke
				(width 0.05)
				(type default)
			)
			(fill no)
			(layer "B.CrtYd")
		)
		(fp_rect
			(start -0.5 0.25)
			(end 0.5 -0.25)
			(stroke
				(width 0.15)
				(type solid)
			)
			(fill no)
			(layer "B.Fab")
		)
		(fp_text user "Author: Antmicro"
			(at -0.95 -4.169 180)
			(layer "B.Fab")
			(effects
				(font
					(size 0.7 0.7)
					(thickness 0.15)
				)
				(justify left bottom mirror)
			)
		)
		(fp_text user "License: Apache-2.0"
			(at -0.95 -5.169 180)
			(layer "B.Fab")
			(effects
				(font
					(size 0.7 0.7)
					(thickness 0.15)
				)
				(justify left bottom mirror)
			)
		)
		(fp_text user "${REFERENCE}"
			(at -0.95 -3.168 180)
			(layer "B.Fab")
			(effects
				(font
					(size 0.7 0.7)
					(thickness 0.15)
				)
				(justify left bottom mirror)
			)
		)
		(pad "1" smd roundrect
			(at -0.48 0)
			(size 0.59 0.64)
			(layers "B.Cu" "B.Mask" "B.Paste")
			(roundrect_rratio 0.25)
			(net 214 "/FPGA MSSIO/EMMC.DAT7")
			(pintype "passive")
		)
		(pad "2" smd roundrect
			(at 0.48 0)
			(size 0.59 0.64)
			(layers "B.Cu" "B.Mask" "B.Paste")
			(roundrect_rratio 0.25)
			(net 137 "SD_VDD")
			(pintype "passive")
		)
	)
	(footprint "antmicro-footprints:C_0402_1005Metric"
		(layer "B.Cu")
		(at 203.375 146.95 -135)
		(descr "Capacitor SMD 0402")
		(tags "capacitor SMD 0402")
		(property "Reference" "C215"
			(at -8.085766 5.617963 225)
			(layer "B.SilkS")
			(effects
				(font
					(size 0.7 0.7)
					(thickness 0.15)
				)
				(justify left bottom mirror)
			)
		)
		(property "Value" "C_100n_0402"
			(at -1.022927 -2.155213 45)
			(layer "B.Fab")
			(hide yes)
			(effects
				(font
					(size 0.7 0.7)
					(thickness 0.15)
				)
				(justify left bottom mirror)
			)
		)
		(property "Datasheet" "https://www.murata.com/products/productdetail?partno=GRM155R61H104KE14%23"
			(at 0 0 225)
			(layer "F.Fab")
			(hide yes)
			(effects
				(font
					(size 1.27 1.27)
					(thickness 0.15)
				)
			)
		)
		(property "Description" "SMD Multilayer Ceramic Capacitor, 0.1 µF, 50 V, 0402 [1005 Metric], ± 10%, X5R, GRM Series"
			(at 0 0 225)
			(layer "F.Fab")
			(hide yes)
			(effects
				(font
					(size 1.27 1.27)
					(thickness 0.15)
				)
			)
		)
		(property "Author" "Antmicro"
			(at 243.2735 394.667183 0)
			(layer "B.Fab")
			(hide yes)
			(effects
				(font
					(size 1 1)
					(thickness 0.15)
				)
				(justify mirror)
			)
		)
		(property "Dielectric" "X5R"
			(at 243.2735 394.667183 0)
			(layer "B.Fab")
			(hide yes)
			(effects
				(font
					(size 1 1)
					(thickness 0.15)
				)
				(justify mirror)
			)
		)
		(property "License" "Apache-2.0"
			(at 243.2735 394.667183 0)
			(layer "B.Fab")
			(hide yes)
			(effects
				(font
					(size 1 1)
					(thickness 0.15)
				)
				(justify mirror)
			)
		)
		(property "MPN" "GRM155R61H104KE14D"
			(at 243.2735 394.667183 0)
			(layer "B.Fab")
			(hide yes)
			(effects
				(font
					(size 1 1)
					(thickness 0.15)
				)
				(justify mirror)
			)
		)
		(property "Manufacturer" "Murata"
			(at 243.2735 394.667183 0)
			(layer "B.Fab")
			(hide yes)
			(effects
				(font
					(size 1 1)
					(thickness 0.15)
				)
				(justify mirror)
			)
		)
		(property "Public" ""
			(at 243.2735 394.667183 0)
			(layer "B.Fab")
			(hide yes)
			(effects
				(font
					(size 1 1)
					(thickness 0.15)
				)
				(justify mirror)
			)
		)
		(property "Val" "100n"
			(at 243.2735 394.667183 0)
			(layer "B.Fab")
			(hide yes)
			(effects
				(font
					(size 1 1)
					(thickness 0.15)
				)
				(justify mirror)
			)
		)
		(property "Voltage" "50V"
			(at 243.2735 394.667183 0)
			(layer "B.Fab")
			(hide yes)
			(effects
				(font
					(size 1 1)
					(thickness 0.15)
				)
				(justify mirror)
			)
		)
		(sheetname "/MIPI CrossLink/")
		(sheetfile "crosslink.kicad_sch")
		(attr smd)
		(fp_poly
			(pts
				(xy -0.925 0.47) (xy 0.925 0.47) (xy 0.925 -0.47) (xy -0.925 -0.47)
			)
			(stroke
				(width 0.05)
				(type default)
			)
			(fill no)
			(layer "B.CrtYd")
		)
		(fp_line
			(start 0.504 0.25)
			(end 0.504 -0.248)
			(stroke
				(width 0.15)
				(type solid)
			)
			(layer "B.Fab")
		)
		(fp_line
			(start 0.504 -0.248)
			(end -0.494 -0.248)
			(stroke
				(width 0.15)
				(type solid)
			)
			(layer "B.Fab")
		)
		(fp_line
			(start -0.494 0.25)
			(end 0.504 0.25)
			(stroke
				(width 0.15)
				(type solid)
			)
			(layer "B.Fab")
		)
		(fp_line
			(start -0.494 -0.248)
			(end -0.494 0.25)
			(stroke
				(width 0.15)
				(type solid)
			)
			(layer "B.Fab")
		)
		(fp_text user "${REFERENCE}"
			(at -0.939 -4.599 45)
			(layer "B.Fab")
			(effects
				(font
					(size 0.7 0.7)
					(thickness 0.15)
				)
				(justify left bottom mirror)
			)
		)
		(fp_text user "License: Apache-2.0"
			(at -0.939 -5.799 45)
			(layer "B.Fab")
			(effects
				(font
					(size 0.7 0.7)
					(thickness 0.15)
				)
				(justify left bottom mirror)
			)
		)
		(fp_text user "Author: Antmicro"
			(at -0.939 -3.399 45)
			(layer "B.Fab")
			(effects
				(font
					(size 0.7 0.7)
					(thickness 0.15)
				)
				(justify left bottom mirror)
			)
		)
		(pad "1" smd roundrect
			(at -0.48 0 225)
			(size 0.59 0.64)
			(layers "B.Cu" "B.Mask" "B.Paste")
			(roundrect_rratio 0.25)
			(net 417 "GND")
			(pintype "passive")
		)
		(pad "2" smd roundrect
			(at 0.48 0 225)
			(size 0.59 0.64)
			(layers "B.Cu" "B.Mask" "B.Paste")
			(roundrect_rratio 0.25)
			(net 176 "/MIPI CrossLink/CL_VCC")
			(pintype "passive")
		)
	)
	(footprint "antmicro-footprints:C_0402_1005Metric"
		(layer "B.Cu")
		(at 208.1 147.44 180)
		(descr "Capacitor SMD 0402")
		(tags "capacitor SMD 0402")
		(property "Reference" "C207"
			(at 4.9 18.375 0)
			(layer "B.SilkS")
			(effects
				(font
					(size 0.7 0.7)
					(thickness 0.15)
				)
				(justify left bottom mirror)
			)
		)
		(property "Value" "C_10u_0402"
			(at -1.022927 -2.155213 0)
			(layer "B.Fab")
			(hide yes)
			(effects
				(font
					(size 0.7 0.7)
					(thickness 0.15)
				)
				(justify left bottom mirror)
			)
		)
		(property "Datasheet" "https://www.yageo.com/en/Chart/Download/pdf/CC0402MRX5R5BB106"
			(at 0 0 180)
			(layer "F.Fab")
			(hide yes)
			(effects
				(font
					(size 1.27 1.27)
					(thickness 0.15)
				)
			)
		)
		(property "Description" "SMD Multilayer Ceramic Capacitor, 10 µF, 6.3 V, 0402 [1005 Metric], ± 20%, X5R, CC Series"
			(at 0 0 180)
			(layer "F.Fab")
			(hide yes)
			(effects
				(font
					(size 1.27 1.27)
					(thickness 0.15)
				)
			)
		)
		(property "Author" "Antmicro"
			(at 416.2 294.88 0)
			(layer "B.Fab")
			(hide yes)
			(effects
				(font
					(size 1 1)
					(thickness 0.15)
				)
				(justify mirror)
			)
		)
		(property "Dielectric" ""
			(at 416.2 294.88 0)
			(layer "B.Fab")
			(hide yes)
			(effects
				(font
					(size 1 1)
					(thickness 0.15)
				)
				(justify mirror)
			)
		)
		(property "License" "Apache-2.0"
			(at 416.2 294.88 0)
			(layer "B.Fab")
			(hide yes)
			(effects
				(font
					(size 1 1)
					(thickness 0.15)
				)
				(justify mirror)
			)
		)
		(property "MPN" "CC0402MRX5R5BB106"
			(at 416.2 294.88 0)
			(layer "B.Fab")
			(hide yes)
			(effects
				(font
					(size 1 1)
					(thickness 0.15)
				)
				(justify mirror)
			)
		)
		(property "Manufacturer" "YAGEO"
			(at 416.2 294.88 0)
			(layer "B.Fab")
			(hide yes)
			(effects
				(font
					(size 1 1)
					(thickness 0.15)
				)
				(justify mirror)
			)
		)
		(property "Public" ""
			(at 416.2 294.88 0)
			(layer "B.Fab")
			(hide yes)
			(effects
				(font
					(size 1 1)
					(thickness 0.15)
				)
				(justify mirror)
			)
		)
		(property "Val" "10u"
			(at 416.2 294.88 0)
			(layer "B.Fab")
			(hide yes)
			(effects
				(font
					(size 1 1)
					(thickness 0.15)
				)
				(justify mirror)
			)
		)
		(property "Voltage" ""
			(at 416.2 294.88 0)
			(layer "B.Fab")
			(hide yes)
			(effects
				(font
					(size 1 1)
					(thickness 0.15)
				)
				(justify mirror)
			)
		)
		(sheetname "/MIPI CrossLink/")
		(sheetfile "crosslink.kicad_sch")
		(attr smd)
		(fp_rect
			(start -0.925 0.47)
			(end 0.925 -0.47)
			(stroke
				(width 0.05)
				(type default)
			)
			(fill no)
			(layer "B.CrtYd")
		)
		(fp_line
			(start 0.504 0.25)
			(end 0.504 -0.248)
			(stroke
				(width 0.15)
				(type solid)
			)
			(layer "B.Fab")
		)
		(fp_line
			(start 0.504 -0.248)
			(end -0.494 -0.248)
			(stroke
				(width 0.15)
				(type solid)
			)
			(layer "B.Fab")
		)
		(fp_line
			(start -0.494 0.25)
			(end 0.504 0.25)
			(stroke
				(width 0.15)
				(type solid)
			)
			(layer "B.Fab")
		)
		(fp_line
			(start -0.494 -0.248)
			(end -0.494 0.25)
			(stroke
				(width 0.15)
				(type solid)
			)
			(layer "B.Fab")
		)
		(fp_text user "${REFERENCE}"
			(at -0.939 -4.599 0)
			(layer "B.Fab")
			(effects
				(font
					(size 0.7 0.7)
					(thickness 0.15)
				)
				(justify left bottom mirror)
			)
		)
		(fp_text user "License: Apache-2.0"
			(at -0.939 -5.799 0)
			(layer "B.Fab")
			(effects
				(font
					(size 0.7 0.7)
					(thickness 0.15)
				)
				(justify left bottom mirror)
			)
		)
		(fp_text user "Author: Antmicro"
			(at -0.939 -3.399 0)
			(layer "B.Fab")
			(effects
				(font
					(size 0.7 0.7)
					(thickness 0.15)
				)
				(justify left bottom mirror)
			)
		)
		(pad "1" smd roundrect
			(at -0.48 0 180)
			(size 0.59 0.64)
			(layers "B.Cu" "B.Mask" "B.Paste")
			(roundrect_rratio 0.25)
			(net 417 "GND")
			(pintype "passive")
		)
		(pad "2" smd roundrect
			(at 0.48 0 180)
			(size 0.59 0.64)
			(layers "B.Cu" "B.Mask" "B.Paste")
			(roundrect_rratio 0.25)
			(net 176 "/MIPI CrossLink/CL_VCC")
			(pintype "passive")
		)
	)
	(footprint "antmicro-footprints:C_0603_1608Metric"
		(layer "B.Cu")
		(at 189.28 146.14 180)
		(descr "Capacitor SMD 0603")
		(tags "capacitor 0603")
		(property "Reference" "C47"
			(at -2.45 -3.525 0)
			(layer "B.SilkS")
			(effects
				(font
					(size 0.7 0.7)
					(thickness 0.15)
				)
				(justify left bottom mirror)
			)
		)
		(property "Value" "C_47u_0603"
			(at -1.42757 -1.770288 0)
			(layer "B.Fab")
			(hide yes)
			(effects
				(font
					(size 0.7 0.7)
					(thickness 0.15)
				)
				(justify left bottom mirror)
			)
		)
		(property "Datasheet" "https://www.murata.com/products/productdetail?partno=GRM188R60J476ME15%23"
			(at 0 0 180)
			(layer "F.Fab")
			(hide yes)
			(effects
				(font
					(size 1.27 1.27)
					(thickness 0.15)
				)
			)
		)
		(property "Description" "SMD Multilayer Ceramic Capacitor, 47 µF, 6.3 V, 0603 [1608 Metric], ± 20%, X5R, GRM Series"
			(at 0 0 180)
			(layer "F.Fab")
			(hide yes)
			(effects
				(font
					(size 1.27 1.27)
					(thickness 0.15)
				)
			)
		)
		(property "Author" "Antmicro"
			(at 378.56 292.28 0)
			(layer "B.Fab")
			(hide yes)
			(effects
				(font
					(size 1 1)
					(thickness 0.15)
				)
				(justify mirror)
			)
		)
		(property "Capacitance" "47u"
			(at 378.56 292.28 0)
			(layer "B.Fab")
			(hide yes)
			(effects
				(font
					(size 1 1)
					(thickness 0.15)
				)
				(justify mirror)
			)
		)
		(property "Dielectric" "X7R"
			(at 378.56 292.28 0)
			(layer "B.Fab")
			(hide yes)
			(effects
				(font
					(size 1 1)
					(thickness 0.15)
				)
				(justify mirror)
			)
		)
		(property "License" "Apache-2.0"
			(at 378.56 292.28 0)
			(layer "B.Fab")
			(hide yes)
			(effects
				(font
					(size 1 1)
					(thickness 0.15)
				)
				(justify mirror)
			)
		)
		(property "MPN" "GRM188R60J476ME15D"
			(at 378.56 292.28 0)
			(layer "B.Fab")
			(hide yes)
			(effects
				(font
					(size 1 1)
					(thickness 0.15)
				)
				(justify mirror)
			)
		)
		(property "Manufacturer" "Murata"
			(at 378.56 292.28 0)
			(layer "B.Fab")
			(hide yes)
			(effects
				(font
					(size 1 1)
					(thickness 0.15)
				)
				(justify mirror)
			)
		)
		(property "Public" ""
			(at 378.56 292.28 0)
			(layer "B.Fab")
			(hide yes)
			(effects
				(font
					(size 1 1)
					(thickness 0.15)
				)
				(justify mirror)
			)
		)
		(property "Val" "47u"
			(at 378.56 292.28 0)
			(layer "B.Fab")
			(hide yes)
			(effects
				(font
					(size 1 1)
					(thickness 0.15)
				)
				(justify mirror)
			)
		)
		(property "Voltage" "50V"
			(at 378.56 292.28 0)
			(layer "B.Fab")
			(hide yes)
			(effects
				(font
					(size 1 1)
					(thickness 0.15)
				)
				(justify mirror)
			)
		)
		(sheetname "/FPGA Supply/")
		(sheetfile "fpga-supply.kicad_sch")
		(attr smd)
		(fp_line
			(start -0.15 0.4)
			(end 0.15 0.4)
			(stroke
				(width 0.15)
				(type solid)
			)
			(layer "B.SilkS")
		)
		(fp_line
			(start -0.15 -0.4)
			(end 0.15 -0.4)
			(stroke
				(width 0.15)
				(type solid)
			)
			(layer "B.SilkS")
		)
		(fp_rect
			(start -1.25 0.65)
			(end 1.25 -0.65)
			(stroke
				(width 0.05)
				(type solid)
			)
			(fill no)
			(layer "B.CrtYd")
		)
		(fp_rect
			(start -0.8 0.4)
			(end 0.8 -0.4)
			(stroke
				(width 0.15)
				(type solid)
			)
			(fill no)
			(layer "B.Fab")
		)
		(fp_text user "${REFERENCE}"
			(at -1.682 -3.895 0)
			(layer "B.Fab")
			(effects
				(font
					(size 0.7 0.7)
					(thickness 0.15)
				)
				(justify left bottom mirror)
			)
		)
		(fp_text user "License: Apache-2.0"
			(at -1.682 -5.895 0)
			(layer "B.Fab")
			(effects
				(font
					(size 0.7 0.7)
					(thickness 0.15)
				)
				(justify left bottom mirror)
			)
		)
		(fp_text user "Author: Antmicro"
			(at -1.682 -4.894 0)
			(layer "B.Fab")
			(effects
				(font
					(size 0.7 0.7)
					(thickness 0.15)
				)
				(justify left bottom mirror)
			)
		)
		(pad "1" smd roundrect
			(at -0.7 0 180)
			(size 0.8 1)
			(layers "B.Cu" "B.Mask" "B.Paste")
			(roundrect_rratio 0.2)
			(net 417 "GND")
			(pintype "passive")
		)
		(pad "2" smd roundrect
			(at 0.7 0 180)
			(size 0.8 1)
			(layers "B.Cu" "B.Mask" "B.Paste")
			(roundrect_rratio 0.2)
			(net 47 "+1V05")
			(pintype "passive")
		)
	)
	(footprint "antmicro-footprints:C_0402_1005Metric"
		(layer "B.Cu")
		(at 197.04 134.73 90)
		(descr "Capacitor SMD 0402")
		(tags "capacitor SMD 0402")
		(property "Reference" "C44"
			(at 7.58 -9.615 270)
			(layer "B.SilkS")
			(effects
				(font
					(size 0.7 0.7)
					(thickness 0.15)
				)
				(justify left bottom mirror)
			)
		)
		(property "Value" "C_22n_0402"
			(at -1.022927 -2.155213 270)
			(layer "B.Fab")
			(hide yes)
			(effects
				(font
					(size 0.7 0.7)
					(thickness 0.15)
				)
				(justify left bottom mirror)
			)
		)
		(property "Datasheet" "https://www.murata.com/products/productdetail?partno=GCM155R71H223MA55%23"
			(at 0 0 90)
			(layer "F.Fab")
			(hide yes)
			(effects
				(font
					(size 1.27 1.27)
					(thickness 0.15)
				)
			)
		)
		(property "Description" "SMD Multilayer Ceramic Capacitors, 0.022 µF, 50 V, 20%, 0402 [1005 Metric], X7R"
			(at 0 0 90)
			(layer "F.Fab")
			(hide yes)
			(effects
				(font
					(size 1.27 1.27)
					(thickness 0.15)
				)
			)
		)
		(property "Author" "Antmicro"
			(at 331.77 -62.31 0)
			(layer "B.Fab")
			(hide yes)
			(effects
				(font
					(size 1 1)
					(thickness 0.15)
				)
				(justify mirror)
			)
		)
		(property "Dielectric" ""
			(at 331.77 -62.31 0)
			(layer "B.Fab")
			(hide yes)
			(effects
				(font
					(size 1 1)
					(thickness 0.15)
				)
				(justify mirror)
			)
		)
		(property "License" "Apache-2.0"
			(at 331.77 -62.31 0)
			(layer "B.Fab")
			(hide yes)
			(effects
				(font
					(size 1 1)
					(thickness 0.15)
				)
				(justify mirror)
			)
		)
		(property "MPN" "GCM155R71H223MA55D"
			(at 331.77 -62.31 0)
			(layer "B.Fab")
			(hide yes)
			(effects
				(font
					(size 1 1)
					(thickness 0.15)
				)
				(justify mirror)
			)
		)
		(property "Manufacturer" "Murata"
			(at 331.77 -62.31 0)
			(layer "B.Fab")
			(hide yes)
			(effects
				(font
					(size 1 1)
					(thickness 0.15)
				)
				(justify mirror)
			)
		)
		(property "Public" ""
			(at 331.77 -62.31 0)
			(layer "B.Fab")
			(hide yes)
			(effects
				(font
					(size 1 1)
					(thickness 0.15)
				)
				(justify mirror)
			)
		)
		(property "Val" "22n"
			(at 331.77 -62.31 0)
			(layer "B.Fab")
			(hide yes)
			(effects
				(font
					(size 1 1)
					(thickness 0.15)
				)
				(justify mirror)
			)
		)
		(property "Voltage" ""
			(at 331.77 -62.31 0)
			(layer "B.Fab")
			(hide yes)
			(effects
				(font
					(size 1 1)
					(thickness 0.15)
				)
				(justify mirror)
			)
		)
		(sheetname "/FPGA Supply/")
		(sheetfile "fpga-supply.kicad_sch")
		(attr smd)
		(fp_rect
			(start -0.925 0.47)
			(end 0.925 -0.47)
			(stroke
				(width 0.05)
				(type default)
			)
			(fill no)
			(layer "B.CrtYd")
		)
		(fp_line
			(start 0.504 -0.248)
			(end -0.494 -0.248)
			(stroke
				(width 0.15)
				(type solid)
			)
			(layer "B.Fab")
		)
		(fp_line
			(start -0.494 -0.248)
			(end -0.494 0.25)
			(stroke
				(width 0.15)
				(type solid)
			)
			(layer "B.Fab")
		)
		(fp_line
			(start 0.504 0.25)
			(end 0.504 -0.248)
			(stroke
				(width 0.15)
				(type solid)
			)
			(layer "B.Fab")
		)
		(fp_line
			(start -0.494 0.25)
			(end 0.504 0.25)
			(stroke
				(width 0.15)
				(type solid)
			)
			(layer "B.Fab")
		)
		(fp_text user "License: Apache-2.0"
			(at -0.939 -5.799 270)
			(layer "B.Fab")
			(effects
				(font
					(size 0.7 0.7)
					(thickness 0.15)
				)
				(justify left bottom mirror)
			)
		)
		(fp_text user "${REFERENCE}"
			(at -0.939 -4.599 270)
			(layer "B.Fab")
			(effects
				(font
					(size 0.7 0.7)
					(thickness 0.15)
				)
				(justify left bottom mirror)
			)
		)
		(fp_text user "Author: Antmicro"
			(at -0.939 -3.399 270)
			(layer "B.Fab")
			(effects
				(font
					(size 0.7 0.7)
					(thickness 0.15)
				)
				(justify left bottom mirror)
			)
		)
		(pad "1" smd roundrect
			(at -0.48 0 90)
			(size 0.59 0.64)
			(layers "B.Cu" "B.Mask" "B.Paste")
			(roundrect_rratio 0.25)
			(net 417 "GND")
			(pintype "passive")
		)
		(pad "2" smd roundrect
			(at 0.48 0 90)
			(size 0.59 0.64)
			(layers "B.Cu" "B.Mask" "B.Paste")
			(roundrect_rratio 0.25)
			(net 47 "+1V05")
			(pintype "passive")
		)
	)
	(footprint "antmicro-footprints:C_0402_1005Metric"
		(layer "B.Cu")
		(at 199.55 140.564 90)
		(descr "Capacitor SMD 0402")
		(tags "capacitor SMD 0402")
		(property "Reference" "C39"
			(at -1.776 3.37 90)
			(layer "B.SilkS")
			(effects
				(font
					(size 0.7 0.7)
					(thickness 0.15)
				)
				(justify right bottom mirror)
			)
		)
		(property "Value" "C_100n_0402"
			(at -1.022927 -2.155213 90)
			(layer "B.Fab")
			(hide yes)
			(effects
				(font
					(size 0.7 0.7)
					(thickness 0.15)
				)
				(justify right bottom mirror)
			)
		)
		(property "Datasheet" "https://www.murata.com/products/productdetail?partno=GRM155R61H104KE14%23"
			(at 0 0 90)
			(layer "F.Fab")
			(hide yes)
			(effects
				(font
					(size 1.27 1.27)
					(thickness 0.15)
				)
			)
		)
		(property "Description" "SMD Multilayer Ceramic Capacitor, 0.1 µF, 50 V, 0402 [1005 Metric], ± 10%, X5R, GRM Series"
			(at 0 0 90)
			(layer "F.Fab")
			(hide yes)
			(effects
				(font
					(size 1.27 1.27)
					(thickness 0.15)
				)
			)
		)
		(property "Author" "Antmicro"
			(at 340.114 -58.986 0)
			(layer "B.Fab")
			(hide yes)
			(effects
				(font
					(size 1 1)
					(thickness 0.15)
				)
				(justify mirror)
			)
		)
		(property "Dielectric" "X5R"
			(at 340.114 -58.986 0)
			(layer "B.Fab")
			(hide yes)
			(effects
				(font
					(size 1 1)
					(thickness 0.15)
				)
				(justify mirror)
			)
		)
		(property "License" "Apache-2.0"
			(at 340.114 -58.986 0)
			(layer "B.Fab")
			(hide yes)
			(effects
				(font
					(size 1 1)
					(thickness 0.15)
				)
				(justify mirror)
			)
		)
		(property "MPN" "GRM155R61H104KE14D"
			(at 340.114 -58.986 0)
			(layer "B.Fab")
			(hide yes)
			(effects
				(font
					(size 1 1)
					(thickness 0.15)
				)
				(justify mirror)
			)
		)
		(property "Manufacturer" "Murata"
			(at 340.114 -58.986 0)
			(layer "B.Fab")
			(hide yes)
			(effects
				(font
					(size 1 1)
					(thickness 0.15)
				)
				(justify mirror)
			)
		)
		(property "Public" ""
			(at 340.114 -58.986 0)
			(layer "B.Fab")
			(hide yes)
			(effects
				(font
					(size 1 1)
					(thickness 0.15)
				)
				(justify mirror)
			)
		)
		(property "Val" "100n"
			(at 340.114 -58.986 0)
			(layer "B.Fab")
			(hide yes)
			(effects
				(font
					(size 1 1)
					(thickness 0.15)
				)
				(justify mirror)
			)
		)
		(property "Voltage" "50V"
			(at 340.114 -58.986 0)
			(layer "B.Fab")
			(hide yes)
			(effects
				(font
					(size 1 1)
					(thickness 0.15)
				)
				(justify mirror)
			)
		)
		(sheetname "/FPGA Supply/")
		(sheetfile "fpga-supply.kicad_sch")
		(attr smd)
		(fp_rect
			(start -0.925 0.47)
			(end 0.925 -0.47)
			(stroke
				(width 0.05)
				(type default)
			)
			(fill no)
			(layer "B.CrtYd")
		)
		(fp_line
			(start 0.504 -0.248)
			(end -0.494 -0.248)
			(stroke
				(width 0.15)
				(type solid)
			)
			(layer "B.Fab")
		)
		(fp_line
			(start -0.494 -0.248)
			(end -0.494 0.25)
			(stroke
				(width 0.15)
				(type solid)
			)
			(layer "B.Fab")
		)
		(fp_line
			(start 0.504 0.25)
			(end 0.504 -0.248)
			(stroke
				(width 0.15)
				(type solid)
			)
			(layer "B.Fab")
		)
		(fp_line
			(start -0.494 0.25)
			(end 0.504 0.25)
			(stroke
				(width 0.15)
				(type solid)
			)
			(layer "B.Fab")
		)
		(fp_text user "Author: Antmicro"
			(at -0.939 -3.399 270)
			(layer "B.Fab")
			(effects
				(font
					(size 0.7 0.7)
					(thickness 0.15)
				)
				(justify left bottom mirror)
			)
		)
		(fp_text user "${REFERENCE}"
			(at -0.939 -4.599 270)
			(layer "B.Fab")
			(effects
				(font
					(size 0.7 0.7)
					(thickness 0.15)
				)
				(justify left bottom mirror)
			)
		)
		(fp_text user "License: Apache-2.0"
			(at -0.939 -5.799 270)
			(layer "B.Fab")
			(effects
				(font
					(size 0.7 0.7)
					(thickness 0.15)
				)
				(justify left bottom mirror)
			)
		)
		(pad "1" smd roundrect
			(at -0.48 0 90)
			(size 0.59 0.64)
			(layers "B.Cu" "B.Mask" "B.Paste")
			(roundrect_rratio 0.25)
			(net 417 "GND")
			(pintype "passive")
		)
		(pad "2" smd roundrect
			(at 0.48 0 90)
			(size 0.59 0.64)
			(layers "B.Cu" "B.Mask" "B.Paste")
			(roundrect_rratio 0.25)
			(net 47 "+1V05")
			(pintype "passive")
		)
	)
	(footprint "antmicro-footprints:C_0402_1005Metric"
		(layer "B.Cu")
		(at 175.25 134.66 90)
		(descr "Capacitor SMD 0402")
		(tags "capacitor SMD 0402")
		(property "Reference" "C122"
			(at 2.12 1.38 90)
			(layer "B.SilkS")
			(effects
				(font
					(size 0.7 0.7)
					(thickness 0.15)
				)
				(justify left bottom mirror)
			)
		)
		(property "Value" "C_1u_0402"
			(at -1.022927 -2.155213 270)
			(layer "B.Fab")
			(hide yes)
			(effects
				(font
					(size 0.7 0.7)
					(thickness 0.15)
				)
				(justify left bottom mirror)
			)
		)
		(property "Datasheet" "https://product.tdk.com/en/search/capacitor/ceramic/mlcc/info?part_no=C1005X6S1A105K050BC"
			(at 0 0 90)
			(layer "F.Fab")
			(hide yes)
			(effects
				(font
					(size 1.27 1.27)
					(thickness 0.15)
				)
			)
		)
		(property "Description" "SMD Multilayer Ceramic Capacitor, 1 µF, 10 V, 0402 [1005 Metric], ± 10%, X6S, C"
			(at 0 0 90)
			(layer "F.Fab")
			(hide yes)
			(effects
				(font
					(size 1.27 1.27)
					(thickness 0.15)
				)
			)
		)
		(property "Author" "Antmicro"
			(at 309.91 -40.59 0)
			(layer "B.Fab")
			(hide yes)
			(effects
				(font
					(size 1 1)
					(thickness 0.15)
				)
				(justify mirror)
			)
		)
		(property "Dielectric" "X5R"
			(at 309.91 -40.59 0)
			(layer "B.Fab")
			(hide yes)
			(effects
				(font
					(size 1 1)
					(thickness 0.15)
				)
				(justify mirror)
			)
		)
		(property "License" "Apache-2.0"
			(at 309.91 -40.59 0)
			(layer "B.Fab")
			(hide yes)
			(effects
				(font
					(size 1 1)
					(thickness 0.15)
				)
				(justify mirror)
			)
		)
		(property "MPN" "C1005X6S1A105K050BC"
			(at 309.91 -40.59 0)
			(layer "B.Fab")
			(hide yes)
			(effects
				(font
					(size 1 1)
					(thickness 0.15)
				)
				(justify mirror)
			)
		)
		(property "Manufacturer" "TDK"
			(at 309.91 -40.59 0)
			(layer "B.Fab")
			(hide yes)
			(effects
				(font
					(size 1 1)
					(thickness 0.15)
				)
				(justify mirror)
			)
		)
		(property "Public" ""
			(at 309.91 -40.59 0)
			(layer "B.Fab")
			(hide yes)
			(effects
				(font
					(size 1 1)
					(thickness 0.15)
				)
				(justify mirror)
			)
		)
		(property "Val" "1u"
			(at 309.91 -40.59 0)
			(layer "B.Fab")
			(hide yes)
			(effects
				(font
					(size 1 1)
					(thickness 0.15)
				)
				(justify mirror)
			)
		)
		(property "Voltage" "16V"
			(at 309.91 -40.59 0)
			(layer "B.Fab")
			(hide yes)
			(effects
				(font
					(size 1 1)
					(thickness 0.15)
				)
				(justify mirror)
			)
		)
		(sheetname "/LPDDR4/")
		(sheetfile "lpddr.kicad_sch")
		(attr smd)
		(fp_rect
			(start -0.925 0.47)
			(end 0.925 -0.47)
			(stroke
				(width 0.05)
				(type default)
			)
			(fill no)
			(layer "B.CrtYd")
		)
		(fp_line
			(start 0.504 -0.248)
			(end -0.494 -0.248)
			(stroke
				(width 0.15)
				(type solid)
			)
			(layer "B.Fab")
		)
		(fp_line
			(start -0.494 -0.248)
			(end -0.494 0.25)
			(stroke
				(width 0.15)
				(type solid)
			)
			(layer "B.Fab")
		)
		(fp_line
			(start 0.504 0.25)
			(end 0.504 -0.248)
			(stroke
				(width 0.15)
				(type solid)
			)
			(layer "B.Fab")
		)
		(fp_line
			(start -0.494 0.25)
			(end 0.504 0.25)
			(stroke
				(width 0.15)
				(type solid)
			)
			(layer "B.Fab")
		)
		(fp_text user "License: Apache-2.0"
			(at -0.939 -5.799 270)
			(layer "B.Fab")
			(effects
				(font
					(size 0.7 0.7)
					(thickness 0.15)
				)
				(justify left bottom mirror)
			)
		)
		(fp_text user "${REFERENCE}"
			(at -0.939 -4.599 270)
			(layer "B.Fab")
			(effects
				(font
					(size 0.7 0.7)
					(thickness 0.15)
				)
				(justify left bottom mirror)
			)
		)
		(fp_text user "Author: Antmicro"
			(at -0.939 -3.399 270)
			(layer "B.Fab")
			(effects
				(font
					(size 0.7 0.7)
					(thickness 0.15)
				)
				(justify left bottom mirror)
			)
		)
		(pad "1" smd roundrect
			(at -0.48 0 90)
			(size 0.59 0.64)
			(layers "B.Cu" "B.Mask" "B.Paste")
			(roundrect_rratio 0.25)
			(net 417 "GND")
			(pintype "passive")
		)
		(pad "2" smd roundrect
			(at 0.48 0 90)
			(size 0.59 0.64)
			(layers "B.Cu" "B.Mask" "B.Paste")
			(roundrect_rratio 0.25)
			(net 48 "+1V8")
			(pintype "passive")
		)
	)
	(footprint "antmicro-footprints:C_0402_1005Metric"
		(layer "B.Cu")
		(at 182.4 122.45 180)
		(descr "Capacitor SMD 0402")
		(tags "capacitor SMD 0402")
		(property "Reference" "C162"
			(at -0.775 -1.425 0)
			(layer "B.SilkS")
			(effects
				(font
					(size 0.7 0.7)
					(thickness 0.15)
				)
				(justify left bottom mirror)
			)
		)
		(property "Value" "C_1u_0402"
			(at -1.022927 -2.155213 0)
			(layer "B.Fab")
			(hide yes)
			(effects
				(font
					(size 0.7 0.7)
					(thickness 0.15)
				)
				(justify left bottom mirror)
			)
		)
		(property "Datasheet" "https://product.tdk.com/en/search/capacitor/ceramic/mlcc/info?part_no=C1005X6S1A105K050BC"
			(at 0 0 180)
			(layer "F.Fab")
			(hide yes)
			(effects
				(font
					(size 1.27 1.27)
					(thickness 0.15)
				)
			)
		)
		(property "Description" "SMD Multilayer Ceramic Capacitor, 1 µF, 10 V, 0402 [1005 Metric], ± 10%, X6S, C"
			(at 0 0 180)
			(layer "F.Fab")
			(hide yes)
			(effects
				(font
					(size 1.27 1.27)
					(thickness 0.15)
				)
			)
		)
		(property "Author" "Antmicro"
			(at 364.8 244.9 0)
			(layer "B.Fab")
			(hide yes)
			(effects
				(font
					(size 1 1)
					(thickness 0.15)
				)
				(justify mirror)
			)
		)
		(property "Dielectric" "X5R"
			(at 364.8 244.9 0)
			(layer "B.Fab")
			(hide yes)
			(effects
				(font
					(size 1 1)
					(thickness 0.15)
				)
				(justify mirror)
			)
		)
		(property "License" "Apache-2.0"
			(at 364.8 244.9 0)
			(layer "B.Fab")
			(hide yes)
			(effects
				(font
					(size 1 1)
					(thickness 0.15)
				)
				(justify mirror)
			)
		)
		(property "MPN" "C1005X6S1A105K050BC"
			(at 364.8 244.9 0)
			(layer "B.Fab")
			(hide yes)
			(effects
				(font
					(size 1 1)
					(thickness 0.15)
				)
				(justify mirror)
			)
		)
		(property "Manufacturer" "TDK"
			(at 364.8 244.9 0)
			(layer "B.Fab")
			(hide yes)
			(effects
				(font
					(size 1 1)
					(thickness 0.15)
				)
				(justify mirror)
			)
		)
		(property "Public" ""
			(at 364.8 244.9 0)
			(layer "B.Fab")
			(hide yes)
			(effects
				(font
					(size 1 1)
					(thickness 0.15)
				)
				(justify mirror)
			)
		)
		(property "Val" "1u"
			(at 364.8 244.9 0)
			(layer "B.Fab")
			(hide yes)
			(effects
				(font
					(size 1 1)
					(thickness 0.15)
				)
				(justify mirror)
			)
		)
		(property "Voltage" "16V"
			(at 364.8 244.9 0)
			(layer "B.Fab")
			(hide yes)
			(effects
				(font
					(size 1 1)
					(thickness 0.15)
				)
				(justify mirror)
			)
		)
		(sheetname "/LPDDR4/")
		(sheetfile "lpddr.kicad_sch")
		(attr smd)
		(fp_rect
			(start -0.925 0.47)
			(end 0.925 -0.47)
			(stroke
				(width 0.05)
				(type default)
			)
			(fill no)
			(layer "B.CrtYd")
		)
		(fp_line
			(start 0.504 0.25)
			(end 0.504 -0.248)
			(stroke
				(width 0.15)
				(type solid)
			)
			(layer "B.Fab")
		)
		(fp_line
			(start 0.504 -0.248)
			(end -0.494 -0.248)
			(stroke
				(width 0.15)
				(type solid)
			)
			(layer "B.Fab")
		)
		(fp_line
			(start -0.494 0.25)
			(end 0.504 0.25)
			(stroke
				(width 0.15)
				(type solid)
			)
			(layer "B.Fab")
		)
		(fp_line
			(start -0.494 -0.248)
			(end -0.494 0.25)
			(stroke
				(width 0.15)
				(type solid)
			)
			(layer "B.Fab")
		)
		(fp_text user "License: Apache-2.0"
			(at -0.939 -5.799 0)
			(layer "B.Fab")
			(effects
				(font
					(size 0.7 0.7)
					(thickness 0.15)
				)
				(justify left bottom mirror)
			)
		)
		(fp_text user "Author: Antmicro"
			(at -0.939 -3.399 0)
			(layer "B.Fab")
			(effects
				(font
					(size 0.7 0.7)
					(thickness 0.15)
				)
				(justify left bottom mirror)
			)
		)
		(fp_text user "${REFERENCE}"
			(at -0.939 -4.599 0)
			(layer "B.Fab")
			(effects
				(font
					(size 0.7 0.7)
					(thickness 0.15)
				)
				(justify left bottom mirror)
			)
		)
		(pad "1" smd roundrect
			(at -0.48 0 180)
			(size 0.59 0.64)
			(layers "B.Cu" "B.Mask" "B.Paste")
			(roundrect_rratio 0.25)
			(net 417 "GND")
			(pintype "passive")
		)
		(pad "2" smd roundrect
			(at 0.48 0 180)
			(size 0.59 0.64)
			(layers "B.Cu" "B.Mask" "B.Paste")
			(roundrect_rratio 0.25)
			(net 2 "+1V1")
			(pintype "passive")
		)
	)
	(footprint "antmicro-footprints:R_0402_1005Metric"
		(layer "B.Cu")
		(at 186.8 120.85 -90)
		(descr "Resistor SMD 0402")
		(tags "resistor SMD 0402")
		(property "Reference" "R44"
			(at -4.875 -0.275 90)
			(layer "B.SilkS")
			(effects
				(font
					(size 0.7 0.7)
					(thickness 0.15)
				)
				(justify left bottom mirror)
			)
		)
		(property "Value" "R_1k_0402"
			(at -1.011843 -1.772047 90)
			(layer "B.Fab")
			(hide yes)
			(effects
				(font
					(size 0.7 0.7)
					(thickness 0.15)
				)
				(justify left bottom mirror)
			)
		)
		(property "Datasheet" "https://www.bourns.com/docs/product-datasheets/cr.pdf"
			(at 0 0 270)
			(layer "F.Fab")
			(hide yes)
			(effects
				(font
					(size 1.27 1.27)
					(thickness 0.15)
				)
			)
		)
		(property "Description" "SMD Chip Resistor, 1 kohm, ± 1%, 63 mW, 0402 [1005 Metric], Thick Film, General Purpose"
			(at 0 0 270)
			(layer "F.Fab")
			(hide yes)
			(effects
				(font
					(size 1.27 1.27)
					(thickness 0.15)
				)
			)
		)
		(property "Author" "Antmicro"
			(at 65.95 307.65 0)
			(layer "B.Fab")
			(hide yes)
			(effects
				(font
					(size 1 1)
					(thickness 0.15)
				)
				(justify mirror)
			)
		)
		(property "License" "Apache-2.0"
			(at 65.95 307.65 0)
			(layer "B.Fab")
			(hide yes)
			(effects
				(font
					(size 1 1)
					(thickness 0.15)
				)
				(justify mirror)
			)
		)
		(property "MPN" "CR0402-FX-1001GLF"
			(at 65.95 307.65 0)
			(layer "B.Fab")
			(hide yes)
			(effects
				(font
					(size 1 1)
					(thickness 0.15)
				)
				(justify mirror)
			)
		)
		(property "Manufacturer" "Bourns"
			(at 65.95 307.65 0)
			(layer "B.Fab")
			(hide yes)
			(effects
				(font
					(size 1 1)
					(thickness 0.15)
				)
				(justify mirror)
			)
		)
		(property "Public" ""
			(at 65.95 307.65 0)
			(layer "B.Fab")
			(hide yes)
			(effects
				(font
					(size 1 1)
					(thickness 0.15)
				)
				(justify mirror)
			)
		)
		(property "Tolerance" "1%"
			(at 65.95 307.65 0)
			(layer "B.Fab")
			(hide yes)
			(effects
				(font
					(size 1 1)
					(thickness 0.15)
				)
				(justify mirror)
			)
		)
		(property "Val" "1k"
			(at 65.95 307.65 0)
			(layer "B.Fab")
			(hide yes)
			(effects
				(font
					(size 1 1)
					(thickness 0.15)
				)
				(justify mirror)
			)
		)
		(sheetname "/FPGA Config/")
		(sheetfile "fpga-config.kicad_sch")
		(attr smd)
		(fp_rect
			(start -0.925 0.47)
			(end 0.925 -0.47)
			(stroke
				(width 0.05)
				(type default)
			)
			(fill no)
			(layer "B.CrtYd")
		)
		(fp_rect
			(start -0.5 0.25)
			(end 0.5 -0.25)
			(stroke
				(width 0.15)
				(type solid)
			)
			(fill no)
			(layer "B.Fab")
		)
		(fp_text user "Author: Antmicro"
			(at -0.95 -4.169 90)
			(layer "B.Fab")
			(effects
				(font
					(size 0.7 0.7)
					(thickness 0.15)
				)
				(justify left bottom mirror)
			)
		)
		(fp_text user "${REFERENCE}"
			(at -0.95 -3.168 90)
			(layer "B.Fab")
			(effects
				(font
					(size 0.7 0.7)
					(thickness 0.15)
				)
				(justify left bottom mirror)
			)
		)
		(fp_text user "License: Apache-2.0"
			(at -0.95 -5.169 90)
			(layer "B.Fab")
			(effects
				(font
					(size 0.7 0.7)
					(thickness 0.15)
				)
				(justify left bottom mirror)
			)
		)
		(pad "1" smd roundrect
			(at -0.48 0 270)
			(size 0.59 0.64)
			(layers "B.Cu" "B.Mask" "B.Paste")
			(roundrect_rratio 0.25)
			(net 127 "JTAG_RESET_n")
			(pintype "passive")
		)
		(pad "2" smd roundrect
			(at 0.48 0 270)
			(size 0.59 0.64)
			(layers "B.Cu" "B.Mask" "B.Paste")
			(roundrect_rratio 0.25)
			(net 50 "+3V3")
			(pintype "passive")
		)
	)
	(footprint "antmicro-footprints:C_0402_1005Metric"
		(layer "B.Cu")
		(at 177.2 130.9 90)
		(descr "Capacitor SMD 0402")
		(tags "capacitor SMD 0402")
		(property "Reference" "C144"
			(at 0.344 0.411 180)
			(layer "B.SilkS")
			(effects
				(font
					(size 0.7 0.7)
					(thickness 0.15)
				)
				(justify right bottom mirror)
			)
		)
		(property "Value" "C_1u_0402"
			(at -1.022927 -2.155213 90)
			(layer "B.Fab")
			(hide yes)
			(effects
				(font
					(size 0.7 0.7)
					(thickness 0.15)
				)
				(justify right bottom mirror)
			)
		)
		(property "Datasheet" "https://product.tdk.com/en/search/capacitor/ceramic/mlcc/info?part_no=C1005X6S1A105K050BC"
			(at 0 0 90)
			(layer "F.Fab")
			(hide yes)
			(effects
				(font
					(size 1.27 1.27)
					(thickness 0.15)
				)
			)
		)
		(property "Description" "SMD Multilayer Ceramic Capacitor, 1 µF, 10 V, 0402 [1005 Metric], ± 10%, X6S, C"
			(at 0 0 90)
			(layer "F.Fab")
			(hide yes)
			(effects
				(font
					(size 1.27 1.27)
					(thickness 0.15)
				)
			)
		)
		(property "Author" "Antmicro"
			(at 308.1 -46.3 0)
			(layer "B.Fab")
			(hide yes)
			(effects
				(font
					(size 1 1)
					(thickness 0.15)
				)
				(justify mirror)
			)
		)
		(property "Dielectric" "X5R"
			(at 308.1 -46.3 0)
			(layer "B.Fab")
			(hide yes)
			(effects
				(font
					(size 1 1)
					(thickness 0.15)
				)
				(justify mirror)
			)
		)
		(property "License" "Apache-2.0"
			(at 308.1 -46.3 0)
			(layer "B.Fab")
			(hide yes)
			(effects
				(font
					(size 1 1)
					(thickness 0.15)
				)
				(justify mirror)
			)
		)
		(property "MPN" "C1005X6S1A105K050BC"
			(at 308.1 -46.3 0)
			(layer "B.Fab")
			(hide yes)
			(effects
				(font
					(size 1 1)
					(thickness 0.15)
				)
				(justify mirror)
			)
		)
		(property "Manufacturer" "TDK"
			(at 308.1 -46.3 0)
			(layer "B.Fab")
			(hide yes)
			(effects
				(font
					(size 1 1)
					(thickness 0.15)
				)
				(justify mirror)
			)
		)
		(property "Public" ""
			(at 308.1 -46.3 0)
			(layer "B.Fab")
			(hide yes)
			(effects
				(font
					(size 1 1)
					(thickness 0.15)
				)
				(justify mirror)
			)
		)
		(property "Val" "1u"
			(at 308.1 -46.3 0)
			(layer "B.Fab")
			(hide yes)
			(effects
				(font
					(size 1 1)
					(thickness 0.15)
				)
				(justify mirror)
			)
		)
		(property "Voltage" "16V"
			(at 308.1 -46.3 0)
			(layer "B.Fab")
			(hide yes)
			(effects
				(font
					(size 1 1)
					(thickness 0.15)
				)
				(justify mirror)
			)
		)
		(sheetname "/LPDDR4/")
		(sheetfile "lpddr.kicad_sch")
		(attr smd)
		(fp_rect
			(start -0.925 0.47)
			(end 0.925 -0.47)
			(stroke
				(width 0.05)
				(type default)
			)
			(fill no)
			(layer "B.CrtYd")
		)
		(fp_line
			(start 0.504 -0.248)
			(end -0.494 -0.248)
			(stroke
				(width 0.15)
				(type solid)
			)
			(layer "B.Fab")
		)
		(fp_line
			(start -0.494 -0.248)
			(end -0.494 0.25)
			(stroke
				(width 0.15)
				(type solid)
			)
			(layer "B.Fab")
		)
		(fp_line
			(start 0.504 0.25)
			(end 0.504 -0.248)
			(stroke
				(width 0.15)
				(type solid)
			)
			(layer "B.Fab")
		)
		(fp_line
			(start -0.494 0.25)
			(end 0.504 0.25)
			(stroke
				(width 0.15)
				(type solid)
			)
			(layer "B.Fab")
		)
		(fp_text user "License: Apache-2.0"
			(at -0.939 -5.799 270)
			(layer "B.Fab")
			(effects
				(font
					(size 0.7 0.7)
					(thickness 0.15)
				)
				(justify left bottom mirror)
			)
		)
		(fp_text user "${REFERENCE}"
			(at -0.939 -4.599 270)
			(layer "B.Fab")
			(effects
				(font
					(size 0.7 0.7)
					(thickness 0.15)
				)
				(justify left bottom mirror)
			)
		)
		(fp_text user "Author: Antmicro"
			(at -0.939 -3.399 270)
			(layer "B.Fab")
			(effects
				(font
					(size 0.7 0.7)
					(thickness 0.15)
				)
				(justify left bottom mirror)
			)
		)
		(pad "1" smd roundrect
			(at -0.48 0 90)
			(size 0.59 0.64)
			(layers "B.Cu" "B.Mask" "B.Paste")
			(roundrect_rratio 0.25)
			(net 417 "GND")
			(pintype "passive")
		)
		(pad "2" smd roundrect
			(at 0.48 0 90)
			(size 0.59 0.64)
			(layers "B.Cu" "B.Mask" "B.Paste")
			(roundrect_rratio 0.25)
			(net 2 "+1V1")
			(pintype "passive")
		)
	)
	(footprint "antmicro-footprints:C_0402_1005Metric"
		(layer "B.Cu")
		(at 210.577 124.3878)
		(descr "Capacitor SMD 0402")
		(tags "capacitor SMD 0402")
		(property "Reference" "C257"
			(at -3.727 2.6372 0)
			(layer "B.SilkS")
			(effects
				(font
					(size 0.7 0.7)
					(thickness 0.15)
				)
				(justify right bottom mirror)
			)
		)
		(property "Value" "C_100n_0402"
			(at -1.022927 -2.155213 0)
			(layer "B.Fab")
			(hide yes)
			(effects
				(font
					(size 0.7 0.7)
					(thickness 0.15)
				)
				(justify right bottom mirror)
			)
		)
		(property "Datasheet" "https://www.murata.com/products/productdetail?partno=GRM155R61H104KE14%23"
			(at 0 0 0)
			(layer "F.Fab")
			(hide yes)
			(effects
				(font
					(size 1.27 1.27)
					(thickness 0.15)
				)
			)
		)
		(property "Description" "SMD Multilayer Ceramic Capacitor, 0.1 µF, 50 V, 0402 [1005 Metric], ± 10%, X5R, GRM Series"
			(at 0 0 0)
			(layer "F.Fab")
			(hide yes)
			(effects
				(font
					(size 1.27 1.27)
					(thickness 0.15)
				)
			)
		)
		(property "Author" "Antmicro"
			(at 0 0 0)
			(layer "B.Fab")
			(hide yes)
			(effects
				(font
					(size 1 1)
					(thickness 0.15)
				)
				(justify mirror)
			)
		)
		(property "Dielectric" "X5R"
			(at 0 0 0)
			(layer "B.Fab")
			(hide yes)
			(effects
				(font
					(size 1 1)
					(thickness 0.15)
				)
				(justify mirror)
			)
		)
		(property "License" "Apache-2.0"
			(at 0 0 0)
			(layer "B.Fab")
			(hide yes)
			(effects
				(font
					(size 1 1)
					(thickness 0.15)
				)
				(justify mirror)
			)
		)
		(property "MPN" "GRM155R61H104KE14D"
			(at 0 0 0)
			(layer "B.Fab")
			(hide yes)
			(effects
				(font
					(size 1 1)
					(thickness 0.15)
				)
				(justify mirror)
			)
		)
		(property "Manufacturer" "Murata"
			(at 0 0 0)
			(layer "B.Fab")
			(hide yes)
			(effects
				(font
					(size 1 1)
					(thickness 0.15)
				)
				(justify mirror)
			)
		)
		(property "Public" ""
			(at 0 0 0)
			(layer "B.Fab")
			(hide yes)
			(effects
				(font
					(size 1 1)
					(thickness 0.15)
				)
				(justify mirror)
			)
		)
		(property "Val" "100n"
			(at 0 0 0)
			(layer "B.Fab")
			(hide yes)
			(effects
				(font
					(size 1 1)
					(thickness 0.15)
				)
				(justify mirror)
			)
		)
		(property "Voltage" "50V"
			(at 0 0 0)
			(layer "B.Fab")
			(hide yes)
			(effects
				(font
					(size 1 1)
					(thickness 0.15)
				)
				(justify mirror)
			)
		)
		(sheetname "/Ethernet/")
		(sheetfile "ethernet.kicad_sch")
		(attr smd)
		(fp_rect
			(start -0.925 0.47)
			(end 0.925 -0.47)
			(stroke
				(width 0.05)
				(type default)
			)
			(fill no)
			(layer "B.CrtYd")
		)
		(fp_line
			(start -0.494 -0.248)
			(end -0.494 0.25)
			(stroke
				(width 0.15)
				(type solid)
			)
			(layer "B.Fab")
		)
		(fp_line
			(start -0.494 0.25)
			(end 0.504 0.25)
			(stroke
				(width 0.15)
				(type solid)
			)
			(layer "B.Fab")
		)
		(fp_line
			(start 0.504 -0.248)
			(end -0.494 -0.248)
			(stroke
				(width 0.15)
				(type solid)
			)
			(layer "B.Fab")
		)
		(fp_line
			(start 0.504 0.25)
			(end 0.504 -0.248)
			(stroke
				(width 0.15)
				(type solid)
			)
			(layer "B.Fab")
		)
		(fp_text user "${REFERENCE}"
			(at -0.939 -4.599 180)
			(layer "B.Fab")
			(effects
				(font
					(size 0.7 0.7)
					(thickness 0.15)
				)
				(justify left bottom mirror)
			)
		)
		(fp_text user "License: Apache-2.0"
			(at -0.939 -5.799 180)
			(layer "B.Fab")
			(effects
				(font
					(size 0.7 0.7)
					(thickness 0.15)
				)
				(justify left bottom mirror)
			)
		)
		(fp_text user "Author: Antmicro"
			(at -0.939 -3.399 180)
			(layer "B.Fab")
			(effects
				(font
					(size 0.7 0.7)
					(thickness 0.15)
				)
				(justify left bottom mirror)
			)
		)
		(pad "1" smd roundrect
			(at -0.48 0)
			(size 0.59 0.64)
			(layers "B.Cu" "B.Mask" "B.Paste")
			(roundrect_rratio 0.25)
			(net 41 "/Ethernet/SGMII.RX0_N")
			(pintype "passive")
		)
		(pad "2" smd roundrect
			(at 0.48 0)
			(size 0.59 0.64)
			(layers "B.Cu" "B.Mask" "B.Paste")
			(roundrect_rratio 0.25)
			(net 166 "/Ethernet/SGMII_SO_N")
			(pintype "passive")
		)
	)
	(footprint "antmicro-footprints:C_0402_1005Metric"
		(layer "B.Cu")
		(at 180 125.1 90)
		(descr "Capacitor SMD 0402")
		(tags "capacitor SMD 0402")
		(property "Reference" "C163"
			(at 1.148 1.356 270)
			(layer "B.SilkS")
			(effects
				(font
					(size 0.7 0.7)
					(thickness 0.15)
				)
				(justify left bottom mirror)
			)
		)
		(property "Value" "C_1u_0402"
			(at -1.022927 -2.155213 270)
			(layer "B.Fab")
			(hide yes)
			(effects
				(font
					(size 0.7 0.7)
					(thickness 0.15)
				)
				(justify left bottom mirror)
			)
		)
		(property "Datasheet" "https://product.tdk.com/en/search/capacitor/ceramic/mlcc/info?part_no=C1005X6S1A105K050BC"
			(at 0 0 90)
			(layer "F.Fab")
			(hide yes)
			(effects
				(font
					(size 1.27 1.27)
					(thickness 0.15)
				)
			)
		)
		(property "Description" "SMD Multilayer Ceramic Capacitor, 1 µF, 10 V, 0402 [1005 Metric], ± 10%, X6S, C"
			(at 0 0 90)
			(layer "F.Fab")
			(hide yes)
			(effects
				(font
					(size 1.27 1.27)
					(thickness 0.15)
				)
			)
		)
		(property "Author" "Antmicro"
			(at 305.1 -54.9 0)
			(layer "B.Fab")
			(hide yes)
			(effects
				(font
					(size 1 1)
					(thickness 0.15)
				)
				(justify mirror)
			)
		)
		(property "Dielectric" "X5R"
			(at 305.1 -54.9 0)
			(layer "B.Fab")
			(hide yes)
			(effects
				(font
					(size 1 1)
					(thickness 0.15)
				)
				(justify mirror)
			)
		)
		(property "License" "Apache-2.0"
			(at 305.1 -54.9 0)
			(layer "B.Fab")
			(hide yes)
			(effects
				(font
					(size 1 1)
					(thickness 0.15)
				)
				(justify mirror)
			)
		)
		(property "MPN" "C1005X6S1A105K050BC"
			(at 305.1 -54.9 0)
			(layer "B.Fab")
			(hide yes)
			(effects
				(font
					(size 1 1)
					(thickness 0.15)
				)
				(justify mirror)
			)
		)
		(property "Manufacturer" "TDK"
			(at 305.1 -54.9 0)
			(layer "B.Fab")
			(hide yes)
			(effects
				(font
					(size 1 1)
					(thickness 0.15)
				)
				(justify mirror)
			)
		)
		(property "Public" ""
			(at 305.1 -54.9 0)
			(layer "B.Fab")
			(hide yes)
			(effects
				(font
					(size 1 1)
					(thickness 0.15)
				)
				(justify mirror)
			)
		)
		(property "Val" "1u"
			(at 305.1 -54.9 0)
			(layer "B.Fab")
			(hide yes)
			(effects
				(font
					(size 1 1)
					(thickness 0.15)
				)
				(justify mirror)
			)
		)
		(property "Voltage" "16V"
			(at 305.1 -54.9 0)
			(layer "B.Fab")
			(hide yes)
			(effects
				(font
					(size 1 1)
					(thickness 0.15)
				)
				(justify mirror)
			)
		)
		(sheetname "/LPDDR4/")
		(sheetfile "lpddr.kicad_sch")
		(attr smd)
		(fp_rect
			(start -0.925 0.47)
			(end 0.925 -0.47)
			(stroke
				(width 0.05)
				(type default)
			)
			(fill no)
			(layer "B.CrtYd")
		)
		(fp_line
			(start 0.504 -0.248)
			(end -0.494 -0.248)
			(stroke
				(width 0.15)
				(type solid)
			)
			(layer "B.Fab")
		)
		(fp_line
			(start -0.494 -0.248)
			(end -0.494 0.25)
			(stroke
				(width 0.15)
				(type solid)
			)
			(layer "B.Fab")
		)
		(fp_line
			(start 0.504 0.25)
			(end 0.504 -0.248)
			(stroke
				(width 0.15)
				(type solid)
			)
			(layer "B.Fab")
		)
		(fp_line
			(start -0.494 0.25)
			(end 0.504 0.25)
			(stroke
				(width 0.15)
				(type solid)
			)
			(layer "B.Fab")
		)
		(fp_text user "License: Apache-2.0"
			(at -0.939 -5.799 270)
			(layer "B.Fab")
			(effects
				(font
					(size 0.7 0.7)
					(thickness 0.15)
				)
				(justify left bottom mirror)
			)
		)
		(fp_text user "Author: Antmicro"
			(at -0.939 -3.399 270)
			(layer "B.Fab")
			(effects
				(font
					(size 0.7 0.7)
					(thickness 0.15)
				)
				(justify left bottom mirror)
			)
		)
		(fp_text user "${REFERENCE}"
			(at -0.939 -4.599 270)
			(layer "B.Fab")
			(effects
				(font
					(size 0.7 0.7)
					(thickness 0.15)
				)
				(justify left bottom mirror)
			)
		)
		(pad "1" smd roundrect
			(at -0.48 0 90)
			(size 0.59 0.64)
			(layers "B.Cu" "B.Mask" "B.Paste")
			(roundrect_rratio 0.25)
			(net 417 "GND")
			(pintype "passive")
		)
		(pad "2" smd roundrect
			(at 0.48 0 90)
			(size 0.59 0.64)
			(layers "B.Cu" "B.Mask" "B.Paste")
			(roundrect_rratio 0.25)
			(net 2 "+1V1")
			(pintype "passive")
		)
	)
	(footprint "antmicro-footprints:C_0402_1005Metric"
		(layer "B.Cu")
		(at 195.72 145.3)
		(descr "Capacitor SMD 0402")
		(tags "capacitor SMD 0402")
		(property "Reference" "C226"
			(at -1.645 -0.425 0)
			(layer "B.SilkS")
			(effects
				(font
					(size 0.7 0.7)
					(thickness 0.15)
				)
				(justify right bottom mirror)
			)
		)
		(property "Value" "C_4u7_0402"
			(at -1.022927 -2.155213 0)
			(layer "B.Fab")
			(hide yes)
			(effects
				(font
					(size 0.7 0.7)
					(thickness 0.15)
				)
				(justify right bottom mirror)
			)
		)
		(property "Datasheet" "https://www.murata.com/products/productdetail?partno=GRM155R61A475MEAA%23"
			(at 0 0 0)
			(layer "F.Fab")
			(hide yes)
			(effects
				(font
					(size 1.27 1.27)
					(thickness 0.15)
				)
			)
		)
		(property "Description" "SMD Multilayer Ceramic Capacitor, 4.7 µF, 10 V, 0402 [1005 Metric], ± 20%, X5R, GRM Series"
			(at 0 0 0)
			(layer "F.Fab")
			(hide yes)
			(effects
				(font
					(size 1.27 1.27)
					(thickness 0.15)
				)
			)
		)
		(property "Author" "Antmicro"
			(at 0 0 0)
			(layer "B.Fab")
			(hide yes)
			(effects
				(font
					(size 1 1)
					(thickness 0.15)
				)
				(justify mirror)
			)
		)
		(property "Dielectric" ""
			(at 0 0 0)
			(layer "B.Fab")
			(hide yes)
			(effects
				(font
					(size 1 1)
					(thickness 0.15)
				)
				(justify mirror)
			)
		)
		(property "License" "Apache-2.0"
			(at 0 0 0)
			(layer "B.Fab")
			(hide yes)
			(effects
				(font
					(size 1 1)
					(thickness 0.15)
				)
				(justify mirror)
			)
		)
		(property "MPN" "GRM155R61A475MEAAD"
			(at 0 0 0)
			(layer "B.Fab")
			(hide yes)
			(effects
				(font
					(size 1 1)
					(thickness 0.15)
				)
				(justify mirror)
			)
		)
		(property "Manufacturer" "Murata"
			(at 0 0 0)
			(layer "B.Fab")
			(hide yes)
			(effects
				(font
					(size 1 1)
					(thickness 0.15)
				)
				(justify mirror)
			)
		)
		(property "Public" ""
			(at 0 0 0)
			(layer "B.Fab")
			(hide yes)
			(effects
				(font
					(size 1 1)
					(thickness 0.15)
				)
				(justify mirror)
			)
		)
		(property "Val" "4u7"
			(at 0 0 0)
			(layer "B.Fab")
			(hide yes)
			(effects
				(font
					(size 1 1)
					(thickness 0.15)
				)
				(justify mirror)
			)
		)
		(property "Voltage" ""
			(at 0 0 0)
			(layer "B.Fab")
			(hide yes)
			(effects
				(font
					(size 1 1)
					(thickness 0.15)
				)
				(justify mirror)
			)
		)
		(sheetname "/HDMI/")
		(sheetfile "hdmi.kicad_sch")
		(attr smd)
		(fp_rect
			(start -0.925 0.47)
			(end 0.925 -0.47)
			(stroke
				(width 0.05)
				(type default)
			)
			(fill no)
			(layer "B.CrtYd")
		)
		(fp_line
			(start -0.494 -0.248)
			(end -0.494 0.25)
			(stroke
				(width 0.15)
				(type solid)
			)
			(layer "B.Fab")
		)
		(fp_line
			(start -0.494 0.25)
			(end 0.504 0.25)
			(stroke
				(width 0.15)
				(type solid)
			)
			(layer "B.Fab")
		)
		(fp_line
			(start 0.504 -0.248)
			(end -0.494 -0.248)
			(stroke
				(width 0.15)
				(type solid)
			)
			(layer "B.Fab")
		)
		(fp_line
			(start 0.504 0.25)
			(end 0.504 -0.248)
			(stroke
				(width 0.15)
				(type solid)
			)
			(layer "B.Fab")
		)
		(fp_text user "Author: Antmicro"
			(at -0.939 -3.399 180)
			(layer "B.Fab")
			(effects
				(font
					(size 0.7 0.7)
					(thickness 0.15)
				)
				(justify left bottom mirror)
			)
		)
		(fp_text user "License: Apache-2.0"
			(at -0.939 -5.799 180)
			(layer "B.Fab")
			(effects
				(font
					(size 0.7 0.7)
					(thickness 0.15)
				)
				(justify left bottom mirror)
			)
		)
		(fp_text user "${REFERENCE}"
			(at -0.939 -4.599 180)
			(layer "B.Fab")
			(effects
				(font
					(size 0.7 0.7)
					(thickness 0.15)
				)
				(justify left bottom mirror)
			)
		)
		(pad "1" smd roundrect
			(at -0.48 0)
			(size 0.59 0.64)
			(layers "B.Cu" "B.Mask" "B.Paste")
			(roundrect_rratio 0.25)
			(net 417 "GND")
			(pintype "passive")
		)
		(pad "2" smd roundrect
			(at 0.48 0)
			(size 0.59 0.64)
			(layers "B.Cu" "B.Mask" "B.Paste")
			(roundrect_rratio 0.25)
			(net 554 "Net-(U15-CEXT)")
			(pintype "passive")
		)
	)
	(footprint "antmicro-footprints:C_0402_1005Metric"
		(layer "B.Cu")
		(at 179.1 144.0125)
		(descr "Capacitor SMD 0402")
		(tags "capacitor SMD 0402")
		(property "Reference" "C104"
			(at 1.53 1.7775 315)
			(layer "B.SilkS")
			(effects
				(font
					(size 0.7 0.7)
					(thickness 0.15)
				)
				(justify right bottom mirror)
			)
		)
		(property "Value" "C_10u_10V_0402"
			(at -1.022927 -2.155213 0)
			(layer "B.Fab")
			(hide yes)
			(effects
				(font
					(size 0.7 0.7)
					(thickness 0.15)
				)
				(justify right bottom mirror)
			)
		)
		(property "Datasheet" "https://www.murata.com/products/productdetail?partno=GRM155R61A106ME11%23"
			(at 0 0 0)
			(layer "F.Fab")
			(hide yes)
			(effects
				(font
					(size 1.27 1.27)
					(thickness 0.15)
				)
			)
		)
		(property "Description" "Multilayer Ceramic Capacitors MLCC - SMD/SMT 10 uF 10 VDC 20% 0402 X5R"
			(at 0 0 0)
			(layer "F.Fab")
			(hide yes)
			(effects
				(font
					(size 1.27 1.27)
					(thickness 0.15)
				)
			)
		)
		(property "Author" "Antmicro"
			(at 0 0 0)
			(layer "B.Fab")
			(hide yes)
			(effects
				(font
					(size 1 1)
					(thickness 0.15)
				)
				(justify mirror)
			)
		)
		(property "Dielectric" "X5R"
			(at 0 0 0)
			(layer "B.Fab")
			(hide yes)
			(effects
				(font
					(size 1 1)
					(thickness 0.15)
				)
				(justify mirror)
			)
		)
		(property "License" "Apache-2.0"
			(at 0 0 0)
			(layer "B.Fab")
			(hide yes)
			(effects
				(font
					(size 1 1)
					(thickness 0.15)
				)
				(justify mirror)
			)
		)
		(property "MPN" "GRM155R61A106ME11D"
			(at 0 0 0)
			(layer "B.Fab")
			(hide yes)
			(effects
				(font
					(size 1 1)
					(thickness 0.15)
				)
				(justify mirror)
			)
		)
		(property "Manufacturer" "Murata"
			(at 0 0 0)
			(layer "B.Fab")
			(hide yes)
			(effects
				(font
					(size 1 1)
					(thickness 0.15)
				)
				(justify mirror)
			)
		)
		(property "Public" ""
			(at 0 0 0)
			(layer "B.Fab")
			(hide yes)
			(effects
				(font
					(size 1 1)
					(thickness 0.15)
				)
				(justify mirror)
			)
		)
		(property "Val" "10u"
			(at 0 0 0)
			(layer "B.Fab")
			(hide yes)
			(effects
				(font
					(size 1 1)
					(thickness 0.15)
				)
				(justify mirror)
			)
		)
		(property "Voltage" "10V"
			(at 0 0 0)
			(layer "B.Fab")
			(hide yes)
			(effects
				(font
					(size 1 1)
					(thickness 0.15)
				)
				(justify mirror)
			)
		)
		(sheetname "/Supply/")
		(sheetfile "supply.kicad_sch")
		(attr smd)
		(fp_rect
			(start -0.925 0.47)
			(end 0.925 -0.47)
			(stroke
				(width 0.05)
				(type default)
			)
			(fill no)
			(layer "B.CrtYd")
		)
		(fp_line
			(start -0.494 -0.248)
			(end -0.494 0.25)
			(stroke
				(width 0.15)
				(type solid)
			)
			(layer "B.Fab")
		)
		(fp_line
			(start -0.494 0.25)
			(end 0.504 0.25)
			(stroke
				(width 0.15)
				(type solid)
			)
			(layer "B.Fab")
		)
		(fp_line
			(start 0.504 -0.248)
			(end -0.494 -0.248)
			(stroke
				(width 0.15)
				(type solid)
			)
			(layer "B.Fab")
		)
		(fp_line
			(start 0.504 0.25)
			(end 0.504 -0.248)
			(stroke
				(width 0.15)
				(type solid)
			)
			(layer "B.Fab")
		)
		(fp_text user "${REFERENCE}"
			(at -0.939 -4.599 180)
			(layer "B.Fab")
			(effects
				(font
					(size 0.7 0.7)
					(thickness 0.15)
				)
				(justify left bottom mirror)
			)
		)
		(fp_text user "License: Apache-2.0"
			(at -0.939 -5.799 180)
			(layer "B.Fab")
			(effects
				(font
					(size 0.7 0.7)
					(thickness 0.15)
				)
				(justify left bottom mirror)
			)
		)
		(fp_text user "Author: Antmicro"
			(at -0.939 -3.399 180)
			(layer "B.Fab")
			(effects
				(font
					(size 0.7 0.7)
					(thickness 0.15)
				)
				(justify left bottom mirror)
			)
		)
		(pad "1" smd roundrect
			(at -0.48 0)
			(size 0.59 0.64)
			(layers "B.Cu" "B.Mask" "B.Paste")
			(roundrect_rratio 0.25)
			(net 417 "GND")
			(pintype "passive")
		)
		(pad "2" smd roundrect
			(at 0.48 0)
			(size 0.59 0.64)
			(layers "B.Cu" "B.Mask" "B.Paste")
			(roundrect_rratio 0.25)
			(net 633 "Net-(U7-OUT4)")
			(pintype "passive")
		)
	)
	(footprint "antmicro-footprints:C_0402_1005Metric"
		(layer "B.Cu")
		(at 191.71 137.46 -90)
		(descr "Capacitor SMD 0402")
		(tags "capacitor SMD 0402")
		(property "Reference" "C56"
			(at -1.316 0.702 90)
			(layer "B.SilkS")
			(effects
				(font
					(size 0.7 0.7)
					(thickness 0.15)
				)
				(justify left bottom mirror)
			)
		)
		(property "Value" "C_4n7_0402"
			(at -1.022927 -2.155213 90)
			(layer "B.Fab")
			(hide yes)
			(effects
				(font
					(size 0.7 0.7)
					(thickness 0.15)
				)
				(justify left bottom mirror)
			)
		)
		(property "Datasheet" "https://product.tdk.com/en/search/capacitor/ceramic/mlcc/info?part_no=CGA2B3X7S2A472K050BB"
			(at 0 0 270)
			(layer "F.Fab")
			(hide yes)
			(effects
				(font
					(size 1.27 1.27)
					(thickness 0.15)
				)
			)
		)
		(property "Description" "SMD Multilayer Ceramic Capacitor, 4700 pF, 100 V, 0402 [1005 Metric], ± 10%, X7S, CGA"
			(at 0 0 270)
			(layer "F.Fab")
			(hide yes)
			(effects
				(font
					(size 1.27 1.27)
					(thickness 0.15)
				)
			)
		)
		(property "Author" "Antmicro"
			(at 54.25 329.17 0)
			(layer "B.Fab")
			(hide yes)
			(effects
				(font
					(size 1 1)
					(thickness 0.15)
				)
				(justify mirror)
			)
		)
		(property "Dielectric" "X7R"
			(at 54.25 329.17 0)
			(layer "B.Fab")
			(hide yes)
			(effects
				(font
					(size 1 1)
					(thickness 0.15)
				)
				(justify mirror)
			)
		)
		(property "License" "Apache-2.0"
			(at 54.25 329.17 0)
			(layer "B.Fab")
			(hide yes)
			(effects
				(font
					(size 1 1)
					(thickness 0.15)
				)
				(justify mirror)
			)
		)
		(property "MPN" "CGA2B3X7S2A472K050BB"
			(at 54.25 329.17 0)
			(layer "B.Fab")
			(hide yes)
			(effects
				(font
					(size 1 1)
					(thickness 0.15)
				)
				(justify mirror)
			)
		)
		(property "Manufacturer" "TDK"
			(at 54.25 329.17 0)
			(layer "B.Fab")
			(hide yes)
			(effects
				(font
					(size 1 1)
					(thickness 0.15)
				)
				(justify mirror)
			)
		)
		(property "Public" ""
			(at 54.25 329.17 0)
			(layer "B.Fab")
			(hide yes)
			(effects
				(font
					(size 1 1)
					(thickness 0.15)
				)
				(justify mirror)
			)
		)
		(property "Val" "4n7"
			(at 54.25 329.17 0)
			(layer "B.Fab")
			(hide yes)
			(effects
				(font
					(size 1 1)
					(thickness 0.15)
				)
				(justify mirror)
			)
		)
		(property "Voltage" "25V"
			(at 54.25 329.17 0)
			(layer "B.Fab")
			(hide yes)
			(effects
				(font
					(size 1 1)
					(thickness 0.15)
				)
				(justify mirror)
			)
		)
		(sheetname "/FPGA Supply/")
		(sheetfile "fpga-supply.kicad_sch")
		(attr smd)
		(fp_rect
			(start -0.925 0.47)
			(end 0.925 -0.47)
			(stroke
				(width 0.05)
				(type default)
			)
			(fill no)
			(layer "B.CrtYd")
		)
		(fp_line
			(start -0.494 0.25)
			(end 0.504 0.25)
			(stroke
				(width 0.15)
				(type solid)
			)
			(layer "B.Fab")
		)
		(fp_line
			(start 0.504 0.25)
			(end 0.504 -0.248)
			(stroke
				(width 0.15)
				(type solid)
			)
			(layer "B.Fab")
		)
		(fp_line
			(start -0.494 -0.248)
			(end -0.494 0.25)
			(stroke
				(width 0.15)
				(type solid)
			)
			(layer "B.Fab")
		)
		(fp_line
			(start 0.504 -0.248)
			(end -0.494 -0.248)
			(stroke
				(width 0.15)
				(type solid)
			)
			(layer "B.Fab")
		)
		(fp_text user "Author: Antmicro"
			(at -0.939 -3.399 90)
			(layer "B.Fab")
			(effects
				(font
					(size 0.7 0.7)
					(thickness 0.15)
				)
				(justify left bottom mirror)
			)
		)
		(fp_text user "${REFERENCE}"
			(at -0.939 -4.599 90)
			(layer "B.Fab")
			(effects
				(font
					(size 0.7 0.7)
					(thickness 0.15)
				)
				(justify left bottom mirror)
			)
		)
		(fp_text user "License: Apache-2.0"
			(at -0.939 -5.799 90)
			(layer "B.Fab")
			(effects
				(font
					(size 0.7 0.7)
					(thickness 0.15)
				)
				(justify left bottom mirror)
			)
		)
		(pad "1" smd roundrect
			(at -0.48 0 270)
			(size 0.59 0.64)
			(layers "B.Cu" "B.Mask" "B.Paste")
			(roundrect_rratio 0.25)
			(net 417 "GND")
			(pintype "passive")
		)
		(pad "2" smd roundrect
			(at 0.48 0 270)
			(size 0.59 0.64)
			(layers "B.Cu" "B.Mask" "B.Paste")
			(roundrect_rratio 0.25)
			(net 48 "+1V8")
			(pintype "passive")
		)
	)
	(footprint "antmicro-footprints:C_0402_1005Metric"
		(layer "B.Cu")
		(at 220.9575 147.295 90)
		(descr "Capacitor SMD 0402")
		(tags "capacitor SMD 0402")
		(property "Reference" "C227"
			(at -3.735 0.9525 90)
			(layer "B.SilkS")
			(effects
				(font
					(size 0.7 0.7)
					(thickness 0.15)
				)
				(justify right bottom mirror)
			)
		)
		(property "Value" "C_100n_0402"
			(at -1.022927 -2.155213 90)
			(layer "B.Fab")
			(hide yes)
			(effects
				(font
					(size 0.7 0.7)
					(thickness 0.15)
				)
				(justify right bottom mirror)
			)
		)
		(property "Datasheet" "https://www.murata.com/products/productdetail?partno=GRM155R61H104KE14%23"
			(at 0 0 90)
			(layer "F.Fab")
			(hide yes)
			(effects
				(font
					(size 1.27 1.27)
					(thickness 0.15)
				)
			)
		)
		(property "Description" "SMD Multilayer Ceramic Capacitor, 0.1 µF, 50 V, 0402 [1005 Metric], ± 10%, X5R, GRM Series"
			(at 0 0 90)
			(layer "F.Fab")
			(hide yes)
			(effects
				(font
					(size 1.27 1.27)
					(thickness 0.15)
				)
			)
		)
		(property "Author" "Antmicro"
			(at 368.2525 -73.6625 0)
			(layer "B.Fab")
			(hide yes)
			(effects
				(font
					(size 1 1)
					(thickness 0.15)
				)
				(justify mirror)
			)
		)
		(property "Dielectric" "X5R"
			(at 368.2525 -73.6625 0)
			(layer "B.Fab")
			(hide yes)
			(effects
				(font
					(size 1 1)
					(thickness 0.15)
				)
				(justify mirror)
			)
		)
		(property "License" "Apache-2.0"
			(at 368.2525 -73.6625 0)
			(layer "B.Fab")
			(hide yes)
			(effects
				(font
					(size 1 1)
					(thickness 0.15)
				)
				(justify mirror)
			)
		)
		(property "MPN" "GRM155R61H104KE14D"
			(at 368.2525 -73.6625 0)
			(layer "B.Fab")
			(hide yes)
			(effects
				(font
					(size 1 1)
					(thickness 0.15)
				)
				(justify mirror)
			)
		)
		(property "Manufacturer" "Murata"
			(at 368.2525 -73.6625 0)
			(layer "B.Fab")
			(hide yes)
			(effects
				(font
					(size 1 1)
					(thickness 0.15)
				)
				(justify mirror)
			)
		)
		(property "Public" ""
			(at 368.2525 -73.6625 0)
			(layer "B.Fab")
			(hide yes)
			(effects
				(font
					(size 1 1)
					(thickness 0.15)
				)
				(justify mirror)
			)
		)
		(property "Val" "100n"
			(at 368.2525 -73.6625 0)
			(layer "B.Fab")
			(hide yes)
			(effects
				(font
					(size 1 1)
					(thickness 0.15)
				)
				(justify mirror)
			)
		)
		(property "Voltage" "50V"
			(at 368.2525 -73.6625 0)
			(layer "B.Fab")
			(hide yes)
			(effects
				(font
					(size 1 1)
					(thickness 0.15)
				)
				(justify mirror)
			)
		)
		(sheetname "/WiFi_Bluetooth/")
		(sheetfile "wifi_bt.kicad_sch")
		(attr smd)
		(fp_rect
			(start -0.925 0.47)
			(end 0.925 -0.47)
			(stroke
				(width 0.05)
				(type default)
			)
			(fill no)
			(layer "B.CrtYd")
		)
		(fp_line
			(start 0.504 -0.248)
			(end -0.494 -0.248)
			(stroke
				(width 0.15)
				(type solid)
			)
			(layer "B.Fab")
		)
		(fp_line
			(start -0.494 -0.248)
			(end -0.494 0.25)
			(stroke
				(width 0.15)
				(type solid)
			)
			(layer "B.Fab")
		)
		(fp_line
			(start 0.504 0.25)
			(end 0.504 -0.248)
			(stroke
				(width 0.15)
				(type solid)
			)
			(layer "B.Fab")
		)
		(fp_line
			(start -0.494 0.25)
			(end 0.504 0.25)
			(stroke
				(width 0.15)
				(type solid)
			)
			(layer "B.Fab")
		)
		(fp_text user "License: Apache-2.0"
			(at -0.939 -5.799 270)
			(layer "B.Fab")
			(effects
				(font
					(size 0.7 0.7)
					(thickness 0.15)
				)
				(justify left bottom mirror)
			)
		)
		(fp_text user "${REFERENCE}"
			(at -0.939 -4.599 270)
			(layer "B.Fab")
			(effects
				(font
					(size 0.7 0.7)
					(thickness 0.15)
				)
				(justify left bottom mirror)
			)
		)
		(fp_text user "Author: Antmicro"
			(at -0.939 -3.399 270)
			(layer "B.Fab")
			(effects
				(font
					(size 0.7 0.7)
					(thickness 0.15)
				)
				(justify left bottom mirror)
			)
		)
		(pad "1" smd roundrect
			(at -0.48 0 90)
			(size 0.59 0.64)
			(layers "B.Cu" "B.Mask" "B.Paste")
			(roundrect_rratio 0.25)
			(net 417 "GND")
			(pintype "passive")
		)
		(pad "2" smd roundrect
			(at 0.48 0 90)
			(size 0.59 0.64)
			(layers "B.Cu" "B.Mask" "B.Paste")
			(roundrect_rratio 0.25)
			(net 172 "BT_REG_ON")
			(pintype "passive")
		)
	)
	(footprint "antmicro-footprints:C_0402_1005Metric"
		(layer "B.Cu")
		(at 198.1 140.564 90)
		(descr "Capacitor SMD 0402")
		(tags "capacitor SMD 0402")
		(property "Reference" "C24"
			(at 1.114 -1.99 270)
			(layer "B.SilkS")
			(effects
				(font
					(size 0.7 0.7)
					(thickness 0.15)
				)
				(justify left bottom mirror)
			)
		)
		(property "Value" "C_4n7_0402"
			(at -1.022927 -2.155213 270)
			(layer "B.Fab")
			(hide yes)
			(effects
				(font
					(size 0.7 0.7)
					(thickness 0.15)
				)
				(justify left bottom mirror)
			)
		)
		(property "Datasheet" "https://product.tdk.com/en/search/capacitor/ceramic/mlcc/info?part_no=CGA2B3X7S2A472K050BB"
			(at 0 0 90)
			(layer "F.Fab")
			(hide yes)
			(effects
				(font
					(size 1.27 1.27)
					(thickness 0.15)
				)
			)
		)
		(property "Description" "SMD Multilayer Ceramic Capacitor, 4700 pF, 100 V, 0402 [1005 Metric], ± 10%, X7S, CGA"
			(at 0 0 90)
			(layer "F.Fab")
			(hide yes)
			(effects
				(font
					(size 1.27 1.27)
					(thickness 0.15)
				)
			)
		)
		(property "Author" "Antmicro"
			(at 338.664 -57.536 0)
			(layer "B.Fab")
			(hide yes)
			(effects
				(font
					(size 1 1)
					(thickness 0.15)
				)
				(justify mirror)
			)
		)
		(property "Dielectric" "X7R"
			(at 338.664 -57.536 0)
			(layer "B.Fab")
			(hide yes)
			(effects
				(font
					(size 1 1)
					(thickness 0.15)
				)
				(justify mirror)
			)
		)
		(property "License" "Apache-2.0"
			(at 338.664 -57.536 0)
			(layer "B.Fab")
			(hide yes)
			(effects
				(font
					(size 1 1)
					(thickness 0.15)
				)
				(justify mirror)
			)
		)
		(property "MPN" "CGA2B3X7S2A472K050BB"
			(at 338.664 -57.536 0)
			(layer "B.Fab")
			(hide yes)
			(effects
				(font
					(size 1 1)
					(thickness 0.15)
				)
				(justify mirror)
			)
		)
		(property "Manufacturer" "TDK"
			(at 338.664 -57.536 0)
			(layer "B.Fab")
			(hide yes)
			(effects
				(font
					(size 1 1)
					(thickness 0.15)
				)
				(justify mirror)
			)
		)
		(property "Public" ""
			(at 338.664 -57.536 0)
			(layer "B.Fab")
			(hide yes)
			(effects
				(font
					(size 1 1)
					(thickness 0.15)
				)
				(justify mirror)
			)
		)
		(property "Val" "4n7"
			(at 338.664 -57.536 0)
			(layer "B.Fab")
			(hide yes)
			(effects
				(font
					(size 1 1)
					(thickness 0.15)
				)
				(justify mirror)
			)
		)
		(property "Voltage" "25V"
			(at 338.664 -57.536 0)
			(layer "B.Fab")
			(hide yes)
			(effects
				(font
					(size 1 1)
					(thickness 0.15)
				)
				(justify mirror)
			)
		)
		(sheetname "/FPGA Supply/")
		(sheetfile "fpga-supply.kicad_sch")
		(attr smd)
		(fp_rect
			(start -0.925 0.47)
			(end 0.925 -0.47)
			(stroke
				(width 0.05)
				(type default)
			)
			(fill no)
			(layer "B.CrtYd")
		)
		(fp_line
			(start 0.504 -0.248)
			(end -0.494 -0.248)
			(stroke
				(width 0.15)
				(type solid)
			)
			(layer "B.Fab")
		)
		(fp_line
			(start -0.494 -0.248)
			(end -0.494 0.25)
			(stroke
				(width 0.15)
				(type solid)
			)
			(layer "B.Fab")
		)
		(fp_line
			(start 0.504 0.25)
			(end 0.504 -0.248)
			(stroke
				(width 0.15)
				(type solid)
			)
			(layer "B.Fab")
		)
		(fp_line
			(start -0.494 0.25)
			(end 0.504 0.25)
			(stroke
				(width 0.15)
				(type solid)
			)
			(layer "B.Fab")
		)
		(fp_text user "License: Apache-2.0"
			(at -0.939 -5.799 270)
			(layer "B.Fab")
			(effects
				(font
					(size 0.7 0.7)
					(thickness 0.15)
				)
				(justify left bottom mirror)
			)
		)
		(fp_text user "Author: Antmicro"
			(at -0.939 -3.399 270)
			(layer "B.Fab")
			(effects
				(font
					(size 0.7 0.7)
					(thickness 0.15)
				)
				(justify left bottom mirror)
			)
		)
		(fp_text user "${REFERENCE}"
			(at -0.939 -4.599 270)
			(layer "B.Fab")
			(effects
				(font
					(size 0.7 0.7)
					(thickness 0.15)
				)
				(justify left bottom mirror)
			)
		)
		(pad "1" smd roundrect
			(at -0.48 0 90)
			(size 0.59 0.64)
			(layers "B.Cu" "B.Mask" "B.Paste")
			(roundrect_rratio 0.25)
			(net 417 "GND")
			(pintype "passive")
		)
		(pad "2" smd roundrect
			(at 0.48 0 90)
			(size 0.59 0.64)
			(layers "B.Cu" "B.Mask" "B.Paste")
			(roundrect_rratio 0.25)
			(net 47 "+1V05")
			(pintype "passive")
		)
	)
	(footprint "antmicro-footprints:XSON-8_1x1.95mm_P0.5mm"
		(layer "B.Cu")
		(at 192.3 142.4)
		(property "Reference" "U14"
			(at 1.85 1.25 90)
			(layer "B.SilkS")
			(effects
				(font
					(size 0.7 0.7)
					(thickness 0.15)
				)
				(justify right bottom mirror)
			)
		)
		(property "Value" "NTS0102_XSON"
			(at 0 -2.2 0)
			(layer "B.Fab")
			(hide yes)
			(effects
				(font
					(size 0.7 0.7)
					(thickness 0.15)
				)
				(justify right bottom mirror)
			)
		)
		(property "Datasheet" "http://www.farnell.com/datasheets/1760723.pdf"
			(at 0 0 0)
			(layer "F.Fab")
			(hide yes)
			(effects
				(font
					(size 1.27 1.27)
					(thickness 0.15)
				)
			)
		)
		(property "Description" "Transceiver, 1.65 V to 3.6 V, XSON-8"
			(at 0 0 0)
			(layer "F.Fab")
			(hide yes)
			(effects
				(font
					(size 1.27 1.27)
					(thickness 0.15)
				)
			)
		)
		(property "Author" "Antmicro"
			(at 0 0 0)
			(layer "B.Fab")
			(hide yes)
			(effects
				(font
					(size 1 1)
					(thickness 0.15)
				)
				(justify mirror)
			)
		)
		(property "License" "Apache-2.0"
			(at 0 0 0)
			(layer "B.Fab")
			(hide yes)
			(effects
				(font
					(size 1 1)
					(thickness 0.15)
				)
				(justify mirror)
			)
		)
		(property "MPN" "NTS0102GT"
			(at 0 0 0)
			(layer "B.Fab")
			(hide yes)
			(effects
				(font
					(size 1 1)
					(thickness 0.15)
				)
				(justify mirror)
			)
		)
		(property "Manufacturer" "NXP"
			(at 0 0 0)
			(layer "B.Fab")
			(hide yes)
			(effects
				(font
					(size 1 1)
					(thickness 0.15)
				)
				(justify mirror)
			)
		)
		(sheetname "/FPGA GPIO/")
		(sheetfile "fpga-gpio.kicad_sch")
		(attr smd)
		(fp_line
			(start -0.5 1.1)
			(end 0.5 1.1)
			(stroke
				(width 0.15)
				(type solid)
			)
			(layer "B.SilkS")
		)
		(fp_line
			(start 0.5 -1.1)
			(end -0.5 -1.1)
			(stroke
				(width 0.15)
				(type solid)
			)
			(layer "B.SilkS")
		)
		(fp_circle
			(center -0.75 1.1)
			(end -0.701 1.1)
			(stroke
				(width 0.15)
				(type solid)
			)
			(fill no)
			(layer "B.SilkS")
		)
		(fp_rect
			(start -0.8 1.2)
			(end 0.8 -1.2)
			(stroke
				(width 0.05)
				(type solid)
			)
			(fill no)
			(layer "B.CrtYd")
		)
		(fp_line
			(start -0.5305 -1)
			(end -0.5305 1.001)
			(stroke
				(width 0.15)
				(type solid)
			)
			(layer "B.Fab")
		)
		(fp_line
			(start -0.5305 1.001)
			(end 0.5305 1.001)
			(stroke
				(width 0.15)
				(type solid)
			)
			(layer "B.Fab")
		)
		(fp_line
			(start 0.5305 -1)
			(end -0.5305 -1)
			(stroke
				(width 0.15)
				(type solid)
			)
			(layer "B.Fab")
		)
		(fp_line
			(start 0.5305 1.001)
			(end 0.5305 -1)
			(stroke
				(width 0.15)
				(type solid)
			)
			(layer "B.Fab")
		)
		(fp_text user "Author: Antmicro"
			(at -0.527 -7.105 180)
			(layer "B.Fab")
			(effects
				(font
					(size 0.7 0.7)
					(thickness 0.15)
				)
				(justify left bottom mirror)
			)
		)
		(fp_text user "${REFERENCE}"
			(at -0.527 -5.905 180)
			(layer "B.Fab")
			(effects
				(font
					(size 0.7 0.7)
					(thickness 0.15)
				)
				(justify left bottom mirror)
			)
		)
		(fp_text user "License: Apache-2.0"
			(at -0.527 -8.306 180)
			(layer "B.Fab")
			(effects
				(font
					(size 0.7 0.7)
					(thickness 0.15)
				)
				(justify left bottom mirror)
			)
		)
		(pad "1" smd roundrect
			(at -0.45 0.75 180)
			(size 0.6 0.3)
			(layers "B.Cu" "B.Mask" "B.Paste")
			(roundrect_rratio 0.25)
			(net 283 "/FPGA GPIO/PI3HDX511F.SCL")
			(pinfunction "B_{2}")
			(pintype "bidirectional")
		)
		(pad "2" smd roundrect
			(at -0.45 0.25 180)
			(size 0.6 0.25)
			(layers "B.Cu" "B.Mask" "B.Paste")
			(roundrect_rratio 0.25)
			(net 417 "GND")
			(pinfunction "GND")
			(pintype "power_in")
		)
		(pad "3" smd roundrect
			(at -0.45 -0.25 180)
			(size 0.6 0.25)
			(layers "B.Cu" "B.Mask" "B.Paste")
			(roundrect_rratio 0.25)
			(net 649 "VDD")
			(pinfunction "VCC_{A}")
			(pintype "power_in")
		)
		(pad "4" smd roundrect
			(at -0.45 -0.75 180)
			(size 0.6 0.3)
			(layers "B.Cu" "B.Mask" "B.Paste")
			(roundrect_rratio 0.25)
			(net 353 "/FPGA GPIO/HDMI0_SCL_SRC")
			(pinfunction "A_{2}")
			(pintype "bidirectional")
		)
		(pad "5" smd roundrect
			(at 0.45 -0.75 180)
			(size 0.6 0.3)
			(layers "B.Cu" "B.Mask" "B.Paste")
			(roundrect_rratio 0.25)
			(net 348 "/FPGA GPIO/HDMI0_SDA_SRC")
			(pinfunction "A_{1}")
			(pintype "bidirectional")
		)
		(pad "6" smd roundrect
			(at 0.45 -0.25 180)
			(size 0.6 0.25)
			(layers "B.Cu" "B.Mask" "B.Paste")
			(roundrect_rratio 0.25)
			(net 649 "VDD")
			(pinfunction "OE")
			(pintype "input")
		)
		(pad "7" smd roundrect
			(at 0.45 0.25 180)
			(size 0.6 0.25)
			(layers "B.Cu" "B.Mask" "B.Paste")
			(roundrect_rratio 0.25)
			(net 50 "+3V3")
			(pinfunction "VCC_{B}")
			(pintype "power_in")
		)
		(pad "8" smd roundrect
			(at 0.45 0.75 180)
			(size 0.6 0.3)
			(layers "B.Cu" "B.Mask" "B.Paste")
			(roundrect_rratio 0.25)
			(net 622 "/FPGA GPIO/PI3HDX511F.SDA")
			(pinfunction "B_{1}")
			(pintype "bidirectional")
		)
	)
	(footprint "antmicro-footprints:C_0402_1005Metric"
		(layer "B.Cu")
		(at 213.861 118.754 180)
		(descr "Capacitor SMD 0402")
		(tags "capacitor SMD 0402")
		(property "Reference" "C190"
			(at 24.711 -18.021 0)
			(layer "B.SilkS")
			(effects
				(font
					(size 0.7 0.7)
					(thickness 0.15)
				)
				(justify left bottom mirror)
			)
		)
		(property "Value" "C_100n_0402"
			(at -1.022927 -2.155213 0)
			(layer "B.Fab")
			(hide yes)
			(effects
				(font
					(size 0.7 0.7)
					(thickness 0.15)
				)
				(justify left bottom mirror)
			)
		)
		(property "Datasheet" "https://www.murata.com/products/productdetail?partno=GRM155R61H104KE14%23"
			(at 0 0 180)
			(layer "F.Fab")
			(hide yes)
			(effects
				(font
					(size 1.27 1.27)
					(thickness 0.15)
				)
			)
		)
		(property "Description" "SMD Multilayer Ceramic Capacitor, 0.1 µF, 50 V, 0402 [1005 Metric], ± 10%, X5R, GRM Series"
			(at 0 0 180)
			(layer "F.Fab")
			(hide yes)
			(effects
				(font
					(size 1.27 1.27)
					(thickness 0.15)
				)
			)
		)
		(property "Author" "Antmicro"
			(at 427.722 237.508 0)
			(layer "B.Fab")
			(hide yes)
			(effects
				(font
					(size 1 1)
					(thickness 0.15)
				)
				(justify mirror)
			)
		)
		(property "Dielectric" "X5R"
			(at 427.722 237.508 0)
			(layer "B.Fab")
			(hide yes)
			(effects
				(font
					(size 1 1)
					(thickness 0.15)
				)
				(justify mirror)
			)
		)
		(property "License" "Apache-2.0"
			(at 427.722 237.508 0)
			(layer "B.Fab")
			(hide yes)
			(effects
				(font
					(size 1 1)
					(thickness 0.15)
				)
				(justify mirror)
			)
		)
		(property "MPN" "GRM155R61H104KE14D"
			(at 427.722 237.508 0)
			(layer "B.Fab")
			(hide yes)
			(effects
				(font
					(size 1 1)
					(thickness 0.15)
				)
				(justify mirror)
			)
		)
		(property "Manufacturer" "Murata"
			(at 427.722 237.508 0)
			(layer "B.Fab")
			(hide yes)
			(effects
				(font
					(size 1 1)
					(thickness 0.15)
				)
				(justify mirror)
			)
		)
		(property "Public" ""
			(at 427.722 237.508 0)
			(layer "B.Fab")
			(hide yes)
			(effects
				(font
					(size 1 1)
					(thickness 0.15)
				)
				(justify mirror)
			)
		)
		(property "Val" "100n"
			(at 427.722 237.508 0)
			(layer "B.Fab")
			(hide yes)
			(effects
				(font
					(size 1 1)
					(thickness 0.15)
				)
				(justify mirror)
			)
		)
		(property "Voltage" "50V"
			(at 427.722 237.508 0)
			(layer "B.Fab")
			(hide yes)
			(effects
				(font
					(size 1 1)
					(thickness 0.15)
				)
				(justify mirror)
			)
		)
		(sheetname "/Ethernet/")
		(sheetfile "ethernet.kicad_sch")
		(attr smd)
		(fp_rect
			(start -0.925 0.47)
			(end 0.925 -0.47)
			(stroke
				(width 0.05)
				(type default)
			)
			(fill no)
			(layer "B.CrtYd")
		)
		(fp_line
			(start 0.504 0.25)
			(end 0.504 -0.248)
			(stroke
				(width 0.15)
				(type solid)
			)
			(layer "B.Fab")
		)
		(fp_line
			(start 0.504 -0.248)
			(end -0.494 -0.248)
			(stroke
				(width 0.15)
				(type solid)
			)
			(layer "B.Fab")
		)
		(fp_line
			(start -0.494 0.25)
			(end 0.504 0.25)
			(stroke
				(width 0.15)
				(type solid)
			)
			(layer "B.Fab")
		)
		(fp_line
			(start -0.494 -0.248)
			(end -0.494 0.25)
			(stroke
				(width 0.15)
				(type solid)
			)
			(layer "B.Fab")
		)
		(fp_text user "Author: Antmicro"
			(at -0.939 -3.399 0)
			(layer "B.Fab")
			(effects
				(font
					(size 0.7 0.7)
					(thickness 0.15)
				)
				(justify left bottom mirror)
			)
		)
		(fp_text user "License: Apache-2.0"
			(at -0.939 -5.799 0)
			(layer "B.Fab")
			(effects
				(font
					(size 0.7 0.7)
					(thickness 0.15)
				)
				(justify left bottom mirror)
			)
		)
		(fp_text user "${REFERENCE}"
			(at -0.939 -4.599 0)
			(layer "B.Fab")
			(effects
				(font
					(size 0.7 0.7)
					(thickness 0.15)
				)
				(justify left bottom mirror)
			)
		)
		(pad "1" smd roundrect
			(at -0.48 0 180)
			(size 0.59 0.64)
			(layers "B.Cu" "B.Mask" "B.Paste")
			(roundrect_rratio 0.25)
			(net 417 "GND")
			(pintype "passive")
		)
		(pad "2" smd roundrect
			(at 0.48 0 180)
			(size 0.59 0.64)
			(layers "B.Cu" "B.Mask" "B.Paste")
			(roundrect_rratio 0.25)
			(net 50 "+3V3")
			(pintype "passive")
		)
	)
	(footprint "antmicro-footprints:C_0402_1005Metric"
		(layer "B.Cu")
		(at 211.965 144.65 90)
		(descr "Capacitor SMD 0402")
		(tags "capacitor SMD 0402")
		(property "Reference" "C183"
			(at 4.925 -0.415 270)
			(layer "B.SilkS")
			(effects
				(font
					(size 0.7 0.7)
					(thickness 0.15)
				)
				(justify left bottom mirror)
			)
		)
		(property "Value" "C_100n_0402"
			(at -1.022927 -2.155213 270)
			(layer "B.Fab")
			(hide yes)
			(effects
				(font
					(size 0.7 0.7)
					(thickness 0.15)
				)
				(justify left bottom mirror)
			)
		)
		(property "Datasheet" "https://www.murata.com/products/productdetail?partno=GRM155R61H104KE14%23"
			(at 0 0 90)
			(layer "F.Fab")
			(hide yes)
			(effects
				(font
					(size 1.27 1.27)
					(thickness 0.15)
				)
			)
		)
		(property "Description" "SMD Multilayer Ceramic Capacitor, 0.1 µF, 50 V, 0402 [1005 Metric], ± 10%, X5R, GRM Series"
			(at 0 0 90)
			(layer "F.Fab")
			(hide yes)
			(effects
				(font
					(size 1.27 1.27)
					(thickness 0.15)
				)
			)
		)
		(property "Author" "Antmicro"
			(at 356.615 -67.315 0)
			(layer "B.Fab")
			(hide yes)
			(effects
				(font
					(size 1 1)
					(thickness 0.15)
				)
				(justify mirror)
			)
		)
		(property "Dielectric" "X5R"
			(at 356.615 -67.315 0)
			(layer "B.Fab")
			(hide yes)
			(effects
				(font
					(size 1 1)
					(thickness 0.15)
				)
				(justify mirror)
			)
		)
		(property "License" "Apache-2.0"
			(at 356.615 -67.315 0)
			(layer "B.Fab")
			(hide yes)
			(effects
				(font
					(size 1 1)
					(thickness 0.15)
				)
				(justify mirror)
			)
		)
		(property "MPN" "GRM155R61H104KE14D"
			(at 356.615 -67.315 0)
			(layer "B.Fab")
			(hide yes)
			(effects
				(font
					(size 1 1)
					(thickness 0.15)
				)
				(justify mirror)
			)
		)
		(property "Manufacturer" "Murata"
			(at 356.615 -67.315 0)
			(layer "B.Fab")
			(hide yes)
			(effects
				(font
					(size 1 1)
					(thickness 0.15)
				)
				(justify mirror)
			)
		)
		(property "Public" ""
			(at 356.615 -67.315 0)
			(layer "B.Fab")
			(hide yes)
			(effects
				(font
					(size 1 1)
					(thickness 0.15)
				)
				(justify mirror)
			)
		)
		(property "Val" "100n"
			(at 356.615 -67.315 0)
			(layer "B.Fab")
			(hide yes)
			(effects
				(font
					(size 1 1)
					(thickness 0.15)
				)
				(justify mirror)
			)
		)
		(property "Voltage" "50V"
			(at 356.615 -67.315 0)
			(layer "B.Fab")
			(hide yes)
			(effects
				(font
					(size 1 1)
					(thickness 0.15)
				)
				(justify mirror)
			)
		)
		(sheetname "/USB/")
		(sheetfile "usb.kicad_sch")
		(attr smd)
		(fp_rect
			(start -0.925 0.47)
			(end 0.925 -0.47)
			(stroke
				(width 0.05)
				(type default)
			)
			(fill no)
			(layer "B.CrtYd")
		)
		(fp_line
			(start 0.504 -0.248)
			(end -0.494 -0.248)
			(stroke
				(width 0.15)
				(type solid)
			)
			(layer "B.Fab")
		)
		(fp_line
			(start -0.494 -0.248)
			(end -0.494 0.25)
			(stroke
				(width 0.15)
				(type solid)
			)
			(layer "B.Fab")
		)
		(fp_line
			(start 0.504 0.25)
			(end 0.504 -0.248)
			(stroke
				(width 0.15)
				(type solid)
			)
			(layer "B.Fab")
		)
		(fp_line
			(start -0.494 0.25)
			(end 0.504 0.25)
			(stroke
				(width 0.15)
				(type solid)
			)
			(layer "B.Fab")
		)
		(fp_text user "${REFERENCE}"
			(at -0.939 -4.599 270)
			(layer "B.Fab")
			(effects
				(font
					(size 0.7 0.7)
					(thickness 0.15)
				)
				(justify left bottom mirror)
			)
		)
		(fp_text user "Author: Antmicro"
			(at -0.939 -3.399 270)
			(layer "B.Fab")
			(effects
				(font
					(size 0.7 0.7)
					(thickness 0.15)
				)
				(justify left bottom mirror)
			)
		)
		(fp_text user "License: Apache-2.0"
			(at -0.939 -5.799 270)
			(layer "B.Fab")
			(effects
				(font
					(size 0.7 0.7)
					(thickness 0.15)
				)
				(justify left bottom mirror)
			)
		)
		(pad "1" smd roundrect
			(at -0.48 0 90)
			(size 0.59 0.64)
			(layers "B.Cu" "B.Mask" "B.Paste")
			(roundrect_rratio 0.25)
			(net 417 "GND")
			(pintype "passive")
		)
		(pad "2" smd roundrect
			(at 0.48 0 90)
			(size 0.59 0.64)
			(layers "B.Cu" "B.Mask" "B.Paste")
			(roundrect_rratio 0.25)
			(net 50 "+3V3")
			(pintype "passive")
		)
	)
	(footprint "antmicro-footprints:R_0402_1005Metric"
		(layer "B.Cu")
		(at 226.075 147.82 90)
		(descr "Resistor SMD 0402")
		(tags "resistor SMD 0402")
		(property "Reference" "R130"
			(at 0.92 2.405 270)
			(layer "B.SilkS")
			(effects
				(font
					(size 0.7 0.7)
					(thickness 0.15)
				)
				(justify left bottom mirror)
			)
		)
		(property "Value" "R_0R_0402"
			(at -1.011843 -1.772047 270)
			(layer "B.Fab")
			(hide yes)
			(effects
				(font
					(size 0.7 0.7)
					(thickness 0.15)
				)
				(justify left bottom mirror)
			)
		)
		(property "Datasheet" "https://industrial.panasonic.com/cdbs/www-data/pdf/RDA0000/AOA0000C301.pdf"
			(at 0 0 90)
			(layer "F.Fab")
			(hide yes)
			(effects
				(font
					(size 1.27 1.27)
					(thickness 0.15)
				)
			)
		)
		(property "Description" "SMD Chip Resistor, Jumper, 0 ohm, 100 mW, 0402 [1005 Metric], Thick Film, General Purpose"
			(at 0 0 90)
			(layer "F.Fab")
			(hide yes)
			(effects
				(font
					(size 1.27 1.27)
					(thickness 0.15)
				)
			)
		)
		(property "Author" "Antmicro"
			(at 373.895 -78.255 0)
			(layer "B.Fab")
			(hide yes)
			(effects
				(font
					(size 1 1)
					(thickness 0.15)
				)
				(justify mirror)
			)
		)
		(property "Current" "1A"
			(at 373.895 -78.255 0)
			(layer "B.Fab")
			(hide yes)
			(effects
				(font
					(size 1 1)
					(thickness 0.15)
				)
				(justify mirror)
			)
		)
		(property "License" "Apache-2.0"
			(at 373.895 -78.255 0)
			(layer "B.Fab")
			(hide yes)
			(effects
				(font
					(size 1 1)
					(thickness 0.15)
				)
				(justify mirror)
			)
		)
		(property "MPN" "ERJ2GE0R00X"
			(at 373.895 -78.255 0)
			(layer "B.Fab")
			(hide yes)
			(effects
				(font
					(size 1 1)
					(thickness 0.15)
				)
				(justify mirror)
			)
		)
		(property "Manufacturer" "Panasonic"
			(at 373.895 -78.255 0)
			(layer "B.Fab")
			(hide yes)
			(effects
				(font
					(size 1 1)
					(thickness 0.15)
				)
				(justify mirror)
			)
		)
		(property "Public" ""
			(at 373.895 -78.255 0)
			(layer "B.Fab")
			(hide yes)
			(effects
				(font
					(size 1 1)
					(thickness 0.15)
				)
				(justify mirror)
			)
		)
		(property "Tolerance" "~"
			(at 373.895 -78.255 0)
			(layer "B.Fab")
			(hide yes)
			(effects
				(font
					(size 1 1)
					(thickness 0.15)
				)
				(justify mirror)
			)
		)
		(property "Val" "0R"
			(at 373.895 -78.255 0)
			(layer "B.Fab")
			(hide yes)
			(effects
				(font
					(size 1 1)
					(thickness 0.15)
				)
				(justify mirror)
			)
		)
		(sheetname "/FPGA MSSIO/")
		(sheetfile "fpga-mssio.kicad_sch")
		(attr smd)
		(fp_rect
			(start -0.925 0.47)
			(end 0.925 -0.47)
			(stroke
				(width 0.05)
				(type default)
			)
			(fill no)
			(layer "B.CrtYd")
		)
		(fp_rect
			(start -0.5 0.25)
			(end 0.5 -0.25)
			(stroke
				(width 0.15)
				(type solid)
			)
			(fill no)
			(layer "B.Fab")
		)
		(fp_text user "${REFERENCE}"
			(at -0.95 -3.168 270)
			(layer "B.Fab")
			(effects
				(font
					(size 0.7 0.7)
					(thickness 0.15)
				)
				(justify left bottom mirror)
			)
		)
		(fp_text user "License: Apache-2.0"
			(at -0.95 -5.169 270)
			(layer "B.Fab")
			(effects
				(font
					(size 0.7 0.7)
					(thickness 0.15)
				)
				(justify left bottom mirror)
			)
		)
		(fp_text user "Author: Antmicro"
			(at -0.95 -4.169 270)
			(layer "B.Fab")
			(effects
				(font
					(size 0.7 0.7)
					(thickness 0.15)
				)
				(justify left bottom mirror)
			)
		)
		(pad "1" smd roundrect
			(at -0.48 0 90)
			(size 0.59 0.64)
			(layers "B.Cu" "B.Mask" "B.Paste")
			(roundrect_rratio 0.25)
			(net 295 "Net-(U1C-MSSIO36B2)")
			(pintype "passive")
		)
		(pad "2" smd roundrect
			(at 0.48 0 90)
			(size 0.59 0.64)
			(layers "B.Cu" "B.Mask" "B.Paste")
			(roundrect_rratio 0.25)
			(net 194 "/FPGA MSSIO/BT_UART_RX")
			(pintype "passive")
		)
	)
	(footprint "antmicro-footprints:C_0402_1005Metric"
		(layer "B.Cu")
		(at 212.1925 133.697)
		(descr "Capacitor SMD 0402")
		(tags "capacitor SMD 0402")
		(property "Reference" "C77"
			(at -0.4175 2.528 0)
			(layer "B.SilkS")
			(effects
				(font
					(size 0.7 0.7)
					(thickness 0.15)
				)
				(justify right bottom mirror)
			)
		)
		(property "Value" "C_100n_0402"
			(at -1.022927 -2.155213 0)
			(layer "B.Fab")
			(hide yes)
			(effects
				(font
					(size 0.7 0.7)
					(thickness 0.15)
				)
				(justify right bottom mirror)
			)
		)
		(property "Datasheet" "https://www.murata.com/products/productdetail?partno=GRM155R61H104KE14%23"
			(at 0 0 0)
			(layer "F.Fab")
			(hide yes)
			(effects
				(font
					(size 1.27 1.27)
					(thickness 0.15)
				)
			)
		)
		(property "Description" "SMD Multilayer Ceramic Capacitor, 0.1 µF, 50 V, 0402 [1005 Metric], ± 10%, X5R, GRM Series"
			(at 0 0 0)
			(layer "F.Fab")
			(hide yes)
			(effects
				(font
					(size 1.27 1.27)
					(thickness 0.15)
				)
			)
		)
		(property "Author" "Antmicro"
			(at 0 0 0)
			(layer "B.Fab")
			(hide yes)
			(effects
				(font
					(size 1 1)
					(thickness 0.15)
				)
				(justify mirror)
			)
		)
		(property "Dielectric" "X5R"
			(at 0 0 0)
			(layer "B.Fab")
			(hide yes)
			(effects
				(font
					(size 1 1)
					(thickness 0.15)
				)
				(justify mirror)
			)
		)
		(property "License" "Apache-2.0"
			(at 0 0 0)
			(layer "B.Fab")
			(hide yes)
			(effects
				(font
					(size 1 1)
					(thickness 0.15)
				)
				(justify mirror)
			)
		)
		(property "MPN" "GRM155R61H104KE14D"
			(at 0 0 0)
			(layer "B.Fab")
			(hide yes)
			(effects
				(font
					(size 1 1)
					(thickness 0.15)
				)
				(justify mirror)
			)
		)
		(property "Manufacturer" "Murata"
			(at 0 0 0)
			(layer "B.Fab")
			(hide yes)
			(effects
				(font
					(size 1 1)
					(thickness 0.15)
				)
				(justify mirror)
			)
		)
		(property "Public" ""
			(at 0 0 0)
			(layer "B.Fab")
			(hide yes)
			(effects
				(font
					(size 1 1)
					(thickness 0.15)
				)
				(justify mirror)
			)
		)
		(property "Val" "100n"
			(at 0 0 0)
			(layer "B.Fab")
			(hide yes)
			(effects
				(font
					(size 1 1)
					(thickness 0.15)
				)
				(justify mirror)
			)
		)
		(property "Voltage" "50V"
			(at 0 0 0)
			(layer "B.Fab")
			(hide yes)
			(effects
				(font
					(size 1 1)
					(thickness 0.15)
				)
				(justify mirror)
			)
		)
		(sheetname "/Memory/")
		(sheetfile "memory.kicad_sch")
		(attr smd)
		(fp_rect
			(start -0.925 0.47)
			(end 0.925 -0.47)
			(stroke
				(width 0.05)
				(type default)
			)
			(fill no)
			(layer "B.CrtYd")
		)
		(fp_line
			(start -0.494 -0.248)
			(end -0.494 0.25)
			(stroke
				(width 0.15)
				(type solid)
			)
			(layer "B.Fab")
		)
		(fp_line
			(start -0.494 0.25)
			(end 0.504 0.25)
			(stroke
				(width 0.15)
				(type solid)
			)
			(layer "B.Fab")
		)
		(fp_line
			(start 0.504 -0.248)
			(end -0.494 -0.248)
			(stroke
				(width 0.15)
				(type solid)
			)
			(layer "B.Fab")
		)
		(fp_line
			(start 0.504 0.25)
			(end 0.504 -0.248)
			(stroke
				(width 0.15)
				(type solid)
			)
			(layer "B.Fab")
		)
		(fp_text user "License: Apache-2.0"
			(at -0.939 -5.799 180)
			(layer "B.Fab")
			(effects
				(font
					(size 0.7 0.7)
					(thickness 0.15)
				)
				(justify left bottom mirror)
			)
		)
		(fp_text user "Author: Antmicro"
			(at -0.939 -3.399 180)
			(layer "B.Fab")
			(effects
				(font
					(size 0.7 0.7)
					(thickness 0.15)
				)
				(justify left bottom mirror)
			)
		)
		(fp_text user "${REFERENCE}"
			(at -0.939 -4.599 180)
			(layer "B.Fab")
			(effects
				(font
					(size 0.7 0.7)
					(thickness 0.15)
				)
				(justify left bottom mirror)
			)
		)
		(pad "1" smd roundrect
			(at -0.48 0)
			(size 0.59 0.64)
			(layers "B.Cu" "B.Mask" "B.Paste")
			(roundrect_rratio 0.25)
			(net 417 "GND")
			(pintype "passive")
		)
		(pad "2" smd roundrect
			(at 0.48 0)
			(size 0.59 0.64)
			(layers "B.Cu" "B.Mask" "B.Paste")
			(roundrect_rratio 0.25)
			(net 137 "SD_VDD")
			(pintype "passive")
		)
	)
	(footprint "antmicro-footprints:C_0402_1005Metric"
		(layer "B.Cu")
		(at 213.415 150.05 180)
		(descr "Capacitor SMD 0402")
		(tags "capacitor SMD 0402")
		(property "Reference" "C221"
			(at -1.085 -1.375 0)
			(layer "B.SilkS")
			(effects
				(font
					(size 0.7 0.7)
					(thickness 0.15)
				)
				(justify left bottom mirror)
			)
		)
		(property "Value" "C_100n_0402"
			(at -1.022927 -2.155213 0)
			(layer "B.Fab")
			(hide yes)
			(effects
				(font
					(size 0.7 0.7)
					(thickness 0.15)
				)
				(justify left bottom mirror)
			)
		)
		(property "Datasheet" "https://www.murata.com/products/productdetail?partno=GRM155R61H104KE14%23"
			(at 0 0 180)
			(layer "F.Fab")
			(hide yes)
			(effects
				(font
					(size 1.27 1.27)
					(thickness 0.15)
				)
			)
		)
		(property "Description" "SMD Multilayer Ceramic Capacitor, 0.1 µF, 50 V, 0402 [1005 Metric], ± 10%, X5R, GRM Series"
			(at 0 0 180)
			(layer "F.Fab")
			(hide yes)
			(effects
				(font
					(size 1.27 1.27)
					(thickness 0.15)
				)
			)
		)
		(property "Author" "Antmicro"
			(at 426.83 300.1 0)
			(layer "B.Fab")
			(hide yes)
			(effects
				(font
					(size 1 1)
					(thickness 0.15)
				)
				(justify mirror)
			)
		)
		(property "Dielectric" "X5R"
			(at 426.83 300.1 0)
			(layer "B.Fab")
			(hide yes)
			(effects
				(font
					(size 1 1)
					(thickness 0.15)
				)
				(justify mirror)
			)
		)
		(property "License" "Apache-2.0"
			(at 426.83 300.1 0)
			(layer "B.Fab")
			(hide yes)
			(effects
				(font
					(size 1 1)
					(thickness 0.15)
				)
				(justify mirror)
			)
		)
		(property "MPN" "GRM155R61H104KE14D"
			(at 426.83 300.1 0)
			(layer "B.Fab")
			(hide yes)
			(effects
				(font
					(size 1 1)
					(thickness 0.15)
				)
				(justify mirror)
			)
		)
		(property "Manufacturer" "Murata"
			(at 426.83 300.1 0)
			(layer "B.Fab")
			(hide yes)
			(effects
				(font
					(size 1 1)
					(thickness 0.15)
				)
				(justify mirror)
			)
		)
		(property "Public" ""
			(at 426.83 300.1 0)
			(layer "B.Fab")
			(hide yes)
			(effects
				(font
					(size 1 1)
					(thickness 0.15)
				)
				(justify mirror)
			)
		)
		(property "Val" "100n"
			(at 426.83 300.1 0)
			(layer "B.Fab")
			(hide yes)
			(effects
				(font
					(size 1 1)
					(thickness 0.15)
				)
				(justify mirror)
			)
		)
		(property "Voltage" "50V"
			(at 426.83 300.1 0)
			(layer "B.Fab")
			(hide yes)
			(effects
				(font
					(size 1 1)
					(thickness 0.15)
				)
				(justify mirror)
			)
		)
		(sheetname "/USB/")
		(sheetfile "usb.kicad_sch")
		(attr smd)
		(fp_rect
			(start -0.925 0.47)
			(end 0.925 -0.47)
			(stroke
				(width 0.05)
				(type default)
			)
			(fill no)
			(layer "B.CrtYd")
		)
		(fp_line
			(start 0.504 0.25)
			(end 0.504 -0.248)
			(stroke
				(width 0.15)
				(type solid)
			)
			(layer "B.Fab")
		)
		(fp_line
			(start 0.504 -0.248)
			(end -0.494 -0.248)
			(stroke
				(width 0.15)
				(type solid)
			)
			(layer "B.Fab")
		)
		(fp_line
			(start -0.494 0.25)
			(end 0.504 0.25)
			(stroke
				(width 0.15)
				(type solid)
			)
			(layer "B.Fab")
		)
		(fp_line
			(start -0.494 -0.248)
			(end -0.494 0.25)
			(stroke
				(width 0.15)
				(type solid)
			)
			(layer "B.Fab")
		)
		(fp_text user "Author: Antmicro"
			(at -0.939 -3.399 0)
			(layer "B.Fab")
			(effects
				(font
					(size 0.7 0.7)
					(thickness 0.15)
				)
				(justify left bottom mirror)
			)
		)
		(fp_text user "License: Apache-2.0"
			(at -0.939 -5.799 0)
			(layer "B.Fab")
			(effects
				(font
					(size 0.7 0.7)
					(thickness 0.15)
				)
				(justify left bottom mirror)
			)
		)
		(fp_text user "${REFERENCE}"
			(at -0.939 -4.599 0)
			(layer "B.Fab")
			(effects
				(font
					(size 0.7 0.7)
					(thickness 0.15)
				)
				(justify left bottom mirror)
			)
		)
		(pad "1" smd roundrect
			(at -0.48 0 180)
			(size 0.59 0.64)
			(layers "B.Cu" "B.Mask" "B.Paste")
			(roundrect_rratio 0.25)
			(net 417 "GND")
			(pintype "passive")
		)
		(pad "2" smd roundrect
			(at 0.48 0 180)
			(size 0.59 0.64)
			(layers "B.Cu" "B.Mask" "B.Paste")
			(roundrect_rratio 0.25)
			(net 50 "+3V3")
			(pintype "passive")
		)
	)
	(footprint "antmicro-footprints:R_0402_1005Metric"
		(layer "B.Cu")
		(at 201.704 137.1 180)
		(descr "Resistor SMD 0402")
		(tags "resistor SMD 0402")
		(property "Reference" "R14"
			(at -0.976 0.56 0)
			(layer "B.SilkS")
			(effects
				(font
					(size 0.7 0.7)
					(thickness 0.15)
				)
				(justify left bottom mirror)
			)
		)
		(property "Value" "R_10k_0402"
			(at -1.011843 -1.772047 0)
			(layer "B.Fab")
			(hide yes)
			(effects
				(font
					(size 0.7 0.7)
					(thickness 0.15)
				)
				(justify left bottom mirror)
			)
		)
		(property "Datasheet" "https://www.bourns.com/docs/product-datasheets/cr.pdf"
			(at 0 0 180)
			(layer "F.Fab")
			(hide yes)
			(effects
				(font
					(size 1.27 1.27)
					(thickness 0.15)
				)
			)
		)
		(property "Description" "SMD Chip Resistor, 10 kohm, ± 1%, 62.5 mW, 0402 [1005 Metric], Thick Film, General Purpose"
			(at 0 0 180)
			(layer "F.Fab")
			(hide yes)
			(effects
				(font
					(size 1.27 1.27)
					(thickness 0.15)
				)
			)
		)
		(property "Author" "Antmicro"
			(at 403.408 274.2 0)
			(layer "B.Fab")
			(hide yes)
			(effects
				(font
					(size 1 1)
					(thickness 0.15)
				)
				(justify mirror)
			)
		)
		(property "License" "Apache-2.0"
			(at 403.408 274.2 0)
			(layer "B.Fab")
			(hide yes)
			(effects
				(font
					(size 1 1)
					(thickness 0.15)
				)
				(justify mirror)
			)
		)
		(property "MPN" "CR0402-FX-1002GLF"
			(at 403.408 274.2 0)
			(layer "B.Fab")
			(hide yes)
			(effects
				(font
					(size 1 1)
					(thickness 0.15)
				)
				(justify mirror)
			)
		)
		(property "Manufacturer" "Bourns"
			(at 403.408 274.2 0)
			(layer "B.Fab")
			(hide yes)
			(effects
				(font
					(size 1 1)
					(thickness 0.15)
				)
				(justify mirror)
			)
		)
		(property "Public" ""
			(at 403.408 274.2 0)
			(layer "B.Fab")
			(hide yes)
			(effects
				(font
					(size 1 1)
					(thickness 0.15)
				)
				(justify mirror)
			)
		)
		(property "Tolerance" "1%"
			(at 403.408 274.2 0)
			(layer "B.Fab")
			(hide yes)
			(effects
				(font
					(size 1 1)
					(thickness 0.15)
				)
				(justify mirror)
			)
		)
		(property "Val" "10k"
			(at 403.408 274.2 0)
			(layer "B.Fab")
			(hide yes)
			(effects
				(font
					(size 1 1)
					(thickness 0.15)
				)
				(justify mirror)
			)
		)
		(sheetname "/FPGA Supply/")
		(sheetfile "fpga-supply.kicad_sch")
		(attr smd)
		(fp_rect
			(start -0.925 0.47)
			(end 0.925 -0.47)
			(stroke
				(width 0.05)
				(type default)
			)
			(fill no)
			(layer "B.CrtYd")
		)
		(fp_rect
			(start -0.5 0.25)
			(end 0.5 -0.25)
			(stroke
				(width 0.15)
				(type solid)
			)
			(fill no)
			(layer "B.Fab")
		)
		(fp_text user "${REFERENCE}"
			(at -0.95 -3.168 0)
			(layer "B.Fab")
			(effects
				(font
					(size 0.7 0.7)
					(thickness 0.15)
				)
				(justify left bottom mirror)
			)
		)
		(fp_text user "License: Apache-2.0"
			(at -0.95 -5.169 0)
			(layer "B.Fab")
			(effects
				(font
					(size 0.7 0.7)
					(thickness 0.15)
				)
				(justify left bottom mirror)
			)
		)
		(fp_text user "Author: Antmicro"
			(at -0.95 -4.169 0)
			(layer "B.Fab")
			(effects
				(font
					(size 0.7 0.7)
					(thickness 0.15)
				)
				(justify left bottom mirror)
			)
		)
		(pad "1" smd roundrect
			(at -0.48 0 180)
			(size 0.59 0.64)
			(layers "B.Cu" "B.Mask" "B.Paste")
			(roundrect_rratio 0.25)
			(net 417 "GND")
			(pintype "passive")
		)
		(pad "2" smd roundrect
			(at 0.48 0 180)
			(size 0.59 0.64)
			(layers "B.Cu" "B.Mask" "B.Paste")
			(roundrect_rratio 0.25)
			(net 1 "/FPGA Supply/XCVR_VREF")
			(pintype "passive")
		)
	)
	(footprint "antmicro-footprints:C_0402_1005Metric"
		(layer "B.Cu")
		(at 199.89 132.79 90)
		(descr "Capacitor SMD 0402")
		(tags "capacitor SMD 0402")
		(property "Reference" "C7"
			(at 7.19 -9.615 270)
			(layer "B.SilkS")
			(effects
				(font
					(size 0.7 0.7)
					(thickness 0.15)
				)
				(justify left bottom mirror)
			)
		)
		(property "Value" "C_100n_0402"
			(at -1.022927 -2.155213 270)
			(layer "B.Fab")
			(hide yes)
			(effects
				(font
					(size 0.7 0.7)
					(thickness 0.15)
				)
				(justify left bottom mirror)
			)
		)
		(property "Datasheet" "https://www.murata.com/products/productdetail?partno=GRM155R61H104KE14%23"
			(at 0 0 90)
			(layer "F.Fab")
			(hide yes)
			(effects
				(font
					(size 1.27 1.27)
					(thickness 0.15)
				)
			)
		)
		(property "Description" "SMD Multilayer Ceramic Capacitor, 0.1 µF, 50 V, 0402 [1005 Metric], ± 10%, X5R, GRM Series"
			(at 0 0 90)
			(layer "F.Fab")
			(hide yes)
			(effects
				(font
					(size 1.27 1.27)
					(thickness 0.15)
				)
			)
		)
		(property "Author" "Antmicro"
			(at 332.68 -67.1 0)
			(layer "B.Fab")
			(hide yes)
			(effects
				(font
					(size 1 1)
					(thickness 0.15)
				)
				(justify mirror)
			)
		)
		(property "Dielectric" "X5R"
			(at 332.68 -67.1 0)
			(layer "B.Fab")
			(hide yes)
			(effects
				(font
					(size 1 1)
					(thickness 0.15)
				)
				(justify mirror)
			)
		)
		(property "License" "Apache-2.0"
			(at 332.68 -67.1 0)
			(layer "B.Fab")
			(hide yes)
			(effects
				(font
					(size 1 1)
					(thickness 0.15)
				)
				(justify mirror)
			)
		)
		(property "MPN" "GRM155R61H104KE14D"
			(at 332.68 -67.1 0)
			(layer "B.Fab")
			(hide yes)
			(effects
				(font
					(size 1 1)
					(thickness 0.15)
				)
				(justify mirror)
			)
		)
		(property "Manufacturer" "Murata"
			(at 332.68 -67.1 0)
			(layer "B.Fab")
			(hide yes)
			(effects
				(font
					(size 1 1)
					(thickness 0.15)
				)
				(justify mirror)
			)
		)
		(property "Public" ""
			(at 332.68 -67.1 0)
			(layer "B.Fab")
			(hide yes)
			(effects
				(font
					(size 1 1)
					(thickness 0.15)
				)
				(justify mirror)
			)
		)
		(property "Val" "100n"
			(at 332.68 -67.1 0)
			(layer "B.Fab")
			(hide yes)
			(effects
				(font
					(size 1 1)
					(thickness 0.15)
				)
				(justify mirror)
			)
		)
		(property "Voltage" "50V"
			(at 332.68 -67.1 0)
			(layer "B.Fab")
			(hide yes)
			(effects
				(font
					(size 1 1)
					(thickness 0.15)
				)
				(justify mirror)
			)
		)
		(sheetname "/FPGA Supply/")
		(sheetfile "fpga-supply.kicad_sch")
		(attr smd)
		(fp_rect
			(start -0.925 0.47)
			(end 0.925 -0.47)
			(stroke
				(width 0.05)
				(type default)
			)
			(fill no)
			(layer "B.CrtYd")
		)
		(fp_line
			(start 0.504 -0.248)
			(end -0.494 -0.248)
			(stroke
				(width 0.15)
				(type solid)
			)
			(layer "B.Fab")
		)
		(fp_line
			(start -0.494 -0.248)
			(end -0.494 0.25)
			(stroke
				(width 0.15)
				(type solid)
			)
			(layer "B.Fab")
		)
		(fp_line
			(start 0.504 0.25)
			(end 0.504 -0.248)
			(stroke
				(width 0.15)
				(type solid)
			)
			(layer "B.Fab")
		)
		(fp_line
			(start -0.494 0.25)
			(end 0.504 0.25)
			(stroke
				(width 0.15)
				(type solid)
			)
			(layer "B.Fab")
		)
		(fp_text user "Author: Antmicro"
			(at -0.939 -3.399 270)
			(layer "B.Fab")
			(effects
				(font
					(size 0.7 0.7)
					(thickness 0.15)
				)
				(justify left bottom mirror)
			)
		)
		(fp_text user "${REFERENCE}"
			(at -0.939 -4.599 270)
			(layer "B.Fab")
			(effects
				(font
					(size 0.7 0.7)
					(thickness 0.15)
				)
				(justify left bottom mirror)
			)
		)
		(fp_text user "License: Apache-2.0"
			(at -0.939 -5.799 270)
			(layer "B.Fab")
			(effects
				(font
					(size 0.7 0.7)
					(thickness 0.15)
				)
				(justify left bottom mirror)
			)
		)
		(pad "1" smd roundrect
			(at -0.48 0 90)
			(size 0.59 0.64)
			(layers "B.Cu" "B.Mask" "B.Paste")
			(roundrect_rratio 0.25)
			(net 417 "GND")
			(pintype "passive")
		)
		(pad "2" smd roundrect
			(at 0.48 0 90)
			(size 0.59 0.64)
			(layers "B.Cu" "B.Mask" "B.Paste")
			(roundrect_rratio 0.25)
			(net 50 "+3V3")
			(pintype "passive")
		)
	)
	(footprint "antmicro-footprints:C_0402_1005Metric"
		(layer "B.Cu")
		(at 181.2 132.1925)
		(descr "Capacitor SMD 0402")
		(tags "capacitor SMD 0402")
		(property "Reference" "C120"
			(at -1.18 -0.5925 0)
			(layer "B.SilkS")
			(effects
				(font
					(size 0.7 0.7)
					(thickness 0.15)
				)
				(justify right bottom mirror)
			)
		)
		(property "Value" "C_1u_0402"
			(at -1.022927 -2.155213 0)
			(layer "B.Fab")
			(hide yes)
			(effects
				(font
					(size 0.7 0.7)
					(thickness 0.15)
				)
				(justify right bottom mirror)
			)
		)
		(property "Datasheet" "https://product.tdk.com/en/search/capacitor/ceramic/mlcc/info?part_no=C1005X6S1A105K050BC"
			(at 0 0 0)
			(layer "F.Fab")
			(hide yes)
			(effects
				(font
					(size 1.27 1.27)
					(thickness 0.15)
				)
			)
		)
		(property "Description" "SMD Multilayer Ceramic Capacitor, 1 µF, 10 V, 0402 [1005 Metric], ± 10%, X6S, C"
			(at 0 0 0)
			(layer "F.Fab")
			(hide yes)
			(effects
				(font
					(size 1.27 1.27)
					(thickness 0.15)
				)
			)
		)
		(property "Author" "Antmicro"
			(at 0 0 0)
			(layer "B.Fab")
			(hide yes)
			(effects
				(font
					(size 1 1)
					(thickness 0.15)
				)
				(justify mirror)
			)
		)
		(property "Dielectric" "X5R"
			(at 0 0 0)
			(layer "B.Fab")
			(hide yes)
			(effects
				(font
					(size 1 1)
					(thickness 0.15)
				)
				(justify mirror)
			)
		)
		(property "License" "Apache-2.0"
			(at 0 0 0)
			(layer "B.Fab")
			(hide yes)
			(effects
				(font
					(size 1 1)
					(thickness 0.15)
				)
				(justify mirror)
			)
		)
		(property "MPN" "C1005X6S1A105K050BC"
			(at 0 0 0)
			(layer "B.Fab")
			(hide yes)
			(effects
				(font
					(size 1 1)
					(thickness 0.15)
				)
				(justify mirror)
			)
		)
		(property "Manufacturer" "TDK"
			(at 0 0 0)
			(layer "B.Fab")
			(hide yes)
			(effects
				(font
					(size 1 1)
					(thickness 0.15)
				)
				(justify mirror)
			)
		)
		(property "Public" ""
			(at 0 0 0)
			(layer "B.Fab")
			(hide yes)
			(effects
				(font
					(size 1 1)
					(thickness 0.15)
				)
				(justify mirror)
			)
		)
		(property "Val" "1u"
			(at 0 0 0)
			(layer "B.Fab")
			(hide yes)
			(effects
				(font
					(size 1 1)
					(thickness 0.15)
				)
				(justify mirror)
			)
		)
		(property "Voltage" "16V"
			(at 0 0 0)
			(layer "B.Fab")
			(hide yes)
			(effects
				(font
					(size 1 1)
					(thickness 0.15)
				)
				(justify mirror)
			)
		)
		(sheetname "/LPDDR4/")
		(sheetfile "lpddr.kicad_sch")
		(attr smd)
		(fp_rect
			(start -0.925 0.47)
			(end 0.925 -0.47)
			(stroke
				(width 0.05)
				(type default)
			)
			(fill no)
			(layer "B.CrtYd")
		)
		(fp_line
			(start -0.494 -0.248)
			(end -0.494 0.25)
			(stroke
				(width 0.15)
				(type solid)
			)
			(layer "B.Fab")
		)
		(fp_line
			(start -0.494 0.25)
			(end 0.504 0.25)
			(stroke
				(width 0.15)
				(type solid)
			)
			(layer "B.Fab")
		)
		(fp_line
			(start 0.504 -0.248)
			(end -0.494 -0.248)
			(stroke
				(width 0.15)
				(type solid)
			)
			(layer "B.Fab")
		)
		(fp_line
			(start 0.504 0.25)
			(end 0.504 -0.248)
			(stroke
				(width 0.15)
				(type solid)
			)
			(layer "B.Fab")
		)
		(fp_text user "License: Apache-2.0"
			(at -0.939 -5.799 180)
			(layer "B.Fab")
			(effects
				(font
					(size 0.7 0.7)
					(thickness 0.15)
				)
				(justify left bottom mirror)
			)
		)
		(fp_text user "${REFERENCE}"
			(at -0.939 -4.599 180)
			(layer "B.Fab")
			(effects
				(font
					(size 0.7 0.7)
					(thickness 0.15)
				)
				(justify left bottom mirror)
			)
		)
		(fp_text user "Author: Antmicro"
			(at -0.939 -3.399 180)
			(layer "B.Fab")
			(effects
				(font
					(size 0.7 0.7)
					(thickness 0.15)
				)
				(justify left bottom mirror)
			)
		)
		(pad "1" smd roundrect
			(at -0.48 0)
			(size 0.59 0.64)
			(layers "B.Cu" "B.Mask" "B.Paste")
			(roundrect_rratio 0.25)
			(net 417 "GND")
			(pintype "passive")
		)
		(pad "2" smd roundrect
			(at 0.48 0)
			(size 0.59 0.64)
			(layers "B.Cu" "B.Mask" "B.Paste")
			(roundrect_rratio 0.25)
			(net 48 "+1V8")
			(pintype "passive")
		)
	)
	(footprint "antmicro-footprints:C_0603_1608Metric"
		(layer "B.Cu")
		(at 190.78 135.52)
		(descr "Capacitor SMD 0603")
		(tags "capacitor 0603")
		(property "Reference" "C54"
			(at -0.58 -0.72 0)
			(layer "B.SilkS")
			(effects
				(font
					(size 0.7 0.7)
					(thickness 0.15)
				)
				(justify right bottom mirror)
			)
		)
		(property "Value" "C_47u_0603"
			(at -1.42757 -1.770288 0)
			(layer "B.Fab")
			(hide yes)
			(effects
				(font
					(size 0.7 0.7)
					(thickness 0.15)
				)
				(justify right bottom mirror)
			)
		)
		(property "Datasheet" "https://www.murata.com/products/productdetail?partno=GRM188R60J476ME15%23"
			(at 0 0 0)
			(layer "F.Fab")
			(hide yes)
			(effects
				(font
					(size 1.27 1.27)
					(thickness 0.15)
				)
			)
		)
		(property "Description" "SMD Multilayer Ceramic Capacitor, 47 µF, 6.3 V, 0603 [1608 Metric], ± 20%, X5R, GRM Series"
			(at 0 0 0)
			(layer "F.Fab")
			(hide yes)
			(effects
				(font
					(size 1.27 1.27)
					(thickness 0.15)
				)
			)
		)
		(property "Author" "Antmicro"
			(at 0 0 0)
			(layer "B.Fab")
			(hide yes)
			(effects
				(font
					(size 1 1)
					(thickness 0.15)
				)
				(justify mirror)
			)
		)
		(property "Capacitance" "47u"
			(at 0 0 0)
			(layer "B.Fab")
			(hide yes)
			(effects
				(font
					(size 1 1)
					(thickness 0.15)
				)
				(justify mirror)
			)
		)
		(property "Dielectric" "X7R"
			(at 0 0 0)
			(layer "B.Fab")
			(hide yes)
			(effects
				(font
					(size 1 1)
					(thickness 0.15)
				)
				(justify mirror)
			)
		)
		(property "License" "Apache-2.0"
			(at 0 0 0)
			(layer "B.Fab")
			(hide yes)
			(effects
				(font
					(size 1 1)
					(thickness 0.15)
				)
				(justify mirror)
			)
		)
		(property "MPN" "GRM188R60J476ME15D"
			(at 0 0 0)
			(layer "B.Fab")
			(hide yes)
			(effects
				(font
					(size 1 1)
					(thickness 0.15)
				)
				(justify mirror)
			)
		)
		(property "Manufacturer" "Murata"
			(at 0 0 0)
			(layer "B.Fab")
			(hide yes)
			(effects
				(font
					(size 1 1)
					(thickness 0.15)
				)
				(justify mirror)
			)
		)
		(property "Public" ""
			(at 0 0 0)
			(layer "B.Fab")
			(hide yes)
			(effects
				(font
					(size 1 1)
					(thickness 0.15)
				)
				(justify mirror)
			)
		)
		(property "Val" "47u"
			(at 0 0 0)
			(layer "B.Fab")
			(hide yes)
			(effects
				(font
					(size 1 1)
					(thickness 0.15)
				)
				(justify mirror)
			)
		)
		(property "Voltage" "50V"
			(at 0 0 0)
			(layer "B.Fab")
			(hide yes)
			(effects
				(font
					(size 1 1)
					(thickness 0.15)
				)
				(justify mirror)
			)
		)
		(sheetname "/FPGA Supply/")
		(sheetfile "fpga-supply.kicad_sch")
		(attr smd)
		(fp_line
			(start -0.15 -0.4)
			(end 0.15 -0.4)
			(stroke
				(width 0.15)
				(type solid)
			)
			(layer "B.SilkS")
		)
		(fp_line
			(start -0.15 0.4)
			(end 0.15 0.4)
			(stroke
				(width 0.15)
				(type solid)
			)
			(layer "B.SilkS")
		)
		(fp_rect
			(start -1.25 0.65)
			(end 1.25 -0.65)
			(stroke
				(width 0.05)
				(type solid)
			)
			(fill no)
			(layer "B.CrtYd")
		)
		(fp_rect
			(start -0.8 0.4)
			(end 0.8 -0.4)
			(stroke
				(width 0.15)
				(type solid)
			)
			(fill no)
			(layer "B.Fab")
		)
		(fp_text user "${REFERENCE}"
			(at -1.682 -3.895 180)
			(layer "B.Fab")
			(effects
				(font
					(size 0.7 0.7)
					(thickness 0.15)
				)
				(justify left bottom mirror)
			)
		)
		(fp_text user "Author: Antmicro"
			(at -1.682 -4.894 180)
			(layer "B.Fab")
			(effects
				(font
					(size 0.7 0.7)
					(thickness 0.15)
				)
				(justify left bottom mirror)
			)
		)
		(fp_text user "License: Apache-2.0"
			(at -1.682 -5.895 180)
			(layer "B.Fab")
			(effects
				(font
					(size 0.7 0.7)
					(thickness 0.15)
				)
				(justify left bottom mirror)
			)
		)
		(pad "1" smd roundrect
			(at -0.7 0)
			(size 0.8 1)
			(layers "B.Cu" "B.Mask" "B.Paste")
			(roundrect_rratio 0.2)
			(net 417 "GND")
			(pintype "passive")
		)
		(pad "2" smd roundrect
			(at 0.7 0)
			(size 0.8 1)
			(layers "B.Cu" "B.Mask" "B.Paste")
			(roundrect_rratio 0.2)
			(net 48 "+1V8")
			(pintype "passive")
		)
	)
	(footprint "antmicro-footprints:R_0603_1608Metric"
		(layer "B.Cu")
		(at 184.225 139.25)
		(descr "Resistor SMD 0603")
		(tags "resistor SMD 0603")
		(property "Reference" "R47"
			(at 1.6 -0.675 180)
			(layer "B.SilkS")
			(effects
				(font
					(size 0.7 0.7)
					(thickness 0.15)
				)
				(justify left bottom mirror)
			)
		)
		(property "Value" "R_0R01_0603"
			(at 0 -1.6 180)
			(layer "B.Fab")
			(hide yes)
			(effects
				(font
					(size 0.7 0.7)
					(thickness 0.15)
				)
				(justify left bottom mirror)
			)
		)
		(property "Datasheet" "https://www.bourns.com/docs/product-datasheets/cfn-a.pdf"
			(at 0 0 0)
			(layer "F.Fab")
			(hide yes)
			(effects
				(font
					(size 1.27 1.27)
					(thickness 0.15)
				)
			)
		)
		(property "Description" "SMD Chip Resistor, 10 mohm, ± 1%, 0.5 W, 0603 [1608 Metric], Metal Foil, Current Sensing"
			(at 0 0 0)
			(layer "F.Fab")
			(hide yes)
			(effects
				(font
					(size 1.27 1.27)
					(thickness 0.15)
				)
			)
		)
		(property "Author" "Antmicro"
			(at 0 0 0)
			(layer "B.Fab")
			(hide yes)
			(effects
				(font
					(size 1 1)
					(thickness 0.15)
				)
				(justify mirror)
			)
		)
		(property "License" "Apache-2.0"
			(at 0 0 0)
			(layer "B.Fab")
			(hide yes)
			(effects
				(font
					(size 1 1)
					(thickness 0.15)
				)
				(justify mirror)
			)
		)
		(property "MPN" "CFN0603AFZ-R010ELF"
			(at 0 0 0)
			(layer "B.Fab")
			(hide yes)
			(effects
				(font
					(size 1 1)
					(thickness 0.15)
				)
				(justify mirror)
			)
		)
		(property "Manufacturer" "Bourns"
			(at 0 0 0)
			(layer "B.Fab")
			(hide yes)
			(effects
				(font
					(size 1 1)
					(thickness 0.15)
				)
				(justify mirror)
			)
		)
		(property "Public" ""
			(at 0 0 0)
			(layer "B.Fab")
			(hide yes)
			(effects
				(font
					(size 1 1)
					(thickness 0.15)
				)
				(justify mirror)
			)
		)
		(property "Tolerance" "1%"
			(at 0 0 0)
			(layer "B.Fab")
			(hide yes)
			(effects
				(font
					(size 1 1)
					(thickness 0.15)
				)
				(justify mirror)
			)
		)
		(property "Val" "0R01"
			(at 0 0 0)
			(layer "B.Fab")
			(hide yes)
			(effects
				(font
					(size 1 1)
					(thickness 0.15)
				)
				(justify mirror)
			)
		)
		(sheetname "/Supply/")
		(sheetfile "supply.kicad_sch")
		(attr smd)
		(fp_line
			(start -0.15 -0.4)
			(end 0.15 -0.4)
			(stroke
				(width 0.15)
				(type solid)
			)
			(layer "B.SilkS")
		)
		(fp_line
			(start -0.15 0.4)
			(end 0.15 0.4)
			(stroke
				(width 0.15)
				(type solid)
			)
			(layer "B.SilkS")
		)
		(fp_rect
			(start -1.25 0.65)
			(end 1.25 -0.65)
			(stroke
				(width 0.05)
				(type solid)
			)
			(fill no)
			(layer "B.CrtYd")
		)
		(fp_rect
			(start -0.8 0.4)
			(end 0.8 -0.4)
			(stroke
				(width 0.15)
				(type solid)
			)
			(fill no)
			(layer "B.Fab")
		)
		(fp_text user "License: Apache-2.0"
			(at -1.25 -5.9 180)
			(layer "B.Fab")
			(effects
				(font
					(size 0.7 0.7)
					(thickness 0.15)
				)
				(justify left bottom mirror)
			)
		)
		(fp_text user "Author: Antmicro"
			(at -1.25 -4.9 180)
			(layer "B.Fab")
			(effects
				(font
					(size 0.7 0.7)
					(thickness 0.15)
				)
				(justify left bottom mirror)
			)
		)
		(fp_text user "${REFERENCE}"
			(at -1.25 -3.898 180)
			(layer "B.Fab")
			(effects
				(font
					(size 0.7 0.7)
					(thickness 0.15)
				)
				(justify left bottom mirror)
			)
		)
		(pad "1" smd roundrect
			(at -0.7 0)
			(size 0.8 1)
			(layers "B.Cu" "B.Mask" "B.Paste")
			(roundrect_rratio 0.2)
			(net 272 "/Supply/SENSE3_P")
			(pintype "passive")
		)
		(pad "2" smd roundrect
			(at 0.7 0)
			(size 0.8 1)
			(layers "B.Cu" "B.Mask" "B.Paste")
			(roundrect_rratio 0.2)
			(net 2 "+1V1")
			(pintype "passive")
		)
	)
	(footprint "antmicro-footprints:C_0402_1005Metric"
		(layer "B.Cu")
		(at 211.72 119.384)
		(descr "Capacitor SMD 0402")
		(tags "capacitor SMD 0402")
		(property "Reference" "C261"
			(at -1.795 1.416 0)
			(layer "B.SilkS")
			(effects
				(font
					(size 0.7 0.7)
					(thickness 0.15)
				)
				(justify right bottom mirror)
			)
		)
		(property "Value" "C_100n_0402"
			(at -1.022927 -2.155213 0)
			(layer "B.Fab")
			(hide yes)
			(effects
				(font
					(size 0.7 0.7)
					(thickness 0.15)
				)
				(justify right bottom mirror)
			)
		)
		(property "Datasheet" "https://www.murata.com/products/productdetail?partno=GRM155R61H104KE14%23"
			(at 0 0 0)
			(layer "F.Fab")
			(hide yes)
			(effects
				(font
					(size 1.27 1.27)
					(thickness 0.15)
				)
			)
		)
		(property "Description" "SMD Multilayer Ceramic Capacitor, 0.1 µF, 50 V, 0402 [1005 Metric], ± 10%, X5R, GRM Series"
			(at 0 0 0)
			(layer "F.Fab")
			(hide yes)
			(effects
				(font
					(size 1.27 1.27)
					(thickness 0.15)
				)
			)
		)
		(property "Author" "Antmicro"
			(at 0 0 0)
			(layer "B.Fab")
			(hide yes)
			(effects
				(font
					(size 1 1)
					(thickness 0.15)
				)
				(justify mirror)
			)
		)
		(property "Dielectric" "X5R"
			(at 0 0 0)
			(layer "B.Fab")
			(hide yes)
			(effects
				(font
					(size 1 1)
					(thickness 0.15)
				)
				(justify mirror)
			)
		)
		(property "License" "Apache-2.0"
			(at 0 0 0)
			(layer "B.Fab")
			(hide yes)
			(effects
				(font
					(size 1 1)
					(thickness 0.15)
				)
				(justify mirror)
			)
		)
		(property "MPN" "GRM155R61H104KE14D"
			(at 0 0 0)
			(layer "B.Fab")
			(hide yes)
			(effects
				(font
					(size 1 1)
					(thickness 0.15)
				)
				(justify mirror)
			)
		)
		(property "Manufacturer" "Murata"
			(at 0 0 0)
			(layer "B.Fab")
			(hide yes)
			(effects
				(font
					(size 1 1)
					(thickness 0.15)
				)
				(justify mirror)
			)
		)
		(property "Public" ""
			(at 0 0 0)
			(layer "B.Fab")
			(hide yes)
			(effects
				(font
					(size 1 1)
					(thickness 0.15)
				)
				(justify mirror)
			)
		)
		(property "Val" "100n"
			(at 0 0 0)
			(layer "B.Fab")
			(hide yes)
			(effects
				(font
					(size 1 1)
					(thickness 0.15)
				)
				(justify mirror)
			)
		)
		(property "Voltage" "50V"
			(at 0 0 0)
			(layer "B.Fab")
			(hide yes)
			(effects
				(font
					(size 1 1)
					(thickness 0.15)
				)
				(justify mirror)
			)
		)
		(sheetname "/Ethernet/")
		(sheetfile "ethernet.kicad_sch")
		(attr smd)
		(fp_rect
			(start -0.925 0.47)
			(end 0.925 -0.47)
			(stroke
				(width 0.05)
				(type default)
			)
			(fill no)
			(layer "B.CrtYd")
		)
		(fp_line
			(start -0.494 -0.248)
			(end -0.494 0.25)
			(stroke
				(width 0.15)
				(type solid)
			)
			(layer "B.Fab")
		)
		(fp_line
			(start -0.494 0.25)
			(end 0.504 0.25)
			(stroke
				(width 0.15)
				(type solid)
			)
			(layer "B.Fab")
		)
		(fp_line
			(start 0.504 -0.248)
			(end -0.494 -0.248)
			(stroke
				(width 0.15)
				(type solid)
			)
			(layer "B.Fab")
		)
		(fp_line
			(start 0.504 0.25)
			(end 0.504 -0.248)
			(stroke
				(width 0.15)
				(type solid)
			)
			(layer "B.Fab")
		)
		(fp_text user "${REFERENCE}"
			(at -0.939 -4.599 180)
			(layer "B.Fab")
			(effects
				(font
					(size 0.7 0.7)
					(thickness 0.15)
				)
				(justify left bottom mirror)
			)
		)
		(fp_text user "Author: Antmicro"
			(at -0.939 -3.399 180)
			(layer "B.Fab")
			(effects
				(font
					(size 0.7 0.7)
					(thickness 0.15)
				)
				(justify left bottom mirror)
			)
		)
		(fp_text user "License: Apache-2.0"
			(at -0.939 -5.799 180)
			(layer "B.Fab")
			(effects
				(font
					(size 0.7 0.7)
					(thickness 0.15)
				)
				(justify left bottom mirror)
			)
		)
		(pad "1" smd roundrect
			(at -0.48 0)
			(size 0.59 0.64)
			(layers "B.Cu" "B.Mask" "B.Paste")
			(roundrect_rratio 0.25)
			(net 68 "/Ethernet/SGMII.TX0_N")
			(pintype "passive")
		)
		(pad "2" smd roundrect
			(at 0.48 0)
			(size 0.59 0.64)
			(layers "B.Cu" "B.Mask" "B.Paste")
			(roundrect_rratio 0.25)
			(net 167 "/Ethernet/SGMII_SI_N")
			(pintype "passive")
		)
	)
	(footprint "antmicro-footprints:R_0402_1005Metric"
		(layer "B.Cu")
		(at 225.6 142.345 180)
		(descr "Resistor SMD 0402")
		(tags "resistor SMD 0402")
		(property "Reference" "R143"
			(at -3.84 -0.375 0)
			(layer "B.SilkS")
			(effects
				(font
					(size 0.7 0.7)
					(thickness 0.15)
				)
				(justify left bottom mirror)
			)
		)
		(property "Value" "R_10k_0402"
			(at -1.011843 -1.772047 0)
			(layer "B.Fab")
			(hide yes)
			(effects
				(font
					(size 0.7 0.7)
					(thickness 0.15)
				)
				(justify left bottom mirror)
			)
		)
		(property "Datasheet" "https://www.bourns.com/docs/product-datasheets/cr.pdf"
			(at 0 0 180)
			(layer "F.Fab")
			(hide yes)
			(effects
				(font
					(size 1.27 1.27)
					(thickness 0.15)
				)
			)
		)
		(property "Description" "SMD Chip Resistor, 10 kohm, ± 1%, 62.5 mW, 0402 [1005 Metric], Thick Film, General Purpose"
			(at 0 0 180)
			(layer "F.Fab")
			(hide yes)
			(effects
				(font
					(size 1.27 1.27)
					(thickness 0.15)
				)
			)
		)
		(property "Author" "Antmicro"
			(at 451.2 284.69 0)
			(layer "B.Fab")
			(hide yes)
			(effects
				(font
					(size 1 1)
					(thickness 0.15)
				)
				(justify mirror)
			)
		)
		(property "License" "Apache-2.0"
			(at 451.2 284.69 0)
			(layer "B.Fab")
			(hide yes)
			(effects
				(font
					(size 1 1)
					(thickness 0.15)
				)
				(justify mirror)
			)
		)
		(property "MPN" "CR0402-FX-1002GLF"
			(at 451.2 284.69 0)
			(layer "B.Fab")
			(hide yes)
			(effects
				(font
					(size 1 1)
					(thickness 0.15)
				)
				(justify mirror)
			)
		)
		(property "Manufacturer" "Bourns"
			(at 451.2 284.69 0)
			(layer "B.Fab")
			(hide yes)
			(effects
				(font
					(size 1 1)
					(thickness 0.15)
				)
				(justify mirror)
			)
		)
		(property "Public" ""
			(at 451.2 284.69 0)
			(layer "B.Fab")
			(hide yes)
			(effects
				(font
					(size 1 1)
					(thickness 0.15)
				)
				(justify mirror)
			)
		)
		(property "Tolerance" "1%"
			(at 451.2 284.69 0)
			(layer "B.Fab")
			(hide yes)
			(effects
				(font
					(size 1 1)
					(thickness 0.15)
				)
				(justify mirror)
			)
		)
		(property "Val" "10k"
			(at 451.2 284.69 0)
			(layer "B.Fab")
			(hide yes)
			(effects
				(font
					(size 1 1)
					(thickness 0.15)
				)
				(justify mirror)
			)
		)
		(sheetname "/WiFi_Bluetooth/")
		(sheetfile "wifi_bt.kicad_sch")
		(attr smd)
		(fp_rect
			(start -0.925 0.47)
			(end 0.925 -0.47)
			(stroke
				(width 0.05)
				(type default)
			)
			(fill no)
			(layer "B.CrtYd")
		)
		(fp_rect
			(start -0.5 0.25)
			(end 0.5 -0.25)
			(stroke
				(width 0.15)
				(type solid)
			)
			(fill no)
			(layer "B.Fab")
		)
		(fp_text user "${REFERENCE}"
			(at -0.95 -3.168 0)
			(layer "B.Fab")
			(effects
				(font
					(size 0.7 0.7)
					(thickness 0.15)
				)
				(justify left bottom mirror)
			)
		)
		(fp_text user "Author: Antmicro"
			(at -0.95 -4.169 0)
			(layer "B.Fab")
			(effects
				(font
					(size 0.7 0.7)
					(thickness 0.15)
				)
				(justify left bottom mirror)
			)
		)
		(fp_text user "License: Apache-2.0"
			(at -0.95 -5.169 0)
			(layer "B.Fab")
			(effects
				(font
					(size 0.7 0.7)
					(thickness 0.15)
				)
				(justify left bottom mirror)
			)
		)
		(pad "1" smd roundrect
			(at -0.48 0 180)
			(size 0.59 0.64)
			(layers "B.Cu" "B.Mask" "B.Paste")
			(roundrect_rratio 0.25)
			(net 417 "GND")
			(pintype "passive")
		)
		(pad "2" smd roundrect
			(at 0.48 0 180)
			(size 0.59 0.64)
			(layers "B.Cu" "B.Mask" "B.Paste")
			(roundrect_rratio 0.25)
			(net 421 "/WiFi_Bluetooth/STRAP_0")
			(pintype "passive")
		)
	)
	(footprint "antmicro-footprints:Fiducial_1mm_Mask2mm"
		(layer "B.Cu")
		(at 224.7 117.1 180)
		(descr "Circular Fiducial, 1mm bare copper, 3mm soldermask opening")
		(tags "fiducial")
		(property "Reference" "FD4"
			(at 0 1.4 0)
			(layer "B.SilkS")
			(hide yes)
			(effects
				(font
					(size 0.7 0.7)
					(thickness 0.15)
				)
				(justify left bottom mirror)
			)
		)
		(property "Value" "Fiducial_1mm_Mask2mm"
			(at 0 -2.2 0)
			(layer "B.Fab")
			(hide yes)
			(effects
				(font
					(size 0.7 0.7)
					(thickness 0.15)
				)
				(justify left bottom mirror)
			)
		)
		(property "Description" "Fiducial mask "
			(at 0 0 180)
			(layer "F.Fab")
			(hide yes)
			(effects
				(font
					(size 1.27 1.27)
					(thickness 0.15)
				)
			)
		)
		(property "Author" "Antmicro"
			(at 449.4 234.2 0)
			(layer "B.Fab")
			(hide yes)
			(effects
				(font
					(size 1 1)
					(thickness 0.15)
				)
				(justify mirror)
			)
		)
		(property "License" "Apache-2.0"
			(at 449.4 234.2 0)
			(layer "B.Fab")
			(hide yes)
			(effects
				(font
					(size 1 1)
					(thickness 0.15)
				)
				(justify mirror)
			)
		)
		(property "exclude_from_bom" ""
			(at 449.4 234.2 0)
			(layer "B.Fab")
			(hide yes)
			(effects
				(font
					(size 1 1)
					(thickness 0.15)
				)
				(justify mirror)
			)
		)
		(sheetfile "polarfire-som.kicad_sch")
		(attr board_only exclude_from_pos_files exclude_from_bom)
		(fp_circle
			(center 0 0)
			(end 1.24 0)
			(stroke
				(width 0.05)
				(type solid)
			)
			(fill no)
			(layer "B.CrtYd")
		)
		(fp_circle
			(center 0 0)
			(end 0.999 0)
			(stroke
				(width 0.15)
				(type solid)
			)
			(fill no)
			(layer "B.Fab")
		)
		(fp_text user "${REFERENCE}"
			(at -1.25 -4.603 0)
			(layer "B.Fab")
			(effects
				(font
					(size 0.7 0.7)
					(thickness 0.15)
				)
				(justify left bottom mirror)
			)
		)
		(fp_text user "Author: Antmicro"
			(at -1.25 -5.803 0)
			(layer "B.Fab")
			(effects
				(font
					(size 0.7 0.7)
					(thickness 0.15)
				)
				(justify left bottom mirror)
			)
		)
		(fp_text user "License: Apache-2.0"
			(at -1.25 -7.003 0)
			(layer "B.Fab")
			(effects
				(font
					(size 0.7 0.7)
					(thickness 0.15)
				)
				(justify left bottom mirror)
			)
		)
		(pad "" smd circle
			(at 0 0 180)
			(size 1 1)
			(layers "B.Cu" "B.Mask")
			(solder_mask_margin 0.5)
			(clearance 0.5)
		)
	)
	(footprint "antmicro-footprints:C_0402_1005Metric"
		(layer "B.Cu")
		(at 175.7 148.4 90)
		(descr "Capacitor SMD 0402")
		(tags "capacitor SMD 0402")
		(property "Reference" "C83"
			(at -4.15 0.25 90)
			(layer "B.SilkS")
			(effects
				(font
					(size 0.7 0.7)
					(thickness 0.15)
				)
				(justify right bottom mirror)
			)
		)
		(property "Value" "C_100n_0402"
			(at -1.022927 -2.155213 90)
			(layer "B.Fab")
			(hide yes)
			(effects
				(font
					(size 0.7 0.7)
					(thickness 0.15)
				)
				(justify right bottom mirror)
			)
		)
		(property "Datasheet" "https://www.murata.com/products/productdetail?partno=GRM155R61H104KE14%23"
			(at 0 0 90)
			(layer "F.Fab")
			(hide yes)
			(effects
				(font
					(size 1.27 1.27)
					(thickness 0.15)
				)
			)
		)
		(property "Description" "SMD Multilayer Ceramic Capacitor, 0.1 µF, 50 V, 0402 [1005 Metric], ± 10%, X5R, GRM Series"
			(at 0 0 90)
			(layer "F.Fab")
			(hide yes)
			(effects
				(font
					(size 1.27 1.27)
					(thickness 0.15)
				)
			)
		)
		(property "Author" "Antmicro"
			(at 324.1 -27.3 0)
			(layer "B.Fab")
			(hide yes)
			(effects
				(font
					(size 1 1)
					(thickness 0.15)
				)
				(justify mirror)
			)
		)
		(property "Dielectric" "X5R"
			(at 324.1 -27.3 0)
			(layer "B.Fab")
			(hide yes)
			(effects
				(font
					(size 1 1)
					(thickness 0.15)
				)
				(justify mirror)
			)
		)
		(property "License" "Apache-2.0"
			(at 324.1 -27.3 0)
			(layer "B.Fab")
			(hide yes)
			(effects
				(font
					(size 1 1)
					(thickness 0.15)
				)
				(justify mirror)
			)
		)
		(property "MPN" "GRM155R61H104KE14D"
			(at 324.1 -27.3 0)
			(layer "B.Fab")
			(hide yes)
			(effects
				(font
					(size 1 1)
					(thickness 0.15)
				)
				(justify mirror)
			)
		)
		(property "Manufacturer" "Murata"
			(at 324.1 -27.3 0)
			(layer "B.Fab")
			(hide yes)
			(effects
				(font
					(size 1 1)
					(thickness 0.15)
				)
				(justify mirror)
			)
		)
		(property "Public" ""
			(at 324.1 -27.3 0)
			(layer "B.Fab")
			(hide yes)
			(effects
				(font
					(size 1 1)
					(thickness 0.15)
				)
				(justify mirror)
			)
		)
		(property "Val" "100n"
			(at 324.1 -27.3 0)
			(layer "B.Fab")
			(hide yes)
			(effects
				(font
					(size 1 1)
					(thickness 0.15)
				)
				(justify mirror)
			)
		)
		(property "Voltage" "50V"
			(at 324.1 -27.3 0)
			(layer "B.Fab")
			(hide yes)
			(effects
				(font
					(size 1 1)
					(thickness 0.15)
				)
				(justify mirror)
			)
		)
		(sheetname "/Supply/")
		(sheetfile "supply.kicad_sch")
		(attr smd)
		(fp_rect
			(start -0.925 0.47)
			(end 0.925 -0.47)
			(stroke
				(width 0.05)
				(type default)
			)
			(fill no)
			(layer "B.CrtYd")
		)
		(fp_line
			(start 0.504 -0.248)
			(end -0.494 -0.248)
			(stroke
				(width 0.15)
				(type solid)
			)
			(layer "B.Fab")
		)
		(fp_line
			(start -0.494 -0.248)
			(end -0.494 0.25)
			(stroke
				(width 0.15)
				(type solid)
			)
			(layer "B.Fab")
		)
		(fp_line
			(start 0.504 0.25)
			(end 0.504 -0.248)
			(stroke
				(width 0.15)
				(type solid)
			)
			(layer "B.Fab")
		)
		(fp_line
			(start -0.494 0.25)
			(end 0.504 0.25)
			(stroke
				(width 0.15)
				(type solid)
			)
			(layer "B.Fab")
		)
		(fp_text user "${REFERENCE}"
			(at -0.939 -4.599 270)
			(layer "B.Fab")
			(effects
				(font
					(size 0.7 0.7)
					(thickness 0.15)
				)
				(justify left bottom mirror)
			)
		)
		(fp_text user "License: Apache-2.0"
			(at -0.939 -5.799 270)
			(layer "B.Fab")
			(effects
				(font
					(size 0.7 0.7)
					(thickness 0.15)
				)
				(justify left bottom mirror)
			)
		)
		(fp_text user "Author: Antmicro"
			(at -0.939 -3.399 270)
			(layer "B.Fab")
			(effects
				(font
					(size 0.7 0.7)
					(thickness 0.15)
				)
				(justify left bottom mirror)
			)
		)
		(pad "1" smd roundrect
			(at -0.48 0 90)
			(size 0.59 0.64)
			(layers "B.Cu" "B.Mask" "B.Paste")
			(roundrect_rratio 0.25)
			(net 417 "GND")
			(pintype "passive")
		)
		(pad "2" smd roundrect
			(at 0.48 0 90)
			(size 0.59 0.64)
			(layers "B.Cu" "B.Mask" "B.Paste")
			(roundrect_rratio 0.25)
			(net 649 "VDD")
			(pintype "passive")
		)
	)
	(footprint "antmicro-footprints:C_0402_1005Metric"
		(layer "B.Cu")
		(at 175.475 140.9675 90)
		(descr "Capacitor SMD 0402")
		(tags "capacitor SMD 0402")
		(property "Reference" "C106"
			(at 0.7975 0.255 270)
			(layer "B.SilkS")
			(effects
				(font
					(size 0.7 0.7)
					(thickness 0.15)
				)
				(justify right bottom mirror)
			)
		)
		(property "Value" "C_22u_0402"
			(at -1.022927 -2.155213 90)
			(layer "B.Fab")
			(hide yes)
			(effects
				(font
					(size 0.7 0.7)
					(thickness 0.15)
				)
				(justify right bottom mirror)
			)
		)
		(property "Datasheet" "https://www.murata.com/products/productdetail?partno=GRM158R60J226ME01%23"
			(at 0 0 90)
			(layer "F.Fab")
			(hide yes)
			(effects
				(font
					(size 1.27 1.27)
					(thickness 0.15)
				)
			)
		)
		(property "Description" "SMD Multilayer Ceramic Capacitor, 22 uF, 4 V, 0402 [1005 Metric], X6S"
			(at 0 0 90)
			(layer "F.Fab")
			(hide yes)
			(effects
				(font
					(size 1.27 1.27)
					(thickness 0.15)
				)
			)
		)
		(property "Author" "Antmicro"
			(at 316.4425 -34.5075 0)
			(layer "B.Fab")
			(hide yes)
			(effects
				(font
					(size 1 1)
					(thickness 0.15)
				)
				(justify mirror)
			)
		)
		(property "Dielectric" ""
			(at 316.4425 -34.5075 0)
			(layer "B.Fab")
			(hide yes)
			(effects
				(font
					(size 1 1)
					(thickness 0.15)
				)
				(justify mirror)
			)
		)
		(property "License" "Apache-2.0"
			(at 316.4425 -34.5075 0)
			(layer "B.Fab")
			(hide yes)
			(effects
				(font
					(size 1 1)
					(thickness 0.15)
				)
				(justify mirror)
			)
		)
		(property "MPN" "GRM158R60J226ME01D"
			(at 316.4425 -34.5075 0)
			(layer "B.Fab")
			(hide yes)
			(effects
				(font
					(size 1 1)
					(thickness 0.15)
				)
				(justify mirror)
			)
		)
		(property "Manufacturer" "Murata"
			(at 316.4425 -34.5075 0)
			(layer "B.Fab")
			(hide yes)
			(effects
				(font
					(size 1 1)
					(thickness 0.15)
				)
				(justify mirror)
			)
		)
		(property "Public" ""
			(at 316.4425 -34.5075 0)
			(layer "B.Fab")
			(hide yes)
			(effects
				(font
					(size 1 1)
					(thickness 0.15)
				)
				(justify mirror)
			)
		)
		(property "Val" "22u"
			(at 316.4425 -34.5075 0)
			(layer "B.Fab")
			(hide yes)
			(effects
				(font
					(size 1 1)
					(thickness 0.15)
				)
				(justify mirror)
			)
		)
		(property "Voltage" ""
			(at 316.4425 -34.5075 0)
			(layer "B.Fab")
			(hide yes)
			(effects
				(font
					(size 1 1)
					(thickness 0.15)
				)
				(justify mirror)
			)
		)
		(sheetname "/Supply/")
		(sheetfile "supply.kicad_sch")
		(attr smd)
		(fp_rect
			(start -0.925 0.47)
			(end 0.925 -0.47)
			(stroke
				(width 0.05)
				(type default)
			)
			(fill no)
			(layer "B.CrtYd")
		)
		(fp_line
			(start 0.504 -0.248)
			(end -0.494 -0.248)
			(stroke
				(width 0.15)
				(type solid)
			)
			(layer "B.Fab")
		)
		(fp_line
			(start -0.494 -0.248)
			(end -0.494 0.25)
			(stroke
				(width 0.15)
				(type solid)
			)
			(layer "B.Fab")
		)
		(fp_line
			(start 0.504 0.25)
			(end 0.504 -0.248)
			(stroke
				(width 0.15)
				(type solid)
			)
			(layer "B.Fab")
		)
		(fp_line
			(start -0.494 0.25)
			(end 0.504 0.25)
			(stroke
				(width 0.15)
				(type solid)
			)
			(layer "B.Fab")
		)
		(fp_text user "License: Apache-2.0"
			(at -0.939 -5.799 270)
			(layer "B.Fab")
			(effects
				(font
					(size 0.7 0.7)
					(thickness 0.15)
				)
				(justify left bottom mirror)
			)
		)
		(fp_text user "${REFERENCE}"
			(at -0.939 -4.599 270)
			(layer "B.Fab")
			(effects
				(font
					(size 0.7 0.7)
					(thickness 0.15)
				)
				(justify left bottom mirror)
			)
		)
		(fp_text user "Author: Antmicro"
			(at -0.939 -3.399 270)
			(layer "B.Fab")
			(effects
				(font
					(size 0.7 0.7)
					(thickness 0.15)
				)
				(justify left bottom mirror)
			)
		)
		(pad "1" smd roundrect
			(at -0.48 0 90)
			(size 0.59 0.64)
			(layers "B.Cu" "B.Mask" "B.Paste")
			(roundrect_rratio 0.25)
			(net 417 "GND")
			(pintype "passive")
		)
		(pad "2" smd roundrect
			(at 0.48 0 90)
			(size 0.59 0.64)
			(layers "B.Cu" "B.Mask" "B.Paste")
			(roundrect_rratio 0.25)
			(net 209 "/Supply/SENSE1_P")
			(pintype "passive")
		)
	)
	(footprint "antmicro-footprints:C_0402_1005Metric"
		(layer "B.Cu")
		(at 178.8 132.1925 180)
		(descr "Capacitor SMD 0402")
		(tags "capacitor SMD 0402")
		(property "Reference" "C265"
			(at -1.45 0.6125 0)
			(layer "B.SilkS")
			(effects
				(font
					(size 0.7 0.7)
					(thickness 0.15)
				)
				(justify left bottom mirror)
			)
		)
		(property "Value" "C_10u_0402"
			(at -1.022927 -2.155213 0)
			(layer "B.Fab")
			(hide yes)
			(effects
				(font
					(size 0.7 0.7)
					(thickness 0.15)
				)
				(justify left bottom mirror)
			)
		)
		(property "Datasheet" "https://www.yageo.com/en/Chart/Download/pdf/CC0402MRX5R5BB106"
			(at 0 0 180)
			(layer "F.Fab")
			(hide yes)
			(effects
				(font
					(size 1.27 1.27)
					(thickness 0.15)
				)
			)
		)
		(property "Description" "SMD Multilayer Ceramic Capacitor, 10 µF, 6.3 V, 0402 [1005 Metric], ± 20%, X5R, CC Series"
			(at 0 0 180)
			(layer "F.Fab")
			(hide yes)
			(effects
				(font
					(size 1.27 1.27)
					(thickness 0.15)
				)
			)
		)
		(property "Author" "Antmicro"
			(at 357.6 264.385 0)
			(layer "B.Fab")
			(hide yes)
			(effects
				(font
					(size 1 1)
					(thickness 0.15)
				)
				(justify mirror)
			)
		)
		(property "Dielectric" ""
			(at 357.6 264.385 0)
			(layer "B.Fab")
			(hide yes)
			(effects
				(font
					(size 1 1)
					(thickness 0.15)
				)
				(justify mirror)
			)
		)
		(property "License" "Apache-2.0"
			(at 357.6 264.385 0)
			(layer "B.Fab")
			(hide yes)
			(effects
				(font
					(size 1 1)
					(thickness 0.15)
				)
				(justify mirror)
			)
		)
		(property "MPN" "CC0402MRX5R5BB106"
			(at 357.6 264.385 0)
			(layer "B.Fab")
			(hide yes)
			(effects
				(font
					(size 1 1)
					(thickness 0.15)
				)
				(justify mirror)
			)
		)
		(property "Manufacturer" "YAGEO"
			(at 357.6 264.385 0)
			(layer "B.Fab")
			(hide yes)
			(effects
				(font
					(size 1 1)
					(thickness 0.15)
				)
				(justify mirror)
			)
		)
		(property "Public" ""
			(at 357.6 264.385 0)
			(layer "B.Fab")
			(hide yes)
			(effects
				(font
					(size 1 1)
					(thickness 0.15)
				)
				(justify mirror)
			)
		)
		(property "Val" "10u"
			(at 357.6 264.385 0)
			(layer "B.Fab")
			(hide yes)
			(effects
				(font
					(size 1 1)
					(thickness 0.15)
				)
				(justify mirror)
			)
		)
		(property "Voltage" ""
			(at 357.6 264.385 0)
			(layer "B.Fab")
			(hide yes)
			(effects
				(font
					(size 1 1)
					(thickness 0.15)
				)
				(justify mirror)
			)
		)
		(sheetname "/LPDDR4/")
		(sheetfile "lpddr.kicad_sch")
		(attr smd)
		(fp_rect
			(start -0.925 0.47)
			(end 0.925 -0.47)
			(stroke
				(width 0.05)
				(type default)
			)
			(fill no)
			(layer "B.CrtYd")
		)
		(fp_line
			(start 0.504 0.25)
			(end 0.504 -0.248)
			(stroke
				(width 0.15)
				(type solid)
			)
			(layer "B.Fab")
		)
		(fp_line
			(start 0.504 -0.248)
			(end -0.494 -0.248)
			(stroke
				(width 0.15)
				(type solid)
			)
			(layer "B.Fab")
		)
		(fp_line
			(start -0.494 0.25)
			(end 0.504 0.25)
			(stroke
				(width 0.15)
				(type solid)
			)
			(layer "B.Fab")
		)
		(fp_line
			(start -0.494 -0.248)
			(end -0.494 0.25)
			(stroke
				(width 0.15)
				(type solid)
			)
			(layer "B.Fab")
		)
		(fp_text user "${REFERENCE}"
			(at -0.939 -4.599 0)
			(layer "B.Fab")
			(effects
				(font
					(size 0.7 0.7)
					(thickness 0.15)
				)
				(justify left bottom mirror)
			)
		)
		(fp_text user "License: Apache-2.0"
			(at -0.939 -5.799 0)
			(layer "B.Fab")
			(effects
				(font
					(size 0.7 0.7)
					(thickness 0.15)
				)
				(justify left bottom mirror)
			)
		)
		(fp_text user "Author: Antmicro"
			(at -0.939 -3.399 0)
			(layer "B.Fab")
			(effects
				(font
					(size 0.7 0.7)
					(thickness 0.15)
				)
				(justify left bottom mirror)
			)
		)
		(pad "1" smd roundrect
			(at -0.48 0 180)
			(size 0.59 0.64)
			(layers "B.Cu" "B.Mask" "B.Paste")
			(roundrect_rratio 0.25)
			(net 417 "GND")
			(pintype "passive")
		)
		(pad "2" smd roundrect
			(at 0.48 0 180)
			(size 0.59 0.64)
			(layers "B.Cu" "B.Mask" "B.Paste")
			(roundrect_rratio 0.25)
			(net 48 "+1V8")
			(pintype "passive")
		)
	)
	(footprint "antmicro-footprints:C_0402_1005Metric"
		(layer "B.Cu")
		(at 215.329 117.56 90)
		(descr "Capacitor SMD 0402")
		(tags "capacitor SMD 0402")
		(property "Reference" "C250"
			(at -3.715 0.471 90)
			(layer "B.SilkS")
			(effects
				(font
					(size 0.7 0.7)
					(thickness 0.15)
				)
				(justify right bottom mirror)
			)
		)
		(property "Value" "C_10u_0402"
			(at -1.022927 -2.155213 90)
			(layer "B.Fab")
			(hide yes)
			(effects
				(font
					(size 0.7 0.7)
					(thickness 0.15)
				)
				(justify right bottom mirror)
			)
		)
		(property "Datasheet" "https://www.yageo.com/en/Chart/Download/pdf/CC0402MRX5R5BB106"
			(at 0 0 90)
			(layer "F.Fab")
			(hide yes)
			(effects
				(font
					(size 1.27 1.27)
					(thickness 0.15)
				)
			)
		)
		(property "Description" "SMD Multilayer Ceramic Capacitor, 10 µF, 6.3 V, 0402 [1005 Metric], ± 20%, X5R, CC Series"
			(at 0 0 90)
			(layer "F.Fab")
			(hide yes)
			(effects
				(font
					(size 1.27 1.27)
					(thickness 0.15)
				)
			)
		)
		(property "Author" "Antmicro"
			(at 332.889 -97.769 0)
			(layer "B.Fab")
			(hide yes)
			(effects
				(font
					(size 1 1)
					(thickness 0.15)
				)
				(justify mirror)
			)
		)
		(property "Dielectric" ""
			(at 332.889 -97.769 0)
			(layer "B.Fab")
			(hide yes)
			(effects
				(font
					(size 1 1)
					(thickness 0.15)
				)
				(justify mirror)
			)
		)
		(property "License" "Apache-2.0"
			(at 332.889 -97.769 0)
			(layer "B.Fab")
			(hide yes)
			(effects
				(font
					(size 1 1)
					(thickness 0.15)
				)
				(justify mirror)
			)
		)
		(property "MPN" "CC0402MRX5R5BB106"
			(at 332.889 -97.769 0)
			(layer "B.Fab")
			(hide yes)
			(effects
				(font
					(size 1 1)
					(thickness 0.15)
				)
				(justify mirror)
			)
		)
		(property "Manufacturer" "YAGEO"
			(at 332.889 -97.769 0)
			(layer "B.Fab")
			(hide yes)
			(effects
				(font
					(size 1 1)
					(thickness 0.15)
				)
				(justify mirror)
			)
		)
		(property "Public" ""
			(at 332.889 -97.769 0)
			(layer "B.Fab")
			(hide yes)
			(effects
				(font
					(size 1 1)
					(thickness 0.15)
				)
				(justify mirror)
			)
		)
		(property "Val" "10u"
			(at 332.889 -97.769 0)
			(layer "B.Fab")
			(hide yes)
			(effects
				(font
					(size 1 1)
					(thickness 0.15)
				)
				(justify mirror)
			)
		)
		(property "Voltage" ""
			(at 332.889 -97.769 0)
			(layer "B.Fab")
			(hide yes)
			(effects
				(font
					(size 1 1)
					(thickness 0.15)
				)
				(justify mirror)
			)
		)
		(sheetname "/Ethernet/")
		(sheetfile "ethernet.kicad_sch")
		(attr smd)
		(fp_rect
			(start -0.925 0.47)
			(end 0.925 -0.47)
			(stroke
				(width 0.05)
				(type default)
			)
			(fill no)
			(layer "B.CrtYd")
		)
		(fp_line
			(start 0.504 -0.248)
			(end -0.494 -0.248)
			(stroke
				(width 0.15)
				(type solid)
			)
			(layer "B.Fab")
		)
		(fp_line
			(start -0.494 -0.248)
			(end -0.494 0.25)
			(stroke
				(width 0.15)
				(type solid)
			)
			(layer "B.Fab")
		)
		(fp_line
			(start 0.504 0.25)
			(end 0.504 -0.248)
			(stroke
				(width 0.15)
				(type solid)
			)
			(layer "B.Fab")
		)
		(fp_line
			(start -0.494 0.25)
			(end 0.504 0.25)
			(stroke
				(width 0.15)
				(type solid)
			)
			(layer "B.Fab")
		)
		(fp_text user "Author: Antmicro"
			(at -0.939 -3.399 270)
			(layer "B.Fab")
			(effects
				(font
					(size 0.7 0.7)
					(thickness 0.15)
				)
				(justify left bottom mirror)
			)
		)
		(fp_text user "License: Apache-2.0"
			(at -0.939 -5.799 270)
			(layer "B.Fab")
			(effects
				(font
					(size 0.7 0.7)
					(thickness 0.15)
				)
				(justify left bottom mirror)
			)
		)
		(fp_text user "${REFERENCE}"
			(at -0.939 -4.599 270)
			(layer "B.Fab")
			(effects
				(font
					(size 0.7 0.7)
					(thickness 0.15)
				)
				(justify left bottom mirror)
			)
		)
		(pad "1" smd roundrect
			(at -0.48 0 90)
			(size 0.59 0.64)
			(layers "B.Cu" "B.Mask" "B.Paste")
			(roundrect_rratio 0.25)
			(net 417 "GND")
			(pintype "passive")
		)
		(pad "2" smd roundrect
			(at 0.48 0 90)
			(size 0.59 0.64)
			(layers "B.Cu" "B.Mask" "B.Paste")
			(roundrect_rratio 0.25)
			(net 50 "+3V3")
			(pintype "passive")
		)
	)
	(footprint "antmicro-footprints:XSON-8_1x1.95mm_P0.5mm"
		(layer "B.Cu")
		(at 222.77 141.61)
		(property "Reference" "U25"
			(at 1.81 -0.63 0)
			(layer "B.SilkS")
			(effects
				(font
					(size 0.7 0.7)
					(thickness 0.15)
				)
				(justify right bottom mirror)
			)
		)
		(property "Value" "NTS0102_XSON"
			(at 0 -2.2 0)
			(layer "B.Fab")
			(hide yes)
			(effects
				(font
					(size 0.7 0.7)
					(thickness 0.15)
				)
				(justify right bottom mirror)
			)
		)
		(property "Datasheet" "http://www.farnell.com/datasheets/1760723.pdf"
			(at 0 0 0)
			(layer "F.Fab")
			(hide yes)
			(effects
				(font
					(size 1.27 1.27)
					(thickness 0.15)
				)
			)
		)
		(property "Description" "Transceiver, 1.65 V to 3.6 V, XSON-8"
			(at 0 0 0)
			(layer "F.Fab")
			(hide yes)
			(effects
				(font
					(size 1.27 1.27)
					(thickness 0.15)
				)
			)
		)
		(property "Author" "Antmicro"
			(at 0 0 0)
			(layer "B.Fab")
			(hide yes)
			(effects
				(font
					(size 1 1)
					(thickness 0.15)
				)
				(justify mirror)
			)
		)
		(property "License" "Apache-2.0"
			(at 0 0 0)
			(layer "B.Fab")
			(hide yes)
			(effects
				(font
					(size 1 1)
					(thickness 0.15)
				)
				(justify mirror)
			)
		)
		(property "MPN" "NTS0102GT"
			(at 0 0 0)
			(layer "B.Fab")
			(hide yes)
			(effects
				(font
					(size 1 1)
					(thickness 0.15)
				)
				(justify mirror)
			)
		)
		(property "Manufacturer" "NXP"
			(at 0 0 0)
			(layer "B.Fab")
			(hide yes)
			(effects
				(font
					(size 1 1)
					(thickness 0.15)
				)
				(justify mirror)
			)
		)
		(sheetname "/FPGA GPIO/")
		(sheetfile "fpga-gpio.kicad_sch")
		(attr smd)
		(fp_line
			(start -0.5 1.1)
			(end 0.5 1.1)
			(stroke
				(width 0.15)
				(type solid)
			)
			(layer "B.SilkS")
		)
		(fp_line
			(start 0.5 -1.1)
			(end -0.5 -1.1)
			(stroke
				(width 0.15)
				(type solid)
			)
			(layer "B.SilkS")
		)
		(fp_circle
			(center -0.75 1.1)
			(end -0.701 1.1)
			(stroke
				(width 0.15)
				(type solid)
			)
			(fill no)
			(layer "B.SilkS")
		)
		(fp_rect
			(start -0.8 1.2)
			(end 0.8 -1.2)
			(stroke
				(width 0.05)
				(type solid)
			)
			(fill no)
			(layer "B.CrtYd")
		)
		(fp_line
			(start -0.5305 -1)
			(end -0.5305 1.001)
			(stroke
				(width 0.15)
				(type solid)
			)
			(layer "B.Fab")
		)
		(fp_line
			(start -0.5305 1.001)
			(end 0.5305 1.001)
			(stroke
				(width 0.15)
				(type solid)
			)
			(layer "B.Fab")
		)
		(fp_line
			(start 0.5305 -1)
			(end -0.5305 -1)
			(stroke
				(width 0.15)
				(type solid)
			)
			(layer "B.Fab")
		)
		(fp_line
			(start 0.5305 1.001)
			(end 0.5305 -1)
			(stroke
				(width 0.15)
				(type solid)
			)
			(layer "B.Fab")
		)
		(fp_text user "${REFERENCE}"
			(at -0.527 -5.905 180)
			(layer "B.Fab")
			(effects
				(font
					(size 0.7 0.7)
					(thickness 0.15)
				)
				(justify left bottom mirror)
			)
		)
		(fp_text user "License: Apache-2.0"
			(at -0.527 -8.306 180)
			(layer "B.Fab")
			(effects
				(font
					(size 0.7 0.7)
					(thickness 0.15)
				)
				(justify left bottom mirror)
			)
		)
		(fp_text user "Author: Antmicro"
			(at -0.527 -7.105 180)
			(layer "B.Fab")
			(effects
				(font
					(size 0.7 0.7)
					(thickness 0.15)
				)
				(justify left bottom mirror)
			)
		)
		(pad "1" smd roundrect
			(at -0.45 0.75 180)
			(size 0.6 0.3)
			(layers "B.Cu" "B.Mask" "B.Paste")
			(roundrect_rratio 0.25)
			(net 226 "/FPGA GPIO/WiFi.DAT1")
			(pinfunction "B_{2}")
			(pintype "bidirectional")
		)
		(pad "2" smd roundrect
			(at -0.45 0.25 180)
			(size 0.6 0.25)
			(layers "B.Cu" "B.Mask" "B.Paste")
			(roundrect_rratio 0.25)
			(net 417 "GND")
			(pinfunction "GND")
			(pintype "power_in")
		)
		(pad "3" smd roundrect
			(at -0.45 -0.25 180)
			(size 0.6 0.25)
			(layers "B.Cu" "B.Mask" "B.Paste")
			(roundrect_rratio 0.25)
			(net 649 "VDD")
			(pinfunction "VCC_{A}")
			(pintype "power_in")
		)
		(pad "4" smd roundrect
			(at -0.45 -0.75 180)
			(size 0.6 0.3)
			(layers "B.Cu" "B.Mask" "B.Paste")
			(roundrect_rratio 0.25)
			(net 355 "/FPGA GPIO/WiFi_DATA_1")
			(pinfunction "A_{2}")
			(pintype "bidirectional")
		)
		(pad "5" smd roundrect
			(at 0.45 -0.75 180)
			(size 0.6 0.3)
			(layers "B.Cu" "B.Mask" "B.Paste")
			(roundrect_rratio 0.25)
			(net 358 "/FPGA GPIO/WiFi_CMD")
			(pinfunction "A_{1}")
			(pintype "bidirectional")
		)
		(pad "6" smd roundrect
			(at 0.45 -0.25 180)
			(size 0.6 0.25)
			(layers "B.Cu" "B.Mask" "B.Paste")
			(roundrect_rratio 0.25)
			(net 649 "VDD")
			(pinfunction "OE")
			(pintype "input")
		)
		(pad "7" smd roundrect
			(at 0.45 0.25 180)
			(size 0.6 0.25)
			(layers "B.Cu" "B.Mask" "B.Paste")
			(roundrect_rratio 0.25)
			(net 50 "+3V3")
			(pinfunction "VCC_{B}")
			(pintype "power_in")
		)
		(pad "8" smd roundrect
			(at 0.45 0.75 180)
			(size 0.6 0.3)
			(layers "B.Cu" "B.Mask" "B.Paste")
			(roundrect_rratio 0.25)
			(net 231 "/FPGA GPIO/WiFi.CMD")
			(pinfunction "B_{1}")
			(pintype "bidirectional")
		)
	)
	(footprint "antmicro-footprints:C_0402_1005Metric"
		(layer "B.Cu")
		(at 183.3 152.025 90)
		(descr "Capacitor SMD 0402")
		(tags "capacitor SMD 0402")
		(property "Reference" "C111"
			(at 0.675 0.35 90)
			(layer "B.SilkS")
			(effects
				(font
					(size 0.7 0.7)
					(thickness 0.15)
				)
				(justify right bottom mirror)
			)
		)
		(property "Value" "C_22p_0402"
			(at -1.022927 -2.155213 90)
			(layer "B.Fab")
			(hide yes)
			(effects
				(font
					(size 0.7 0.7)
					(thickness 0.15)
				)
				(justify right bottom mirror)
			)
		)
		(property "Datasheet" "https://www.yageo.com/en/Chart/Download/pdf/CC0402JRNPO9BN220"
			(at 0 0 90)
			(layer "F.Fab")
			(hide yes)
			(effects
				(font
					(size 1.27 1.27)
					(thickness 0.15)
				)
			)
		)
		(property "Description" "SMD Multilayer Ceramic Capacitor, 22 pF, 50 V, 0402 [1005 Metric], ± 5%, C0G / NP0, CC Series"
			(at 0 0 90)
			(layer "F.Fab")
			(hide yes)
			(effects
				(font
					(size 1.27 1.27)
					(thickness 0.15)
				)
			)
		)
		(property "Author" "Antmicro"
			(at 335.325 -31.275 0)
			(layer "B.Fab")
			(hide yes)
			(effects
				(font
					(size 1 1)
					(thickness 0.15)
				)
				(justify mirror)
			)
		)
		(property "Dielectric" ""
			(at 335.325 -31.275 0)
			(layer "B.Fab")
			(hide yes)
			(effects
				(font
					(size 1 1)
					(thickness 0.15)
				)
				(justify mirror)
			)
		)
		(property "License" "Apache-2.0"
			(at 335.325 -31.275 0)
			(layer "B.Fab")
			(hide yes)
			(effects
				(font
					(size 1 1)
					(thickness 0.15)
				)
				(justify mirror)
			)
		)
		(property "MPN" "CC0402JRNPO9BN220"
			(at 335.325 -31.275 0)
			(layer "B.Fab")
			(hide yes)
			(effects
				(font
					(size 1 1)
					(thickness 0.15)
				)
				(justify mirror)
			)
		)
		(property "Manufacturer" "YAGEO"
			(at 335.325 -31.275 0)
			(layer "B.Fab")
			(hide yes)
			(effects
				(font
					(size 1 1)
					(thickness 0.15)
				)
				(justify mirror)
			)
		)
		(property "Public" ""
			(at 335.325 -31.275 0)
			(layer "B.Fab")
			(hide yes)
			(effects
				(font
					(size 1 1)
					(thickness 0.15)
				)
				(justify mirror)
			)
		)
		(property "Val" "22p"
			(at 335.325 -31.275 0)
			(layer "B.Fab")
			(hide yes)
			(effects
				(font
					(size 1 1)
					(thickness 0.15)
				)
				(justify mirror)
			)
		)
		(property "Voltage" ""
			(at 335.325 -31.275 0)
			(layer "B.Fab")
			(hide yes)
			(effects
				(font
					(size 1 1)
					(thickness 0.15)
				)
				(justify mirror)
			)
		)
		(sheetname "/Supply/")
		(sheetfile "supply.kicad_sch")
		(attr smd)
		(fp_rect
			(start -0.925 0.47)
			(end 0.925 -0.47)
			(stroke
				(width 0.05)
				(type default)
			)
			(fill no)
			(layer "B.CrtYd")
		)
		(fp_line
			(start 0.504 -0.248)
			(end -0.494 -0.248)
			(stroke
				(width 0.15)
				(type solid)
			)
			(layer "B.Fab")
		)
		(fp_line
			(start -0.494 -0.248)
			(end -0.494 0.25)
			(stroke
				(width 0.15)
				(type solid)
			)
			(layer "B.Fab")
		)
		(fp_line
			(start 0.504 0.25)
			(end 0.504 -0.248)
			(stroke
				(width 0.15)
				(type solid)
			)
			(layer "B.Fab")
		)
		(fp_line
			(start -0.494 0.25)
			(end 0.504 0.25)
			(stroke
				(width 0.15)
				(type solid)
			)
			(layer "B.Fab")
		)
		(fp_text user "License: Apache-2.0"
			(at -0.939 -5.799 270)
			(layer "B.Fab")
			(effects
				(font
					(size 0.7 0.7)
					(thickness 0.15)
				)
				(justify left bottom mirror)
			)
		)
		(fp_text user "Author: Antmicro"
			(at -0.939 -3.399 270)
			(layer "B.Fab")
			(effects
				(font
					(size 0.7 0.7)
					(thickness 0.15)
				)
				(justify left bottom mirror)
			)
		)
		(fp_text user "${REFERENCE}"
			(at -0.939 -4.599 270)
			(layer "B.Fab")
			(effects
				(font
					(size 0.7 0.7)
					(thickness 0.15)
				)
				(justify left bottom mirror)
			)
		)
		(pad "1" smd roundrect
			(at -0.48 0 90)
			(size 0.59 0.64)
			(layers "B.Cu" "B.Mask" "B.Paste")
			(roundrect_rratio 0.25)
			(net 14 "Net-(C111-Pad1)")
			(pintype "passive")
		)
		(pad "2" smd roundrect
			(at 0.48 0 90)
			(size 0.59 0.64)
			(layers "B.Cu" "B.Mask" "B.Paste")
			(roundrect_rratio 0.25)
			(net 522 "/Supply/1V05_REG")
			(pintype "passive")
		)
	)
	(footprint "antmicro-footprints:C_0402_1005Metric"
		(layer "B.Cu")
		(at 213.861 120.754 180)
		(descr "Capacitor SMD 0402")
		(tags "capacitor SMD 0402")
		(property "Reference" "C255"
			(at -15.389 -13.246 0)
			(layer "B.SilkS")
			(effects
				(font
					(size 0.7 0.7)
					(thickness 0.15)
				)
				(justify left bottom mirror)
			)
		)
		(property "Value" "C_10n_0402"
			(at -1.022927 -2.155213 0)
			(layer "B.Fab")
			(hide yes)
			(effects
				(font
					(size 0.7 0.7)
					(thickness 0.15)
				)
				(justify left bottom mirror)
			)
		)
		(property "Datasheet" "https://www.murata.com/products/productdetail?partno=GRM155R71H103KA88%23"
			(at 0 0 180)
			(layer "F.Fab")
			(hide yes)
			(effects
				(font
					(size 1.27 1.27)
					(thickness 0.15)
				)
			)
		)
		(property "Description" "SMD Multilayer Ceramic Capacitor, 10000 pF, 50 V, 0402 [1005 Metric], ± 10%, X7R, GRM Series"
			(at 0 0 180)
			(layer "F.Fab")
			(hide yes)
			(effects
				(font
					(size 1.27 1.27)
					(thickness 0.15)
				)
			)
		)
		(property "Author" "Antmicro"
			(at 427.722 241.508 0)
			(layer "B.Fab")
			(hide yes)
			(effects
				(font
					(size 1 1)
					(thickness 0.15)
				)
				(justify mirror)
			)
		)
		(property "Dielectric" "X7R"
			(at 427.722 241.508 0)
			(layer "B.Fab")
			(hide yes)
			(effects
				(font
					(size 1 1)
					(thickness 0.15)
				)
				(justify mirror)
			)
		)
		(property "License" "Apache-2.0"
			(at 427.722 241.508 0)
			(layer "B.Fab")
			(hide yes)
			(effects
				(font
					(size 1 1)
					(thickness 0.15)
				)
				(justify mirror)
			)
		)
		(property "MPN" "GRM155R71H103KA88D"
			(at 427.722 241.508 0)
			(layer "B.Fab")
			(hide yes)
			(effects
				(font
					(size 1 1)
					(thickness 0.15)
				)
				(justify mirror)
			)
		)
		(property "Manufacturer" "Murata"
			(at 427.722 241.508 0)
			(layer "B.Fab")
			(hide yes)
			(effects
				(font
					(size 1 1)
					(thickness 0.15)
				)
				(justify mirror)
			)
		)
		(property "Public" ""
			(at 427.722 241.508 0)
			(layer "B.Fab")
			(hide yes)
			(effects
				(font
					(size 1 1)
					(thickness 0.15)
				)
				(justify mirror)
			)
		)
		(property "Val" "10n"
			(at 427.722 241.508 0)
			(layer "B.Fab")
			(hide yes)
			(effects
				(font
					(size 1 1)
					(thickness 0.15)
				)
				(justify mirror)
			)
		)
		(property "Voltage" "50V"
			(at 427.722 241.508 0)
			(layer "B.Fab")
			(hide yes)
			(effects
				(font
					(size 1 1)
					(thickness 0.15)
				)
				(justify mirror)
			)
		)
		(sheetname "/Ethernet/")
		(sheetfile "ethernet.kicad_sch")
		(attr smd)
		(fp_rect
			(start -0.925 0.47)
			(end 0.925 -0.47)
			(stroke
				(width 0.05)
				(type default)
			)
			(fill no)
			(layer "B.CrtYd")
		)
		(fp_line
			(start 0.504 0.25)
			(end 0.504 -0.248)
			(stroke
				(width 0.15)
				(type solid)
			)
			(layer "B.Fab")
		)
		(fp_line
			(start 0.504 -0.248)
			(end -0.494 -0.248)
			(stroke
				(width 0.15)
				(type solid)
			)
			(layer "B.Fab")
		)
		(fp_line
			(start -0.494 0.25)
			(end 0.504 0.25)
			(stroke
				(width 0.15)
				(type solid)
			)
			(layer "B.Fab")
		)
		(fp_line
			(start -0.494 -0.248)
			(end -0.494 0.25)
			(stroke
				(width 0.15)
				(type solid)
			)
			(layer "B.Fab")
		)
		(fp_text user "Author: Antmicro"
			(at -0.939 -3.399 0)
			(layer "B.Fab")
			(effects
				(font
					(size 0.7 0.7)
					(thickness 0.15)
				)
				(justify left bottom mirror)
			)
		)
		(fp_text user "License: Apache-2.0"
			(at -0.939 -5.799 0)
			(layer "B.Fab")
			(effects
				(font
					(size 0.7 0.7)
					(thickness 0.15)
				)
				(justify left bottom mirror)
			)
		)
		(fp_text user "${REFERENCE}"
			(at -0.939 -4.599 0)
			(layer "B.Fab")
			(effects
				(font
					(size 0.7 0.7)
					(thickness 0.15)
				)
				(justify left bottom mirror)
			)
		)
		(pad "1" smd roundrect
			(at -0.48 0 180)
			(size 0.59 0.64)
			(layers "B.Cu" "B.Mask" "B.Paste")
			(roundrect_rratio 0.25)
			(net 417 "GND")
			(pintype "passive")
		)
		(pad "2" smd roundrect
			(at 0.48 0 180)
			(size 0.59 0.64)
			(layers "B.Cu" "B.Mask" "B.Paste")
			(roundrect_rratio 0.25)
			(net 47 "+1V05")
			(pintype "passive")
		)
	)
	(footprint "antmicro-footprints:C_0402_1005Metric"
		(layer "B.Cu")
		(at 198 130.83 90)
		(descr "Capacitor SMD 0402")
		(tags "capacitor SMD 0402")
		(property "Reference" "C232"
			(at 5.18 -9.525 90)
			(layer "B.SilkS")
			(effects
				(font
					(size 0.7 0.7)
					(thickness 0.15)
				)
				(justify right bottom mirror)
			)
		)
		(property "Value" "C_100n_0402"
			(at -1.022927 -2.155213 90)
			(layer "B.Fab")
			(hide yes)
			(effects
				(font
					(size 0.7 0.7)
					(thickness 0.15)
				)
				(justify right bottom mirror)
			)
		)
		(property "Datasheet" "https://www.murata.com/products/productdetail?partno=GRM155R61H104KE14%23"
			(at 0 0 90)
			(layer "F.Fab")
			(hide yes)
			(effects
				(font
					(size 1.27 1.27)
					(thickness 0.15)
				)
			)
		)
		(property "Description" "SMD Multilayer Ceramic Capacitor, 0.1 µF, 50 V, 0402 [1005 Metric], ± 10%, X5R, GRM Series"
			(at 0 0 90)
			(layer "F.Fab")
			(hide yes)
			(effects
				(font
					(size 1.27 1.27)
					(thickness 0.15)
				)
			)
		)
		(property "Author" "Antmicro"
			(at 328.83 -67.17 0)
			(layer "B.Fab")
			(hide yes)
			(effects
				(font
					(size 1 1)
					(thickness 0.15)
				)
				(justify mirror)
			)
		)
		(property "Dielectric" "X5R"
			(at 328.83 -67.17 0)
			(layer "B.Fab")
			(hide yes)
			(effects
				(font
					(size 1 1)
					(thickness 0.15)
				)
				(justify mirror)
			)
		)
		(property "License" "Apache-2.0"
			(at 328.83 -67.17 0)
			(layer "B.Fab")
			(hide yes)
			(effects
				(font
					(size 1 1)
					(thickness 0.15)
				)
				(justify mirror)
			)
		)
		(property "MPN" "GRM155R61H104KE14D"
			(at 328.83 -67.17 0)
			(layer "B.Fab")
			(hide yes)
			(effects
				(font
					(size 1 1)
					(thickness 0.15)
				)
				(justify mirror)
			)
		)
		(property "Manufacturer" "Murata"
			(at 328.83 -67.17 0)
			(layer "B.Fab")
			(hide yes)
			(effects
				(font
					(size 1 1)
					(thickness 0.15)
				)
				(justify mirror)
			)
		)
		(property "Public" ""
			(at 328.83 -67.17 0)
			(layer "B.Fab")
			(hide yes)
			(effects
				(font
					(size 1 1)
					(thickness 0.15)
				)
				(justify mirror)
			)
		)
		(property "Val" "100n"
			(at 328.83 -67.17 0)
			(layer "B.Fab")
			(hide yes)
			(effects
				(font
					(size 1 1)
					(thickness 0.15)
				)
				(justify mirror)
			)
		)
		(property "Voltage" "50V"
			(at 328.83 -67.17 0)
			(layer "B.Fab")
			(hide yes)
			(effects
				(font
					(size 1 1)
					(thickness 0.15)
				)
				(justify mirror)
			)
		)
		(sheetname "/FPGA Supply/")
		(sheetfile "fpga-supply.kicad_sch")
		(attr smd)
		(fp_rect
			(start -0.925 0.47)
			(end 0.925 -0.47)
			(stroke
				(width 0.05)
				(type default)
			)
			(fill no)
			(layer "B.CrtYd")
		)
		(fp_line
			(start 0.504 -0.248)
			(end -0.494 -0.248)
			(stroke
				(width 0.15)
				(type solid)
			)
			(layer "B.Fab")
		)
		(fp_line
			(start -0.494 -0.248)
			(end -0.494 0.25)
			(stroke
				(width 0.15)
				(type solid)
			)
			(layer "B.Fab")
		)
		(fp_line
			(start 0.504 0.25)
			(end 0.504 -0.248)
			(stroke
				(width 0.15)
				(type solid)
			)
			(layer "B.Fab")
		)
		(fp_line
			(start -0.494 0.25)
			(end 0.504 0.25)
			(stroke
				(width 0.15)
				(type solid)
			)
			(layer "B.Fab")
		)
		(fp_text user "License: Apache-2.0"
			(at -0.939 -5.799 270)
			(layer "B.Fab")
			(effects
				(font
					(size 0.7 0.7)
					(thickness 0.15)
				)
				(justify left bottom mirror)
			)
		)
		(fp_text user "Author: Antmicro"
			(at -0.939 -3.399 270)
			(layer "B.Fab")
			(effects
				(font
					(size 0.7 0.7)
					(thickness 0.15)
				)
				(justify left bottom mirror)
			)
		)
		(fp_text user "${REFERENCE}"
			(at -0.939 -4.599 270)
			(layer "B.Fab")
			(effects
				(font
					(size 0.7 0.7)
					(thickness 0.15)
				)
				(justify left bottom mirror)
			)
		)
		(pad "1" smd roundrect
			(at -0.48 0 90)
			(size 0.59 0.64)
			(layers "B.Cu" "B.Mask" "B.Paste")
			(roundrect_rratio 0.25)
			(net 417 "GND")
			(pintype "passive")
		)
		(pad "2" smd roundrect
			(at 0.48 0 90)
			(size 0.59 0.64)
			(layers "B.Cu" "B.Mask" "B.Paste")
			(roundrect_rratio 0.25)
			(net 49 "VDDAUX")
			(pintype "passive")
		)
	)
	(footprint "antmicro-footprints:C_0402_1005Metric"
		(layer "B.Cu")
		(at 181.1 144.0125)
		(descr "Capacitor SMD 0402")
		(tags "capacitor SMD 0402")
		(property "Reference" "C112"
			(at 0.2 1.1175 315)
			(layer "B.SilkS")
			(effects
				(font
					(size 0.7 0.7)
					(thickness 0.15)
				)
				(justify right bottom mirror)
			)
		)
		(property "Value" "C_10u_10V_0402"
			(at -1.022927 -2.155213 0)
			(layer "B.Fab")
			(hide yes)
			(effects
				(font
					(size 0.7 0.7)
					(thickness 0.15)
				)
				(justify right bottom mirror)
			)
		)
		(property "Datasheet" "https://www.murata.com/products/productdetail?partno=GRM155R61A106ME11%23"
			(at 0 0 0)
			(layer "F.Fab")
			(hide yes)
			(effects
				(font
					(size 1.27 1.27)
					(thickness 0.15)
				)
			)
		)
		(property "Description" "Multilayer Ceramic Capacitors MLCC - SMD/SMT 10 uF 10 VDC 20% 0402 X5R"
			(at 0 0 0)
			(layer "F.Fab")
			(hide yes)
			(effects
				(font
					(size 1.27 1.27)
					(thickness 0.15)
				)
			)
		)
		(property "Author" "Antmicro"
			(at 0 0 0)
			(layer "B.Fab")
			(hide yes)
			(effects
				(font
					(size 1 1)
					(thickness 0.15)
				)
				(justify mirror)
			)
		)
		(property "Dielectric" "X5R"
			(at 0 0 0)
			(layer "B.Fab")
			(hide yes)
			(effects
				(font
					(size 1 1)
					(thickness 0.15)
				)
				(justify mirror)
			)
		)
		(property "License" "Apache-2.0"
			(at 0 0 0)
			(layer "B.Fab")
			(hide yes)
			(effects
				(font
					(size 1 1)
					(thickness 0.15)
				)
				(justify mirror)
			)
		)
		(property "MPN" "GRM155R61A106ME11D"
			(at 0 0 0)
			(layer "B.Fab")
			(hide yes)
			(effects
				(font
					(size 1 1)
					(thickness 0.15)
				)
				(justify mirror)
			)
		)
		(property "Manufacturer" "Murata"
			(at 0 0 0)
			(layer "B.Fab")
			(hide yes)
			(effects
				(font
					(size 1 1)
					(thickness 0.15)
				)
				(justify mirror)
			)
		)
		(property "Public" ""
			(at 0 0 0)
			(layer "B.Fab")
			(hide yes)
			(effects
				(font
					(size 1 1)
					(thickness 0.15)
				)
				(justify mirror)
			)
		)
		(property "Val" "10u"
			(at 0 0 0)
			(layer "B.Fab")
			(hide yes)
			(effects
				(font
					(size 1 1)
					(thickness 0.15)
				)
				(justify mirror)
			)
		)
		(property "Voltage" "10V"
			(at 0 0 0)
			(layer "B.Fab")
			(hide yes)
			(effects
				(font
					(size 1 1)
					(thickness 0.15)
				)
				(justify mirror)
			)
		)
		(sheetname "/Supply/")
		(sheetfile "supply.kicad_sch")
		(attr smd)
		(fp_rect
			(start -0.925 0.47)
			(end 0.925 -0.47)
			(stroke
				(width 0.05)
				(type default)
			)
			(fill no)
			(layer "B.CrtYd")
		)
		(fp_line
			(start -0.494 -0.248)
			(end -0.494 0.25)
			(stroke
				(width 0.15)
				(type solid)
			)
			(layer "B.Fab")
		)
		(fp_line
			(start -0.494 0.25)
			(end 0.504 0.25)
			(stroke
				(width 0.15)
				(type solid)
			)
			(layer "B.Fab")
		)
		(fp_line
			(start 0.504 -0.248)
			(end -0.494 -0.248)
			(stroke
				(width 0.15)
				(type solid)
			)
			(layer "B.Fab")
		)
		(fp_line
			(start 0.504 0.25)
			(end 0.504 -0.248)
			(stroke
				(width 0.15)
				(type solid)
			)
			(layer "B.Fab")
		)
		(fp_text user "Author: Antmicro"
			(at -0.939 -3.399 180)
			(layer "B.Fab")
			(effects
				(font
					(size 0.7 0.7)
					(thickness 0.15)
				)
				(justify left bottom mirror)
			)
		)
		(fp_text user "License: Apache-2.0"
			(at -0.939 -5.799 180)
			(layer "B.Fab")
			(effects
				(font
					(size 0.7 0.7)
					(thickness 0.15)
				)
				(justify left bottom mirror)
			)
		)
		(fp_text user "${REFERENCE}"
			(at -0.939 -4.599 180)
			(layer "B.Fab")
			(effects
				(font
					(size 0.7 0.7)
					(thickness 0.15)
				)
				(justify left bottom mirror)
			)
		)
		(pad "1" smd roundrect
			(at -0.48 0)
			(size 0.59 0.64)
			(layers "B.Cu" "B.Mask" "B.Paste")
			(roundrect_rratio 0.25)
			(net 417 "GND")
			(pintype "passive")
		)
		(pad "2" smd roundrect
			(at 0.48 0)
			(size 0.59 0.64)
			(layers "B.Cu" "B.Mask" "B.Paste")
			(roundrect_rratio 0.25)
			(net 634 "Net-(U7-OUT5)")
			(pintype "passive")
		)
	)
	(footprint "antmicro-footprints:C_0402_1005Metric"
		(layer "B.Cu")
		(at 221.9325 147.295 90)
		(descr "Capacitor SMD 0402")
		(tags "capacitor SMD 0402")
		(property "Reference" "C228"
			(at -3.725 0.8975 90)
			(layer "B.SilkS")
			(effects
				(font
					(size 0.7 0.7)
					(thickness 0.15)
				)
				(justify right bottom mirror)
			)
		)
		(property "Value" "C_100n_0402"
			(at -1.022927 -2.155213 90)
			(layer "B.Fab")
			(hide yes)
			(effects
				(font
					(size 0.7 0.7)
					(thickness 0.15)
				)
				(justify right bottom mirror)
			)
		)
		(property "Datasheet" "https://www.murata.com/products/productdetail?partno=GRM155R61H104KE14%23"
			(at 0 0 90)
			(layer "F.Fab")
			(hide yes)
			(effects
				(font
					(size 1.27 1.27)
					(thickness 0.15)
				)
			)
		)
		(property "Description" "SMD Multilayer Ceramic Capacitor, 0.1 µF, 50 V, 0402 [1005 Metric], ± 10%, X5R, GRM Series"
			(at 0 0 90)
			(layer "F.Fab")
			(hide yes)
			(effects
				(font
					(size 1.27 1.27)
					(thickness 0.15)
				)
			)
		)
		(property "Author" "Antmicro"
			(at 369.2275 -74.6375 0)
			(layer "B.Fab")
			(hide yes)
			(effects
				(font
					(size 1 1)
					(thickness 0.15)
				)
				(justify mirror)
			)
		)
		(property "Dielectric" "X5R"
			(at 369.2275 -74.6375 0)
			(layer "B.Fab")
			(hide yes)
			(effects
				(font
					(size 1 1)
					(thickness 0.15)
				)
				(justify mirror)
			)
		)
		(property "License" "Apache-2.0"
			(at 369.2275 -74.6375 0)
			(layer "B.Fab")
			(hide yes)
			(effects
				(font
					(size 1 1)
					(thickness 0.15)
				)
				(justify mirror)
			)
		)
		(property "MPN" "GRM155R61H104KE14D"
			(at 369.2275 -74.6375 0)
			(layer "B.Fab")
			(hide yes)
			(effects
				(font
					(size 1 1)
					(thickness 0.15)
				)
				(justify mirror)
			)
		)
		(property "Manufacturer" "Murata"
			(at 369.2275 -74.6375 0)
			(layer "B.Fab")
			(hide yes)
			(effects
				(font
					(size 1 1)
					(thickness 0.15)
				)
				(justify mirror)
			)
		)
		(property "Public" ""
			(at 369.2275 -74.6375 0)
			(layer "B.Fab")
			(hide yes)
			(effects
				(font
					(size 1 1)
					(thickness 0.15)
				)
				(justify mirror)
			)
		)
		(property "Val" "100n"
			(at 369.2275 -74.6375 0)
			(layer "B.Fab")
			(hide yes)
			(effects
				(font
					(size 1 1)
					(thickness 0.15)
				)
				(justify mirror)
			)
		)
		(property "Voltage" "50V"
			(at 369.2275 -74.6375 0)
			(layer "B.Fab")
			(hide yes)
			(effects
				(font
					(size 1 1)
					(thickness 0.15)
				)
				(justify mirror)
			)
		)
		(sheetname "/WiFi_Bluetooth/")
		(sheetfile "wifi_bt.kicad_sch")
		(attr smd)
		(fp_rect
			(start -0.925 0.47)
			(end 0.925 -0.47)
			(stroke
				(width 0.05)
				(type default)
			)
			(fill no)
			(layer "B.CrtYd")
		)
		(fp_line
			(start 0.504 -0.248)
			(end -0.494 -0.248)
			(stroke
				(width 0.15)
				(type solid)
			)
			(layer "B.Fab")
		)
		(fp_line
			(start -0.494 -0.248)
			(end -0.494 0.25)
			(stroke
				(width 0.15)
				(type solid)
			)
			(layer "B.Fab")
		)
		(fp_line
			(start 0.504 0.25)
			(end 0.504 -0.248)
			(stroke
				(width 0.15)
				(type solid)
			)
			(layer "B.Fab")
		)
		(fp_line
			(start -0.494 0.25)
			(end 0.504 0.25)
			(stroke
				(width 0.15)
				(type solid)
			)
			(layer "B.Fab")
		)
		(fp_text user "License: Apache-2.0"
			(at -0.939 -5.799 270)
			(layer "B.Fab")
			(effects
				(font
					(size 0.7 0.7)
					(thickness 0.15)
				)
				(justify left bottom mirror)
			)
		)
		(fp_text user "${REFERENCE}"
			(at -0.939 -4.599 270)
			(layer "B.Fab")
			(effects
				(font
					(size 0.7 0.7)
					(thickness 0.15)
				)
				(justify left bottom mirror)
			)
		)
		(fp_text user "Author: Antmicro"
			(at -0.939 -3.399 270)
			(layer "B.Fab")
			(effects
				(font
					(size 0.7 0.7)
					(thickness 0.15)
				)
				(justify left bottom mirror)
			)
		)
		(pad "1" smd roundrect
			(at -0.48 0 90)
			(size 0.59 0.64)
			(layers "B.Cu" "B.Mask" "B.Paste")
			(roundrect_rratio 0.25)
			(net 417 "GND")
			(pintype "passive")
		)
		(pad "2" smd roundrect
			(at 0.48 0 90)
			(size 0.59 0.64)
			(layers "B.Cu" "B.Mask" "B.Paste")
			(roundrect_rratio 0.25)
			(net 171 "WL_REG_ON")
			(pintype "passive")
		)
	)
	(footprint "antmicro-footprints:C_0402_1005Metric"
		(layer "B.Cu")
		(at 198.91 128.75 -90)
		(descr "Capacitor SMD 0402")
		(tags "capacitor SMD 0402")
		(property "Reference" "C26"
			(at -1.05 0.41 90)
			(layer "B.SilkS")
			(effects
				(font
					(size 0.7 0.7)
					(thickness 0.15)
				)
				(justify left bottom mirror)
			)
		)
		(property "Value" "C_1n_0402"
			(at -1.022927 -2.155213 90)
			(layer "B.Fab")
			(hide yes)
			(effects
				(font
					(size 0.7 0.7)
					(thickness 0.15)
				)
				(justify left bottom mirror)
			)
		)
		(property "Datasheet" "https://www.murata.com/products/productdetail?partno=GRM1555C1H102JA01%23"
			(at 0 0 270)
			(layer "F.Fab")
			(hide yes)
			(effects
				(font
					(size 1.27 1.27)
					(thickness 0.15)
				)
			)
		)
		(property "Description" "SMD Multilayer Ceramic Capacitor, 1000 pF, 50 V, 0402 [1005 Metric], ± 5%, C0G / NP0, GRM Series"
			(at 0 0 270)
			(layer "F.Fab")
			(hide yes)
			(effects
				(font
					(size 1.27 1.27)
					(thickness 0.15)
				)
			)
		)
		(property "Author" "Antmicro"
			(at 70.16 327.66 0)
			(layer "B.Fab")
			(hide yes)
			(effects
				(font
					(size 1 1)
					(thickness 0.15)
				)
				(justify mirror)
			)
		)
		(property "Dielectric" "C0G"
			(at 70.16 327.66 0)
			(layer "B.Fab")
			(hide yes)
			(effects
				(font
					(size 1 1)
					(thickness 0.15)
				)
				(justify mirror)
			)
		)
		(property "License" "Apache-2.0"
			(at 70.16 327.66 0)
			(layer "B.Fab")
			(hide yes)
			(effects
				(font
					(size 1 1)
					(thickness 0.15)
				)
				(justify mirror)
			)
		)
		(property "MPN" "GRM1555C1H102JA01D"
			(at 70.16 327.66 0)
			(layer "B.Fab")
			(hide yes)
			(effects
				(font
					(size 1 1)
					(thickness 0.15)
				)
				(justify mirror)
			)
		)
		(property "Manufacturer" "Murata"
			(at 70.16 327.66 0)
			(layer "B.Fab")
			(hide yes)
			(effects
				(font
					(size 1 1)
					(thickness 0.15)
				)
				(justify mirror)
			)
		)
		(property "Public" ""
			(at 70.16 327.66 0)
			(layer "B.Fab")
			(hide yes)
			(effects
				(font
					(size 1 1)
					(thickness 0.15)
				)
				(justify mirror)
			)
		)
		(property "Val" "1n"
			(at 70.16 327.66 0)
			(layer "B.Fab")
			(hide yes)
			(effects
				(font
					(size 1 1)
					(thickness 0.15)
				)
				(justify mirror)
			)
		)
		(property "Voltage" "50V"
			(at 70.16 327.66 0)
			(layer "B.Fab")
			(hide yes)
			(effects
				(font
					(size 1 1)
					(thickness 0.15)
				)
				(justify mirror)
			)
		)
		(sheetname "/FPGA Supply/")
		(sheetfile "fpga-supply.kicad_sch")
		(attr smd)
		(fp_rect
			(start -0.925 0.47)
			(end 0.925 -0.47)
			(stroke
				(width 0.05)
				(type default)
			)
			(fill no)
			(layer "B.CrtYd")
		)
		(fp_line
			(start -0.494 0.25)
			(end 0.504 0.25)
			(stroke
				(width 0.15)
				(type solid)
			)
			(layer "B.Fab")
		)
		(fp_line
			(start 0.504 0.25)
			(end 0.504 -0.248)
			(stroke
				(width 0.15)
				(type solid)
			)
			(layer "B.Fab")
		)
		(fp_line
			(start -0.494 -0.248)
			(end -0.494 0.25)
			(stroke
				(width 0.15)
				(type solid)
			)
			(layer "B.Fab")
		)
		(fp_line
			(start 0.504 -0.248)
			(end -0.494 -0.248)
			(stroke
				(width 0.15)
				(type solid)
			)
			(layer "B.Fab")
		)
		(fp_text user "License: Apache-2.0"
			(at -0.939 -5.799 90)
			(layer "B.Fab")
			(effects
				(font
					(size 0.7 0.7)
					(thickness 0.15)
				)
				(justify left bottom mirror)
			)
		)
		(fp_text user "Author: Antmicro"
			(at -0.939 -3.399 90)
			(layer "B.Fab")
			(effects
				(font
					(size 0.7 0.7)
					(thickness 0.15)
				)
				(justify left bottom mirror)
			)
		)
		(fp_text user "${REFERENCE}"
			(at -0.939 -4.599 90)
			(layer "B.Fab")
			(effects
				(font
					(size 0.7 0.7)
					(thickness 0.15)
				)
				(justify left bottom mirror)
			)
		)
		(pad "1" smd roundrect
			(at -0.48 0 270)
			(size 0.59 0.64)
			(layers "B.Cu" "B.Mask" "B.Paste")
			(roundrect_rratio 0.25)
			(net 417 "GND")
			(pintype "passive")
		)
		(pad "2" smd roundrect
			(at 0.48 0 270)
			(size 0.59 0.64)
			(layers "B.Cu" "B.Mask" "B.Paste")
			(roundrect_rratio 0.25)
			(net 418 "+2V5")
			(pintype "passive")
		)
	)
	(footprint "antmicro-footprints:C_0402_1005Metric"
		(layer "B.Cu")
		(at 214.915 149.55 -90)
		(descr "Capacitor SMD 0402")
		(tags "capacitor SMD 0402")
		(property "Reference" "C292"
			(at 0.86 -0.375 90)
			(layer "B.SilkS")
			(effects
				(font
					(size 0.7 0.7)
					(thickness 0.15)
				)
				(justify left bottom mirror)
			)
		)
		(property "Value" "C_1u_0402"
			(at -1.022927 -2.155213 90)
			(layer "B.Fab")
			(hide yes)
			(effects
				(font
					(size 0.7 0.7)
					(thickness 0.15)
				)
				(justify left bottom mirror)
			)
		)
		(property "Datasheet" "https://product.tdk.com/en/search/capacitor/ceramic/mlcc/info?part_no=C1005X6S1A105K050BC"
			(at 0 0 270)
			(layer "F.Fab")
			(hide yes)
			(effects
				(font
					(size 1.27 1.27)
					(thickness 0.15)
				)
			)
		)
		(property "Description" "SMD Multilayer Ceramic Capacitor, 1 µF, 10 V, 0402 [1005 Metric], ± 10%, X6S, C"
			(at 0 0 270)
			(layer "F.Fab")
			(hide yes)
			(effects
				(font
					(size 1.27 1.27)
					(thickness 0.15)
				)
			)
		)
		(property "Author" "Antmicro"
			(at 65.365 364.465 0)
			(layer "B.Fab")
			(hide yes)
			(effects
				(font
					(size 1 1)
					(thickness 0.15)
				)
				(justify mirror)
			)
		)
		(property "Dielectric" ""
			(at 65.365 364.465 0)
			(layer "B.Fab")
			(hide yes)
			(effects
				(font
					(size 1 1)
					(thickness 0.15)
				)
				(justify mirror)
			)
		)
		(property "License" "Apache-2.0"
			(at 65.365 364.465 0)
			(layer "B.Fab")
			(hide yes)
			(effects
				(font
					(size 1 1)
					(thickness 0.15)
				)
				(justify mirror)
			)
		)
		(property "MPN" "C1005X6S1A105K050BC"
			(at 65.365 364.465 0)
			(layer "B.Fab")
			(hide yes)
			(effects
				(font
					(size 1 1)
					(thickness 0.15)
				)
				(justify mirror)
			)
		)
		(property "Manufacturer" "TDK"
			(at 65.365 364.465 0)
			(layer "B.Fab")
			(hide yes)
			(effects
				(font
					(size 1 1)
					(thickness 0.15)
				)
				(justify mirror)
			)
		)
		(property "Public" ""
			(at 65.365 364.465 0)
			(layer "B.Fab")
			(hide yes)
			(effects
				(font
					(size 1 1)
					(thickness 0.15)
				)
				(justify mirror)
			)
		)
		(property "Val" "1u"
			(at 65.365 364.465 0)
			(layer "B.Fab")
			(hide yes)
			(effects
				(font
					(size 1 1)
					(thickness 0.15)
				)
				(justify mirror)
			)
		)
		(property "Voltage" ""
			(at 65.365 364.465 0)
			(layer "B.Fab")
			(hide yes)
			(effects
				(font
					(size 1 1)
					(thickness 0.15)
				)
				(justify mirror)
			)
		)
		(sheetname "/USB/")
		(sheetfile "usb.kicad_sch")
		(attr smd)
		(fp_rect
			(start -0.925 0.47)
			(end 0.925 -0.47)
			(stroke
				(width 0.05)
				(type default)
			)
			(fill no)
			(layer "B.CrtYd")
		)
		(fp_line
			(start -0.494 0.25)
			(end 0.504 0.25)
			(stroke
				(width 0.15)
				(type solid)
			)
			(layer "B.Fab")
		)
		(fp_line
			(start 0.504 0.25)
			(end 0.504 -0.248)
			(stroke
				(width 0.15)
				(type solid)
			)
			(layer "B.Fab")
		)
		(fp_line
			(start -0.494 -0.248)
			(end -0.494 0.25)
			(stroke
				(width 0.15)
				(type solid)
			)
			(layer "B.Fab")
		)
		(fp_line
			(start 0.504 -0.248)
			(end -0.494 -0.248)
			(stroke
				(width 0.15)
				(type solid)
			)
			(layer "B.Fab")
		)
		(fp_text user "License: Apache-2.0"
			(at -0.939 -5.799 90)
			(layer "B.Fab")
			(effects
				(font
					(size 0.7 0.7)
					(thickness 0.15)
				)
				(justify left bottom mirror)
			)
		)
		(fp_text user "${REFERENCE}"
			(at -0.939 -4.599 90)
			(layer "B.Fab")
			(effects
				(font
					(size 0.7 0.7)
					(thickness 0.15)
				)
				(justify left bottom mirror)
			)
		)
		(fp_text user "Author: Antmicro"
			(at -0.939 -3.399 90)
			(layer "B.Fab")
			(effects
				(font
					(size 0.7 0.7)
					(thickness 0.15)
				)
				(justify left bottom mirror)
			)
		)
		(pad "1" smd roundrect
			(at -0.48 0 270)
			(size 0.59 0.64)
			(layers "B.Cu" "B.Mask" "B.Paste")
			(roundrect_rratio 0.25)
			(net 417 "GND")
			(pintype "passive")
		)
		(pad "2" smd roundrect
			(at 0.48 0 270)
			(size 0.59 0.64)
			(layers "B.Cu" "B.Mask" "B.Paste")
			(roundrect_rratio 0.25)
			(net 182 "Net-(U28-CRFILT)")
			(pintype "passive")
		)
	)
	(footprint "antmicro-footprints:XSON-8_1x1.95mm_P0.5mm"
		(layer "B.Cu")
		(at 208.45 137.75 90)
		(property "Reference" "U21"
			(at -1.9 0.55 180)
			(layer "B.SilkS")
			(effects
				(font
					(size 0.7 0.7)
					(thickness 0.15)
				)
				(justify right bottom mirror)
			)
		)
		(property "Value" "NTS0102_XSON"
			(at 0 -2.2 90)
			(layer "B.Fab")
			(hide yes)
			(effects
				(font
					(size 0.7 0.7)
					(thickness 0.15)
				)
				(justify right bottom mirror)
			)
		)
		(property "Datasheet" "http://www.farnell.com/datasheets/1760723.pdf"
			(at 0 0 90)
			(layer "F.Fab")
			(hide yes)
			(effects
				(font
					(size 1.27 1.27)
					(thickness 0.15)
				)
			)
		)
		(property "Description" "Transceiver, 1.65 V to 3.6 V, XSON-8"
			(at 0 0 90)
			(layer "F.Fab")
			(hide yes)
			(effects
				(font
					(size 1.27 1.27)
					(thickness 0.15)
				)
			)
		)
		(property "Author" "Antmicro"
			(at 346.2 -70.7 0)
			(layer "B.Fab")
			(hide yes)
			(effects
				(font
					(size 1 1)
					(thickness 0.15)
				)
				(justify mirror)
			)
		)
		(property "License" "Apache-2.0"
			(at 346.2 -70.7 0)
			(layer "B.Fab")
			(hide yes)
			(effects
				(font
					(size 1 1)
					(thickness 0.15)
				)
				(justify mirror)
			)
		)
		(property "MPN" "NTS0102GT"
			(at 346.2 -70.7 0)
			(layer "B.Fab")
			(hide yes)
			(effects
				(font
					(size 1 1)
					(thickness 0.15)
				)
				(justify mirror)
			)
		)
		(property "Manufacturer" "NXP"
			(at 346.2 -70.7 0)
			(layer "B.Fab")
			(hide yes)
			(effects
				(font
					(size 1 1)
					(thickness 0.15)
				)
				(justify mirror)
			)
		)
		(sheetname "/FPGA GPIO/")
		(sheetfile "fpga-gpio.kicad_sch")
		(attr smd)
		(fp_line
			(start 0.5 -1.1)
			(end -0.5 -1.1)
			(stroke
				(width 0.15)
				(type solid)
			)
			(layer "B.SilkS")
		)
		(fp_line
			(start -0.5 1.1)
			(end 0.5 1.1)
			(stroke
				(width 0.15)
				(type solid)
			)
			(layer "B.SilkS")
		)
		(fp_circle
			(center -0.75 1.1)
			(end -0.701 1.1)
			(stroke
				(width 0.15)
				(type solid)
			)
			(fill no)
			(layer "B.SilkS")
		)
		(fp_rect
			(start -0.8 1.2)
			(end 0.8 -1.2)
			(stroke
				(width 0.05)
				(type solid)
			)
			(fill no)
			(layer "B.CrtYd")
		)
		(fp_line
			(start 0.5305 -1)
			(end -0.5305 -1)
			(stroke
				(width 0.15)
				(type solid)
			)
			(layer "B.Fab")
		)
		(fp_line
			(start -0.5305 -1)
			(end -0.5305 1.001)
			(stroke
				(width 0.15)
				(type solid)
			)
			(layer "B.Fab")
		)
		(fp_line
			(start 0.5305 1.001)
			(end 0.5305 -1)
			(stroke
				(width 0.15)
				(type solid)
			)
			(layer "B.Fab")
		)
		(fp_line
			(start -0.5305 1.001)
			(end 0.5305 1.001)
			(stroke
				(width 0.15)
				(type solid)
			)
			(layer "B.Fab")
		)
		(fp_text user "Author: Antmicro"
			(at -0.527 -7.105 270)
			(layer "B.Fab")
			(effects
				(font
					(size 0.7 0.7)
					(thickness 0.15)
				)
				(justify left bottom mirror)
			)
		)
		(fp_text user "License: Apache-2.0"
			(at -0.527 -8.306 270)
			(layer "B.Fab")
			(effects
				(font
					(size 0.7 0.7)
					(thickness 0.15)
				)
				(justify left bottom mirror)
			)
		)
		(fp_text user "${REFERENCE}"
			(at -0.527 -5.905 270)
			(layer "B.Fab")
			(effects
				(font
					(size 0.7 0.7)
					(thickness 0.15)
				)
				(justify left bottom mirror)
			)
		)
		(pad "1" smd roundrect
			(at -0.45 0.75 270)
			(size 0.6 0.3)
			(layers "B.Cu" "B.Mask" "B.Paste")
			(roundrect_rratio 0.25)
			(net 202 "PCIe_nRST")
			(pinfunction "B_{2}")
			(pintype "bidirectional")
		)
		(pad "2" smd roundrect
			(at -0.45 0.25 270)
			(size 0.6 0.25)
			(layers "B.Cu" "B.Mask" "B.Paste")
			(roundrect_rratio 0.25)
			(net 417 "GND")
			(pinfunction "GND")
			(pintype "power_in")
		)
		(pad "3" smd roundrect
			(at -0.45 -0.25 270)
			(size 0.6 0.25)
			(layers "B.Cu" "B.Mask" "B.Paste")
			(roundrect_rratio 0.25)
			(net 649 "VDD")
			(pinfunction "VCC_{A}")
			(pintype "power_in")
		)
		(pad "4" smd roundrect
			(at -0.45 -0.75 270)
			(size 0.6 0.3)
			(layers "B.Cu" "B.Mask" "B.Paste")
			(roundrect_rratio 0.25)
			(net 543 "/FPGA GPIO/PCIe_nRST_PF")
			(pinfunction "A_{2}")
			(pintype "bidirectional")
		)
		(pad "5" smd roundrect
			(at 0.45 -0.75 270)
			(size 0.6 0.3)
			(layers "B.Cu" "B.Mask" "B.Paste")
			(roundrect_rratio 0.25)
			(net 544 "/FPGA GPIO/PCIe_CLK_nREQ_PF")
			(pinfunction "A_{1}")
			(pintype "bidirectional")
		)
		(pad "6" smd roundrect
			(at 0.45 -0.25 270)
			(size 0.6 0.25)
			(layers "B.Cu" "B.Mask" "B.Paste")
			(roundrect_rratio 0.25)
			(net 649 "VDD")
			(pinfunction "OE")
			(pintype "input")
		)
		(pad "7" smd roundrect
			(at 0.45 0.25 270)
			(size 0.6 0.25)
			(layers "B.Cu" "B.Mask" "B.Paste")
			(roundrect_rratio 0.25)
			(net 50 "+3V3")
			(pinfunction "VCC_{B}")
			(pintype "power_in")
		)
		(pad "8" smd roundrect
			(at 0.45 0.75 270)
			(size 0.6 0.3)
			(layers "B.Cu" "B.Mask" "B.Paste")
			(roundrect_rratio 0.25)
			(net 200 "PCIe_CLK_nREQ")
			(pinfunction "B_{1}")
			(pintype "bidirectional")
		)
	)
	(footprint "antmicro-footprints:TP_SMD_0.75mm"
		(layer "B.Cu")
		(at 184 140.4 180)
		(property "Reference" "TP5"
			(at -0.01 -0.85 0)
			(layer "B.SilkS")
			(hide yes)
			(effects
				(font
					(size 0.7 0.7)
					(thickness 0.15)
				)
				(justify left bottom mirror)
			)
		)
		(property "Value" "TP_0.75mm_SMD"
			(at 0 -1.2 0)
			(layer "B.Fab")
			(hide yes)
			(effects
				(font
					(size 0.7 0.7)
					(thickness 0.15)
				)
				(justify left bottom mirror)
			)
		)
		(property "Description" "SMT test point"
			(at 0 0 0)
			(layer "B.Fab")
			(hide yes)
			(effects
				(font
					(size 1.27 1.27)
					(thickness 0.15)
				)
				(justify mirror)
			)
		)
		(property "MPN" ""
			(at 0 0 0)
			(unlocked yes)
			(layer "B.Fab")
			(hide yes)
			(effects
				(font
					(size 1 1)
					(thickness 0.15)
				)
				(justify mirror)
			)
		)
		(property "Manufacturer" ""
			(at 0 0 0)
			(unlocked yes)
			(layer "B.Fab")
			(hide yes)
			(effects
				(font
					(size 1 1)
					(thickness 0.15)
				)
				(justify mirror)
			)
		)
		(property "Author" "Antmicro"
			(at 0 0 0)
			(unlocked yes)
			(layer "B.Fab")
			(hide yes)
			(effects
				(font
					(size 1 1)
					(thickness 0.15)
				)
				(justify mirror)
			)
		)
		(property "License" "Apache-2.0"
			(at 0 0 0)
			(unlocked yes)
			(layer "B.Fab")
			(hide yes)
			(effects
				(font
					(size 1 1)
					(thickness 0.15)
				)
				(justify mirror)
			)
		)
		(property "Public" "False"
			(at 0 0 0)
			(unlocked yes)
			(layer "B.Fab")
			(hide yes)
			(effects
				(font
					(size 1 1)
					(thickness 0.15)
				)
				(justify mirror)
			)
		)
		(sheetname "/Supply/")
		(sheetfile "supply.kicad_sch")
		(attr exclude_from_pos_files exclude_from_bom)
		(fp_circle
			(center 0 0)
			(end 0.475 0)
			(stroke
				(width 0.05)
				(type default)
			)
			(fill no)
			(layer "B.CrtYd")
		)
		(fp_text user "${REFERENCE}"
			(at -0.4 -2.7 0)
			(layer "B.Fab")
			(effects
				(font
					(size 0.7 0.7)
					(thickness 0.15)
				)
				(justify left bottom mirror)
			)
		)
		(fp_text user "License: Apache-2.0"
			(at -0.4 -5.101 0)
			(layer "B.Fab")
			(effects
				(font
					(size 0.7 0.7)
					(thickness 0.15)
				)
				(justify left bottom mirror)
			)
		)
		(fp_text user "Author: Antmicro"
			(at -0.4 -3.901 0)
			(layer "B.Fab")
			(effects
				(font
					(size 0.7 0.7)
					(thickness 0.15)
				)
				(justify left bottom mirror)
			)
		)
		(pad "1" smd circle
			(at 0 0 180)
			(size 0.75 0.75)
			(layers "B.Cu" "B.Mask")
			(net 272 "/Supply/SENSE3_P")
			(pinfunction "1")
			(pintype "passive")
		)
	)
	(footprint "antmicro-footprints:R_0402_1005Metric"
		(layer "B.Cu")
		(at 222.08 131.6)
		(descr "Resistor SMD 0402")
		(tags "resistor SMD 0402")
		(property "Reference" "R80"
			(at 1.07 1.3 180)
			(layer "B.SilkS")
			(effects
				(font
					(size 0.7 0.7)
					(thickness 0.15)
				)
				(justify left bottom mirror)
			)
		)
		(property "Value" "R_100k_0402"
			(at -1.011843 -1.772047 180)
			(layer "B.Fab")
			(hide yes)
			(effects
				(font
					(size 0.7 0.7)
					(thickness 0.15)
				)
				(justify left bottom mirror)
			)
		)
		(property "Datasheet" "https://www.bourns.com/docs/product-datasheets/cr.pdf"
			(at 0 0 0)
			(layer "F.Fab")
			(hide yes)
			(effects
				(font
					(size 1.27 1.27)
					(thickness 0.15)
				)
			)
		)
		(property "Description" "SMD Chip Resistor, 100 kohm, ± 1%, 62.5 mW, 0402 [1005 Metric], Thick Film, General Purpose"
			(at 0 0 0)
			(layer "F.Fab")
			(hide yes)
			(effects
				(font
					(size 1.27 1.27)
					(thickness 0.15)
				)
			)
		)
		(property "Author" "Antmicro"
			(at 0 0 0)
			(layer "B.Fab")
			(hide yes)
			(effects
				(font
					(size 1 1)
					(thickness 0.15)
				)
				(justify mirror)
			)
		)
		(property "License" "Apache-2.0"
			(at 0 0 0)
			(layer "B.Fab")
			(hide yes)
			(effects
				(font
					(size 1 1)
					(thickness 0.15)
				)
				(justify mirror)
			)
		)
		(property "MPN" "CR0402-FX-1003GLF"
			(at 0 0 0)
			(layer "B.Fab")
			(hide yes)
			(effects
				(font
					(size 1 1)
					(thickness 0.15)
				)
				(justify mirror)
			)
		)
		(property "Manufacturer" "Bourns"
			(at 0 0 0)
			(layer "B.Fab")
			(hide yes)
			(effects
				(font
					(size 1 1)
					(thickness 0.15)
				)
				(justify mirror)
			)
		)
		(property "Public" ""
			(at 0 0 0)
			(layer "B.Fab")
			(hide yes)
			(effects
				(font
					(size 1 1)
					(thickness 0.15)
				)
				(justify mirror)
			)
		)
		(property "Tolerance" "1%"
			(at 0 0 0)
			(layer "B.Fab")
			(hide yes)
			(effects
				(font
					(size 1 1)
					(thickness 0.15)
				)
				(justify mirror)
			)
		)
		(property "Val" "100k"
			(at 0 0 0)
			(layer "B.Fab")
			(hide yes)
			(effects
				(font
					(size 1 1)
					(thickness 0.15)
				)
				(justify mirror)
			)
		)
		(sheetname "/FPGA GPIO/")
		(sheetfile "fpga-gpio.kicad_sch")
		(attr smd)
		(fp_rect
			(start -0.925 0.47)
			(end 0.925 -0.47)
			(stroke
				(width 0.05)
				(type default)
			)
			(fill no)
			(layer "B.CrtYd")
		)
		(fp_rect
			(start -0.5 0.25)
			(end 0.5 -0.25)
			(stroke
				(width 0.15)
				(type solid)
			)
			(fill no)
			(layer "B.Fab")
		)
		(fp_text user "License: Apache-2.0"
			(at -0.95 -5.169 180)
			(layer "B.Fab")
			(effects
				(font
					(size 0.7 0.7)
					(thickness 0.15)
				)
				(justify left bottom mirror)
			)
		)
		(fp_text user "${REFERENCE}"
			(at -0.95 -3.168 180)
			(layer "B.Fab")
			(effects
				(font
					(size 0.7 0.7)
					(thickness 0.15)
				)
				(justify left bottom mirror)
			)
		)
		(fp_text user "Author: Antmicro"
			(at -0.95 -4.169 180)
			(layer "B.Fab")
			(effects
				(font
					(size 0.7 0.7)
					(thickness 0.15)
				)
				(justify left bottom mirror)
			)
		)
		(pad "1" smd roundrect
			(at -0.48 0)
			(size 0.59 0.64)
			(layers "B.Cu" "B.Mask" "B.Paste")
			(roundrect_rratio 0.25)
			(net 417 "GND")
			(pintype "passive")
		)
		(pad "2" smd roundrect
			(at 0.48 0)
			(size 0.59 0.64)
			(layers "B.Cu" "B.Mask" "B.Paste")
			(roundrect_rratio 0.25)
			(net 224 "/FPGA GPIO/USER_LED_B")
			(pintype "passive")
		)
	)
	(footprint "antmicro-footprints:C_0402_1005Metric"
		(layer "B.Cu")
		(at 175.475 142.9675 -90)
		(descr "Capacitor SMD 0402")
		(tags "capacitor SMD 0402")
		(property "Reference" "C108"
			(at 3.6525 0.435 90)
			(layer "B.SilkS")
			(effects
				(font
					(size 0.7 0.7)
					(thickness 0.15)
				)
				(justify right top mirror)
			)
		)
		(property "Value" "C_22u_0402"
			(at -1.022927 -2.155213 90)
			(layer "B.Fab")
			(hide yes)
			(effects
				(font
					(size 0.7 0.7)
					(thickness 0.15)
				)
				(justify left bottom mirror)
			)
		)
		(property "Datasheet" "https://www.murata.com/products/productdetail?partno=GRM158R60J226ME01%23"
			(at 0 0 90)
			(layer "F.Fab")
			(hide yes)
			(effects
				(font
					(size 1.27 1.27)
					(thickness 0.15)
				)
			)
		)
		(property "Description" "SMD Multilayer Ceramic Capacitor, 22 uF, 4 V, 0402 [1005 Metric], X6S"
			(at 0 0 90)
			(layer "F.Fab")
			(hide yes)
			(effects
				(font
					(size 1.27 1.27)
					(thickness 0.15)
				)
			)
		)
		(property "Author" "Antmicro"
			(at 32.5075 318.4425 0)
			(layer "B.Fab")
			(hide yes)
			(effects
				(font
					(size 1 1)
					(thickness 0.15)
				)
				(justify mirror)
			)
		)
		(property "Dielectric" ""
			(at 32.5075 318.4425 0)
			(layer "B.Fab")
			(hide yes)
			(effects
				(font
					(size 1 1)
					(thickness 0.15)
				)
				(justify mirror)
			)
		)
		(property "License" "Apache-2.0"
			(at 32.5075 318.4425 0)
			(layer "B.Fab")
			(hide yes)
			(effects
				(font
					(size 1 1)
					(thickness 0.15)
				)
				(justify mirror)
			)
		)
		(property "MPN" "GRM158R60J226ME01D"
			(at 32.5075 318.4425 0)
			(layer "B.Fab")
			(hide yes)
			(effects
				(font
					(size 1 1)
					(thickness 0.15)
				)
				(justify mirror)
			)
		)
		(property "Manufacturer" "Murata"
			(at 32.5075 318.4425 0)
			(layer "B.Fab")
			(hide yes)
			(effects
				(font
					(size 1 1)
					(thickness 0.15)
				)
				(justify mirror)
			)
		)
		(property "Public" ""
			(at 32.5075 318.4425 0)
			(layer "B.Fab")
			(hide yes)
			(effects
				(font
					(size 1 1)
					(thickness 0.15)
				)
				(justify mirror)
			)
		)
		(property "Val" "22u"
			(at 32.5075 318.4425 0)
			(layer "B.Fab")
			(hide yes)
			(effects
				(font
					(size 1 1)
					(thickness 0.15)
				)
				(justify mirror)
			)
		)
		(property "Voltage" ""
			(at 32.5075 318.4425 0)
			(layer "B.Fab")
			(hide yes)
			(effects
				(font
					(size 1 1)
					(thickness 0.15)
				)
				(justify mirror)
			)
		)
		(sheetname "/Supply/")
		(sheetfile "supply.kicad_sch")
		(attr smd)
		(fp_rect
			(start -0.925 0.47)
			(end 0.925 -0.47)
			(stroke
				(width 0.05)
				(type default)
			)
			(fill no)
			(layer "B.CrtYd")
		)
		(fp_line
			(start -0.494 0.25)
			(end 0.504 0.25)
			(stroke
				(width 0.15)
				(type solid)
			)
			(layer "B.Fab")
		)
		(fp_line
			(start 0.504 0.25)
			(end 0.504 -0.248)
			(stroke
				(width 0.15)
				(type solid)
			)
			(layer "B.Fab")
		)
		(fp_line
			(start -0.494 -0.248)
			(end -0.494 0.25)
			(stroke
				(width 0.15)
				(type solid)
			)
			(layer "B.Fab")
		)
		(fp_line
			(start 0.504 -0.248)
			(end -0.494 -0.248)
			(stroke
				(width 0.15)
				(type solid)
			)
			(layer "B.Fab")
		)
		(fp_text user "Author: Antmicro"
			(at -0.939 -3.399 90)
			(layer "B.Fab")
			(effects
				(font
					(size 0.7 0.7)
					(thickness 0.15)
				)
				(justify left bottom mirror)
			)
		)
		(fp_text user "${REFERENCE}"
			(at -0.939 -4.599 90)
			(layer "B.Fab")
			(effects
				(font
					(size 0.7 0.7)
					(thickness 0.15)
				)
				(justify left bottom mirror)
			)
		)
		(fp_text user "License: Apache-2.0"
			(at -0.939 -5.799 90)
			(layer "B.Fab")
			(effects
				(font
					(size 0.7 0.7)
					(thickness 0.15)
				)
				(justify left bottom mirror)
			)
		)
		(pad "1" smd roundrect
			(at -0.48 0 270)
			(size 0.59 0.64)
			(layers "B.Cu" "B.Mask" "B.Paste")
			(roundrect_rratio 0.25)
			(net 417 "GND")
			(pintype "passive")
		)
		(pad "2" smd roundrect
			(at 0.48 0 270)
			(size 0.59 0.64)
			(layers "B.Cu" "B.Mask" "B.Paste")
			(roundrect_rratio 0.25)
			(net 406 "/Supply/SENSE2_P")
			(pintype "passive")
		)
	)
	(footprint "antmicro-footprints:C_0402_1005Metric"
		(layer "B.Cu")
		(at 222.2168 117.3457 180)
		(descr "Capacitor SMD 0402")
		(tags "capacitor SMD 0402")
		(property "Reference" "C239"
			(at -1.6132 0.3957 0)
			(layer "B.SilkS")
			(effects
				(font
					(size 0.7 0.7)
					(thickness 0.15)
				)
				(justify left bottom mirror)
			)
		)
		(property "Value" "C_100n_0402"
			(at -1.022927 -2.155213 0)
			(layer "B.Fab")
			(hide yes)
			(effects
				(font
					(size 0.7 0.7)
					(thickness 0.15)
				)
				(justify left bottom mirror)
			)
		)
		(property "Datasheet" "https://www.murata.com/products/productdetail?partno=GRM155R61H104KE14%23"
			(at 0 0 180)
			(layer "F.Fab")
			(hide yes)
			(effects
				(font
					(size 1.27 1.27)
					(thickness 0.15)
				)
			)
		)
		(property "Description" "SMD Multilayer Ceramic Capacitor, 0.1 µF, 50 V, 0402 [1005 Metric], ± 10%, X5R, GRM Series"
			(at 0 0 180)
			(layer "F.Fab")
			(hide yes)
			(effects
				(font
					(size 1.27 1.27)
					(thickness 0.15)
				)
			)
		)
		(property "Author" "Antmicro"
			(at 444.4336 234.6914 0)
			(layer "B.Fab")
			(hide yes)
			(effects
				(font
					(size 1 1)
					(thickness 0.15)
				)
				(justify mirror)
			)
		)
		(property "Dielectric" "X5R"
			(at 444.4336 234.6914 0)
			(layer "B.Fab")
			(hide yes)
			(effects
				(font
					(size 1 1)
					(thickness 0.15)
				)
				(justify mirror)
			)
		)
		(property "License" "Apache-2.0"
			(at 444.4336 234.6914 0)
			(layer "B.Fab")
			(hide yes)
			(effects
				(font
					(size 1 1)
					(thickness 0.15)
				)
				(justify mirror)
			)
		)
		(property "MPN" "GRM155R61H104KE14D"
			(at 444.4336 234.6914 0)
			(layer "B.Fab")
			(hide yes)
			(effects
				(font
					(size 1 1)
					(thickness 0.15)
				)
				(justify mirror)
			)
		)
		(property "Manufacturer" "Murata"
			(at 444.4336 234.6914 0)
			(layer "B.Fab")
			(hide yes)
			(effects
				(font
					(size 1 1)
					(thickness 0.15)
				)
				(justify mirror)
			)
		)
		(property "Public" ""
			(at 444.4336 234.6914 0)
			(layer "B.Fab")
			(hide yes)
			(effects
				(font
					(size 1 1)
					(thickness 0.15)
				)
				(justify mirror)
			)
		)
		(property "Val" "100n"
			(at 444.4336 234.6914 0)
			(layer "B.Fab")
			(hide yes)
			(effects
				(font
					(size 1 1)
					(thickness 0.15)
				)
				(justify mirror)
			)
		)
		(property "Voltage" "50V"
			(at 444.4336 234.6914 0)
			(layer "B.Fab")
			(hide yes)
			(effects
				(font
					(size 1 1)
					(thickness 0.15)
				)
				(justify mirror)
			)
		)
		(sheetname "/Ethernet/")
		(sheetfile "ethernet.kicad_sch")
		(attr smd)
		(fp_rect
			(start -0.925 0.47)
			(end 0.925 -0.47)
			(stroke
				(width 0.05)
				(type default)
			)
			(fill no)
			(layer "B.CrtYd")
		)
		(fp_line
			(start 0.504 0.25)
			(end 0.504 -0.248)
			(stroke
				(width 0.15)
				(type solid)
			)
			(layer "B.Fab")
		)
		(fp_line
			(start 0.504 -0.248)
			(end -0.494 -0.248)
			(stroke
				(width 0.15)
				(type solid)
			)
			(layer "B.Fab")
		)
		(fp_line
			(start -0.494 0.25)
			(end 0.504 0.25)
			(stroke
				(width 0.15)
				(type solid)
			)
			(layer "B.Fab")
		)
		(fp_line
			(start -0.494 -0.248)
			(end -0.494 0.25)
			(stroke
				(width 0.15)
				(type solid)
			)
			(layer "B.Fab")
		)
		(fp_text user "${REFERENCE}"
			(at -0.939 -4.599 0)
			(layer "B.Fab")
			(effects
				(font
					(size 0.7 0.7)
					(thickness 0.15)
				)
				(justify left bottom mirror)
			)
		)
		(fp_text user "Author: Antmicro"
			(at -0.939 -3.399 0)
			(layer "B.Fab")
			(effects
				(font
					(size 0.7 0.7)
					(thickness 0.15)
				)
				(justify left bottom mirror)
			)
		)
		(fp_text user "License: Apache-2.0"
			(at -0.939 -5.799 0)
			(layer "B.Fab")
			(effects
				(font
					(size 0.7 0.7)
					(thickness 0.15)
				)
				(justify left bottom mirror)
			)
		)
		(pad "1" smd roundrect
			(at -0.48 0 180)
			(size 0.59 0.64)
			(layers "B.Cu" "B.Mask" "B.Paste")
			(roundrect_rratio 0.25)
			(net 417 "GND")
			(pintype "passive")
		)
		(pad "2" smd roundrect
			(at 0.48 0 180)
			(size 0.59 0.64)
			(layers "B.Cu" "B.Mask" "B.Paste")
			(roundrect_rratio 0.25)
			(net 50 "+3V3")
			(pintype "passive")
		)
	)
	(footprint "antmicro-footprints:C_0402_1005Metric"
		(layer "B.Cu")
		(at 192.45 146.75 -90)
		(descr "Capacitor SMD 0402")
		(tags "capacitor SMD 0402")
		(property "Reference" "C189"
			(at 0.8 -0.7 90)
			(layer "B.SilkS")
			(effects
				(font
					(size 0.7 0.7)
					(thickness 0.15)
				)
				(justify left bottom mirror)
			)
		)
		(property "Value" "C_10u_10V_0402"
			(at -1.022927 -2.155213 90)
			(layer "B.Fab")
			(hide yes)
			(effects
				(font
					(size 0.7 0.7)
					(thickness 0.15)
				)
				(justify left bottom mirror)
			)
		)
		(property "Datasheet" "https://www.murata.com/products/productdetail?partno=GRM155R61A106ME11%23"
			(at 0 0 270)
			(layer "F.Fab")
			(hide yes)
			(effects
				(font
					(size 1.27 1.27)
					(thickness 0.15)
				)
			)
		)
		(property "Description" "Multilayer Ceramic Capacitors MLCC - SMD/SMT 10 uF 10 VDC 20% 0402 X5R"
			(at 0 0 270)
			(layer "F.Fab")
			(hide yes)
			(effects
				(font
					(size 1.27 1.27)
					(thickness 0.15)
				)
			)
		)
		(property "Author" "Antmicro"
			(at 45.7 339.2 0)
			(layer "B.Fab")
			(hide yes)
			(effects
				(font
					(size 1 1)
					(thickness 0.15)
				)
				(justify mirror)
			)
		)
		(property "Dielectric" "X5R"
			(at 45.7 339.2 0)
			(layer "B.Fab")
			(hide yes)
			(effects
				(font
					(size 1 1)
					(thickness 0.15)
				)
				(justify mirror)
			)
		)
		(property "License" "Apache-2.0"
			(at 45.7 339.2 0)
			(layer "B.Fab")
			(hide yes)
			(effects
				(font
					(size 1 1)
					(thickness 0.15)
				)
				(justify mirror)
			)
		)
		(property "MPN" "GRM155R61A106ME11D"
			(at 45.7 339.2 0)
			(layer "B.Fab")
			(hide yes)
			(effects
				(font
					(size 1 1)
					(thickness 0.15)
				)
				(justify mirror)
			)
		)
		(property "Manufacturer" "Murata"
			(at 45.7 339.2 0)
			(layer "B.Fab")
			(hide yes)
			(effects
				(font
					(size 1 1)
					(thickness 0.15)
				)
				(justify mirror)
			)
		)
		(property "Public" ""
			(at 45.7 339.2 0)
			(layer "B.Fab")
			(hide yes)
			(effects
				(font
					(size 1 1)
					(thickness 0.15)
				)
				(justify mirror)
			)
		)
		(property "Val" "10u"
			(at 45.7 339.2 0)
			(layer "B.Fab")
			(hide yes)
			(effects
				(font
					(size 1 1)
					(thickness 0.15)
				)
				(justify mirror)
			)
		)
		(property "Voltage" "10V"
			(at 45.7 339.2 0)
			(layer "B.Fab")
			(hide yes)
			(effects
				(font
					(size 1 1)
					(thickness 0.15)
				)
				(justify mirror)
			)
		)
		(sheetname "/HDMI/")
		(sheetfile "hdmi.kicad_sch")
		(attr smd)
		(fp_rect
			(start -0.925 0.47)
			(end 0.925 -0.47)
			(stroke
				(width 0.05)
				(type default)
			)
			(fill no)
			(layer "B.CrtYd")
		)
		(fp_line
			(start -0.494 0.25)
			(end 0.504 0.25)
			(stroke
				(width 0.15)
				(type solid)
			)
			(layer "B.Fab")
		)
		(fp_line
			(start 0.504 0.25)
			(end 0.504 -0.248)
			(stroke
				(width 0.15)
				(type solid)
			)
			(layer "B.Fab")
		)
		(fp_line
			(start -0.494 -0.248)
			(end -0.494 0.25)
			(stroke
				(width 0.15)
				(type solid)
			)
			(layer "B.Fab")
		)
		(fp_line
			(start 0.504 -0.248)
			(end -0.494 -0.248)
			(stroke
				(width 0.15)
				(type solid)
			)
			(layer "B.Fab")
		)
		(fp_text user "License: Apache-2.0"
			(at -0.939 -5.799 90)
			(layer "B.Fab")
			(effects
				(font
					(size 0.7 0.7)
					(thickness 0.15)
				)
				(justify left bottom mirror)
			)
		)
		(fp_text user "${REFERENCE}"
			(at -0.939 -4.599 90)
			(layer "B.Fab")
			(effects
				(font
					(size 0.7 0.7)
					(thickness 0.15)
				)
				(justify left bottom mirror)
			)
		)
		(fp_text user "Author: Antmicro"
			(at -0.939 -3.399 90)
			(layer "B.Fab")
			(effects
				(font
					(size 0.7 0.7)
					(thickness 0.15)
				)
				(justify left bottom mirror)
			)
		)
		(pad "1" smd roundrect
			(at -0.48 0 270)
			(size 0.59 0.64)
			(layers "B.Cu" "B.Mask" "B.Paste")
			(roundrect_rratio 0.25)
			(net 417 "GND")
			(pintype "passive")
		)
		(pad "2" smd roundrect
			(at 0.48 0 270)
			(size 0.59 0.64)
			(layers "B.Cu" "B.Mask" "B.Paste")
			(roundrect_rratio 0.25)
			(net 553 "/HDMI/HDMI_3V3")
			(pintype "passive")
		)
	)
	(footprint "antmicro-footprints:SOT-583"
		(layer "B.Cu")
		(at 219.35 129.899 -90)
		(property "Reference" "U5"
			(at -1.199 -1.95 180)
			(layer "B.SilkS")
			(effects
				(font
					(size 0.7 0.7)
					(thickness 0.15)
				)
				(justify left bottom mirror)
			)
		)
		(property "Value" "TPS2117DRLR"
			(at 0 -2.3 90)
			(layer "B.Fab")
			(hide yes)
			(effects
				(font
					(size 0.7 0.7)
					(thickness 0.15)
				)
				(justify left bottom mirror)
			)
		)
		(property "Datasheet" "https://www.ti.com/lit/ds/symlink/tps2117.pdf"
			(at 0 0 270)
			(layer "F.Fab")
			(hide yes)
			(effects
				(font
					(size 1.27 1.27)
					(thickness 0.15)
				)
			)
		)
		(property "Description" "TPS2117 1.6-V to 5.5-V, 4-A Low IQ Power Mux With Manual and Priority Switchover"
			(at 0 0 270)
			(layer "F.Fab")
			(hide yes)
			(effects
				(font
					(size 1.27 1.27)
					(thickness 0.15)
				)
			)
		)
		(property "Author" "Antmicro"
			(at 89.451 349.249 0)
			(layer "B.Fab")
			(hide yes)
			(effects
				(font
					(size 1 1)
					(thickness 0.15)
				)
				(justify mirror)
			)
		)
		(property "License" "Apache-2.0"
			(at 89.451 349.249 0)
			(layer "B.Fab")
			(hide yes)
			(effects
				(font
					(size 1 1)
					(thickness 0.15)
				)
				(justify mirror)
			)
		)
		(property "MPN" "TPS2117DRLR"
			(at 89.451 349.249 0)
			(layer "B.Fab")
			(hide yes)
			(effects
				(font
					(size 1 1)
					(thickness 0.15)
				)
				(justify mirror)
			)
		)
		(property "Manufacturer" "Texas Instruments"
			(at 89.451 349.249 0)
			(layer "B.Fab")
			(hide yes)
			(effects
				(font
					(size 1 1)
					(thickness 0.15)
				)
				(justify mirror)
			)
		)
		(property ki_fp_filters "DRL0008A-MFG")
		(sheetname "/Supply/")
		(sheetfile "supply.kicad_sch")
		(attr smd)
		(fp_line
			(start -0.65 1.15)
			(end 0.65 1.15)
			(stroke
				(width 0.15)
				(type solid)
			)
			(layer "B.SilkS")
		)
		(fp_line
			(start -0.651 -1.15)
			(end 0.651 -1.15)
			(stroke
				(width 0.15)
				(type solid)
			)
			(layer "B.SilkS")
		)
		(fp_circle
			(center -0.9 1.1)
			(end -0.85 1.05)
			(stroke
				(width 0.15)
				(type solid)
			)
			(fill yes)
			(layer "B.SilkS")
		)
		(fp_rect
			(start -1.15 1.3)
			(end 1.15 -1.3)
			(stroke
				(width 0.05)
				(type solid)
			)
			(fill no)
			(layer "B.CrtYd")
		)
		(fp_line
			(start -0.651 1.1005)
			(end 0.651 1.1005)
			(stroke
				(width 0.15)
				(type solid)
			)
			(layer "B.Fab")
		)
		(fp_line
			(start -0.651 -1.1005)
			(end -0.651 1.1005)
			(stroke
				(width 0.15)
				(type solid)
			)
			(layer "B.Fab")
		)
		(fp_line
			(start -0.651 -1.1005)
			(end 0.651 -1.1005)
			(stroke
				(width 0.15)
				(type solid)
			)
			(layer "B.Fab")
		)
		(fp_line
			(start 0.651 -1.1005)
			(end 0.651 1.1005)
			(stroke
				(width 0.15)
				(type solid)
			)
			(layer "B.Fab")
		)
		(fp_text user "${REFERENCE}"
			(at -0.06 -4.025 90)
			(layer "B.Fab")
			(effects
				(font
					(size 0.7 0.7)
					(thickness 0.15)
				)
				(justify left bottom mirror)
			)
		)
		(fp_text user "Author: Antmicro"
			(at -0.06 -5.025 90)
			(layer "B.Fab")
			(effects
				(font
					(size 0.7 0.7)
					(thickness 0.15)
				)
				(justify left bottom mirror)
			)
		)
		(fp_text user "License: Apache-2.0"
			(at -0.06 -6.025 90)
			(layer "B.Fab")
			(effects
				(font
					(size 0.7 0.7)
					(thickness 0.15)
				)
				(justify left bottom mirror)
			)
		)
		(pad "1" smd roundrect
			(at -0.739 0.7495 270)
			(size 0.670001 0.299999)
			(layers "B.Cu" "B.Mask" "B.Paste")
			(roundrect_rratio 0.25)
			(net 417 "GND")
			(pinfunction "GND")
			(pintype "power_in")
		)
		(pad "2" smd roundrect
			(at -0.739 0.2505 270)
			(size 0.670001 0.299999)
			(layers "B.Cu" "B.Mask" "B.Paste")
			(roundrect_rratio 0.25)
			(net 188 "Net-(R9-Pad1)")
			(pinfunction "VOUT")
			(pintype "power_out")
		)
		(pad "3" smd roundrect
			(at -0.739 -0.2495 270)
			(size 0.670001 0.299999)
			(layers "B.Cu" "B.Mask" "B.Paste")
			(roundrect_rratio 0.25)
			(net 50 "+3V3")
			(pinfunction "VIN1")
			(pintype "power_in")
		)
		(pad "4" smd roundrect
			(at -0.739 -0.7495 270)
			(size 0.670001 0.299999)
			(layers "B.Cu" "B.Mask" "B.Paste")
			(roundrect_rratio 0.25)
			(net 186 "/Supply/PR")
			(pinfunction "PR1")
			(pintype "input")
		)
		(pad "5" smd roundrect
			(at 0.74 -0.7495 270)
			(size 0.670001 0.299999)
			(layers "B.Cu" "B.Mask" "B.Paste")
			(roundrect_rratio 0.25)
			(net 50 "+3V3")
			(pinfunction "MODE")
			(pintype "input")
		)
		(pad "6" smd roundrect
			(at 0.74 -0.2495 270)
			(size 0.670001 0.299999)
			(layers "B.Cu" "B.Mask" "B.Paste")
			(roundrect_rratio 0.25)
			(net 418 "+2V5")
			(pinfunction "VIN2")
			(pintype "power_in")
		)
		(pad "7" smd roundrect
			(at 0.74 0.2505 270)
			(size 0.670001 0.299999)
			(layers "B.Cu" "B.Mask" "B.Paste")
			(roundrect_rratio 0.25)
			(net 188 "Net-(R9-Pad1)")
			(pinfunction "VOUT")
			(pintype "passive")
		)
		(pad "8" smd roundrect
			(at 0.74 0.7495 270)
			(size 0.670001 0.299999)
			(layers "B.Cu" "B.Mask" "B.Paste")
			(roundrect_rratio 0.25)
			(net 477 "unconnected-(U5-ST-Pad8)")
			(pinfunction "ST")
			(pintype "output+no_connect")
		)
	)
	(footprint "antmicro-footprints:C_0402_1005Metric"
		(layer "B.Cu")
		(at 196.09 136.67 90)
		(descr "Capacitor SMD 0402")
		(tags "capacitor SMD 0402")
		(property "Reference" "C46"
			(at 5.17 -9.615 90)
			(layer "B.SilkS")
			(effects
				(font
					(size 0.7 0.7)
					(thickness 0.15)
				)
				(justify right bottom mirror)
			)
		)
		(property "Value" "C_100n_0402"
			(at -1.022927 -2.155213 90)
			(layer "B.Fab")
			(hide yes)
			(effects
				(font
					(size 0.7 0.7)
					(thickness 0.15)
				)
				(justify right bottom mirror)
			)
		)
		(property "Datasheet" "https://www.murata.com/products/productdetail?partno=GRM155R61H104KE14%23"
			(at 0 0 90)
			(layer "F.Fab")
			(hide yes)
			(effects
				(font
					(size 1.27 1.27)
					(thickness 0.15)
				)
			)
		)
		(property "Description" "SMD Multilayer Ceramic Capacitor, 0.1 µF, 50 V, 0402 [1005 Metric], ± 10%, X5R, GRM Series"
			(at 0 0 90)
			(layer "F.Fab")
			(hide yes)
			(effects
				(font
					(size 1.27 1.27)
					(thickness 0.15)
				)
			)
		)
		(property "Author" "Antmicro"
			(at 332.76 -59.42 0)
			(layer "B.Fab")
			(hide yes)
			(effects
				(font
					(size 1 1)
					(thickness 0.15)
				)
				(justify mirror)
			)
		)
		(property "Dielectric" "X5R"
			(at 332.76 -59.42 0)
			(layer "B.Fab")
			(hide yes)
			(effects
				(font
					(size 1 1)
					(thickness 0.15)
				)
				(justify mirror)
			)
		)
		(property "License" "Apache-2.0"
			(at 332.76 -59.42 0)
			(layer "B.Fab")
			(hide yes)
			(effects
				(font
					(size 1 1)
					(thickness 0.15)
				)
				(justify mirror)
			)
		)
		(property "MPN" "GRM155R61H104KE14D"
			(at 332.76 -59.42 0)
			(layer "B.Fab")
			(hide yes)
			(effects
				(font
					(size 1 1)
					(thickness 0.15)
				)
				(justify mirror)
			)
		)
		(property "Manufacturer" "Murata"
			(at 332.76 -59.42 0)
			(layer "B.Fab")
			(hide yes)
			(effects
				(font
					(size 1 1)
					(thickness 0.15)
				)
				(justify mirror)
			)
		)
		(property "Public" ""
			(at 332.76 -59.42 0)
			(layer "B.Fab")
			(hide yes)
			(effects
				(font
					(size 1 1)
					(thickness 0.15)
				)
				(justify mirror)
			)
		)
		(property "Val" "100n"
			(at 332.76 -59.42 0)
			(layer "B.Fab")
			(hide yes)
			(effects
				(font
					(size 1 1)
					(thickness 0.15)
				)
				(justify mirror)
			)
		)
		(property "Voltage" "50V"
			(at 332.76 -59.42 0)
			(layer "B.Fab")
			(hide yes)
			(effects
				(font
					(size 1 1)
					(thickness 0.15)
				)
				(justify mirror)
			)
		)
		(sheetname "/FPGA Supply/")
		(sheetfile "fpga-supply.kicad_sch")
		(attr smd)
		(fp_rect
			(start -0.925 0.47)
			(end 0.925 -0.47)
			(stroke
				(width 0.05)
				(type default)
			)
			(fill no)
			(layer "B.CrtYd")
		)
		(fp_line
			(start 0.504 -0.248)
			(end -0.494 -0.248)
			(stroke
				(width 0.15)
				(type solid)
			)
			(layer "B.Fab")
		)
		(fp_line
			(start -0.494 -0.248)
			(end -0.494 0.25)
			(stroke
				(width 0.15)
				(type solid)
			)
			(layer "B.Fab")
		)
		(fp_line
			(start 0.504 0.25)
			(end 0.504 -0.248)
			(stroke
				(width 0.15)
				(type solid)
			)
			(layer "B.Fab")
		)
		(fp_line
			(start -0.494 0.25)
			(end 0.504 0.25)
			(stroke
				(width 0.15)
				(type solid)
			)
			(layer "B.Fab")
		)
		(fp_text user "${REFERENCE}"
			(at -0.939 -4.599 270)
			(layer "B.Fab")
			(effects
				(font
					(size 0.7 0.7)
					(thickness 0.15)
				)
				(justify left bottom mirror)
			)
		)
		(fp_text user "License: Apache-2.0"
			(at -0.939 -5.799 270)
			(layer "B.Fab")
			(effects
				(font
					(size 0.7 0.7)
					(thickness 0.15)
				)
				(justify left bottom mirror)
			)
		)
		(fp_text user "Author: Antmicro"
			(at -0.939 -3.399 270)
			(layer "B.Fab")
			(effects
				(font
					(size 0.7 0.7)
					(thickness 0.15)
				)
				(justify left bottom mirror)
			)
		)
		(pad "1" smd roundrect
			(at -0.48 0 90)
			(size 0.59 0.64)
			(layers "B.Cu" "B.Mask" "B.Paste")
			(roundrect_rratio 0.25)
			(net 417 "GND")
			(pintype "passive")
		)
		(pad "2" smd roundrect
			(at 0.48 0 90)
			(size 0.59 0.64)
			(layers "B.Cu" "B.Mask" "B.Paste")
			(roundrect_rratio 0.25)
			(net 48 "+1V8")
			(pintype "passive")
		)
	)
	(footprint "antmicro-footprints:C_0402_1005Metric"
		(layer "B.Cu")
		(at 216.365 145.85)
		(descr "Capacitor SMD 0402")
		(tags "capacitor SMD 0402")
		(property "Reference" "C222"
			(at 0.145 4.46 0)
			(layer "B.SilkS")
			(effects
				(font
					(size 0.7 0.7)
					(thickness 0.15)
				)
				(justify right bottom mirror)
			)
		)
		(property "Value" "C_100n_0402"
			(at -1.022927 -2.155213 0)
			(layer "B.Fab")
			(hide yes)
			(effects
				(font
					(size 0.7 0.7)
					(thickness 0.15)
				)
				(justify right bottom mirror)
			)
		)
		(property "Datasheet" "https://www.murata.com/products/productdetail?partno=GRM155R61H104KE14%23"
			(at 0 0 0)
			(layer "F.Fab")
			(hide yes)
			(effects
				(font
					(size 1.27 1.27)
					(thickness 0.15)
				)
			)
		)
		(property "Description" "SMD Multilayer Ceramic Capacitor, 0.1 µF, 50 V, 0402 [1005 Metric], ± 10%, X5R, GRM Series"
			(at 0 0 0)
			(layer "F.Fab")
			(hide yes)
			(effects
				(font
					(size 1.27 1.27)
					(thickness 0.15)
				)
			)
		)
		(property "Author" "Antmicro"
			(at 0 0 0)
			(layer "B.Fab")
			(hide yes)
			(effects
				(font
					(size 1 1)
					(thickness 0.15)
				)
				(justify mirror)
			)
		)
		(property "Dielectric" "X5R"
			(at 0 0 0)
			(layer "B.Fab")
			(hide yes)
			(effects
				(font
					(size 1 1)
					(thickness 0.15)
				)
				(justify mirror)
			)
		)
		(property "License" "Apache-2.0"
			(at 0 0 0)
			(layer "B.Fab")
			(hide yes)
			(effects
				(font
					(size 1 1)
					(thickness 0.15)
				)
				(justify mirror)
			)
		)
		(property "MPN" "GRM155R61H104KE14D"
			(at 0 0 0)
			(layer "B.Fab")
			(hide yes)
			(effects
				(font
					(size 1 1)
					(thickness 0.15)
				)
				(justify mirror)
			)
		)
		(property "Manufacturer" "Murata"
			(at 0 0 0)
			(layer "B.Fab")
			(hide yes)
			(effects
				(font
					(size 1 1)
					(thickness 0.15)
				)
				(justify mirror)
			)
		)
		(property "Public" ""
			(at 0 0 0)
			(layer "B.Fab")
			(hide yes)
			(effects
				(font
					(size 1 1)
					(thickness 0.15)
				)
				(justify mirror)
			)
		)
		(property "Val" "100n"
			(at 0 0 0)
			(layer "B.Fab")
			(hide yes)
			(effects
				(font
					(size 1 1)
					(thickness 0.15)
				)
				(justify mirror)
			)
		)
		(property "Voltage" "50V"
			(at 0 0 0)
			(layer "B.Fab")
			(hide yes)
			(effects
				(font
					(size 1 1)
					(thickness 0.15)
				)
				(justify mirror)
			)
		)
		(sheetname "/USB/")
		(sheetfile "usb.kicad_sch")
		(attr smd)
		(fp_rect
			(start -0.925 0.47)
			(end 0.925 -0.47)
			(stroke
				(width 0.05)
				(type default)
			)
			(fill no)
			(layer "B.CrtYd")
		)
		(fp_line
			(start -0.494 -0.248)
			(end -0.494 0.25)
			(stroke
				(width 0.15)
				(type solid)
			)
			(layer "B.Fab")
		)
		(fp_line
			(start -0.494 0.25)
			(end 0.504 0.25)
			(stroke
				(width 0.15)
				(type solid)
			)
			(layer "B.Fab")
		)
		(fp_line
			(start 0.504 -0.248)
			(end -0.494 -0.248)
			(stroke
				(width 0.15)
				(type solid)
			)
			(layer "B.Fab")
		)
		(fp_line
			(start 0.504 0.25)
			(end 0.504 -0.248)
			(stroke
				(width 0.15)
				(type solid)
			)
			(layer "B.Fab")
		)
		(fp_text user "Author: Antmicro"
			(at -0.939 -3.399 180)
			(layer "B.Fab")
			(effects
				(font
					(size 0.7 0.7)
					(thickness 0.15)
				)
				(justify left bottom mirror)
			)
		)
		(fp_text user "${REFERENCE}"
			(at -0.939 -4.599 180)
			(layer "B.Fab")
			(effects
				(font
					(size 0.7 0.7)
					(thickness 0.15)
				)
				(justify left bottom mirror)
			)
		)
		(fp_text user "License: Apache-2.0"
			(at -0.939 -5.799 180)
			(layer "B.Fab")
			(effects
				(font
					(size 0.7 0.7)
					(thickness 0.15)
				)
				(justify left bottom mirror)
			)
		)
		(pad "1" smd roundrect
			(at -0.48 0)
			(size 0.59 0.64)
			(layers "B.Cu" "B.Mask" "B.Paste")
			(roundrect_rratio 0.25)
			(net 417 "GND")
			(pintype "passive")
		)
		(pad "2" smd roundrect
			(at 0.48 0)
			(size 0.59 0.64)
			(layers "B.Cu" "B.Mask" "B.Paste")
			(roundrect_rratio 0.25)
			(net 50 "+3V3")
			(pintype "passive")
		)
	)
	(footprint "antmicro-footprints:C_0402_1005Metric"
		(layer "B.Cu")
		(at 177.65 136.775)
		(descr "Capacitor SMD 0402")
		(tags "capacitor SMD 0402")
		(property "Reference" "C166"
			(at -1.06 -0.4 0)
			(layer "B.SilkS")
			(effects
				(font
					(size 0.7 0.7)
					(thickness 0.15)
				)
				(justify right bottom mirror)
			)
		)
		(property "Value" "C_1u_0402"
			(at -1.022927 -2.155213 0)
			(layer "B.Fab")
			(hide yes)
			(effects
				(font
					(size 0.7 0.7)
					(thickness 0.15)
				)
				(justify right bottom mirror)
			)
		)
		(property "Datasheet" "https://product.tdk.com/en/search/capacitor/ceramic/mlcc/info?part_no=C1005X6S1A105K050BC"
			(at 0 0 0)
			(layer "F.Fab")
			(hide yes)
			(effects
				(font
					(size 1.27 1.27)
					(thickness 0.15)
				)
			)
		)
		(property "Description" "SMD Multilayer Ceramic Capacitor, 1 µF, 10 V, 0402 [1005 Metric], ± 10%, X6S, C"
			(at 0 0 0)
			(layer "F.Fab")
			(hide yes)
			(effects
				(font
					(size 1.27 1.27)
					(thickness 0.15)
				)
			)
		)
		(property "Author" "Antmicro"
			(at 0 0 0)
			(layer "B.Fab")
			(hide yes)
			(effects
				(font
					(size 1 1)
					(thickness 0.15)
				)
				(justify mirror)
			)
		)
		(property "Dielectric" "X5R"
			(at 0 0 0)
			(layer "B.Fab")
			(hide yes)
			(effects
				(font
					(size 1 1)
					(thickness 0.15)
				)
				(justify mirror)
			)
		)
		(property "License" "Apache-2.0"
			(at 0 0 0)
			(layer "B.Fab")
			(hide yes)
			(effects
				(font
					(size 1 1)
					(thickness 0.15)
				)
				(justify mirror)
			)
		)
		(property "MPN" "C1005X6S1A105K050BC"
			(at 0 0 0)
			(layer "B.Fab")
			(hide yes)
			(effects
				(font
					(size 1 1)
					(thickness 0.15)
				)
				(justify mirror)
			)
		)
		(property "Manufacturer" "TDK"
			(at 0 0 0)
			(layer "B.Fab")
			(hide yes)
			(effects
				(font
					(size 1 1)
					(thickness 0.15)
				)
				(justify mirror)
			)
		)
		(property "Public" ""
			(at 0 0 0)
			(layer "B.Fab")
			(hide yes)
			(effects
				(font
					(size 1 1)
					(thickness 0.15)
				)
				(justify mirror)
			)
		)
		(property "Val" "1u"
			(at 0 0 0)
			(layer "B.Fab")
			(hide yes)
			(effects
				(font
					(size 1 1)
					(thickness 0.15)
				)
				(justify mirror)
			)
		)
		(property "Voltage" "16V"
			(at 0 0 0)
			(layer "B.Fab")
			(hide yes)
			(effects
				(font
					(size 1 1)
					(thickness 0.15)
				)
				(justify mirror)
			)
		)
		(sheetname "/LPDDR4/")
		(sheetfile "lpddr.kicad_sch")
		(attr smd)
		(fp_rect
			(start -0.925 0.47)
			(end 0.925 -0.47)
			(stroke
				(width 0.05)
				(type default)
			)
			(fill no)
			(layer "B.CrtYd")
		)
		(fp_line
			(start -0.494 -0.248)
			(end -0.494 0.25)
			(stroke
				(width 0.15)
				(type solid)
			)
			(layer "B.Fab")
		)
		(fp_line
			(start -0.494 0.25)
			(end 0.504 0.25)
			(stroke
				(width 0.15)
				(type solid)
			)
			(layer "B.Fab")
		)
		(fp_line
			(start 0.504 -0.248)
			(end -0.494 -0.248)
			(stroke
				(width 0.15)
				(type solid)
			)
			(layer "B.Fab")
		)
		(fp_line
			(start 0.504 0.25)
			(end 0.504 -0.248)
			(stroke
				(width 0.15)
				(type solid)
			)
			(layer "B.Fab")
		)
		(fp_text user "License: Apache-2.0"
			(at -0.939 -5.799 180)
			(layer "B.Fab")
			(effects
				(font
					(size 0.7 0.7)
					(thickness 0.15)
				)
				(justify left bottom mirror)
			)
		)
		(fp_text user "${REFERENCE}"
			(at -0.939 -4.599 180)
			(layer "B.Fab")
			(effects
				(font
					(size 0.7 0.7)
					(thickness 0.15)
				)
				(justify left bottom mirror)
			)
		)
		(fp_text user "Author: Antmicro"
			(at -0.939 -3.399 180)
			(layer "B.Fab")
			(effects
				(font
					(size 0.7 0.7)
					(thickness 0.15)
				)
				(justify left bottom mirror)
			)
		)
		(pad "1" smd roundrect
			(at -0.48 0)
			(size 0.59 0.64)
			(layers "B.Cu" "B.Mask" "B.Paste")
			(roundrect_rratio 0.25)
			(net 417 "GND")
			(pintype "passive")
		)
		(pad "2" smd roundrect
			(at 0.48 0)
			(size 0.59 0.64)
			(layers "B.Cu" "B.Mask" "B.Paste")
			(roundrect_rratio 0.25)
			(net 2 "+1V1")
			(pintype "passive")
		)
	)
	(footprint "antmicro-footprints:R_0603_1608Metric"
		(layer "B.Cu")
		(at 176.61 144.7 -90)
		(descr "Resistor SMD 0603")
		(tags "resistor SMD 0603")
		(property "Reference" "R48"
			(at -2.14 -1.54 270)
			(layer "B.SilkS")
			(effects
				(font
					(size 0.7 0.7)
					(thickness 0.15)
				)
				(justify left bottom mirror)
			)
		)
		(property "Value" "R_0R01_0603"
			(at 0 -1.6 90)
			(layer "B.Fab")
			(hide yes)
			(effects
				(font
					(size 0.7 0.7)
					(thickness 0.15)
				)
				(justify left bottom mirror)
			)
		)
		(property "Datasheet" "https://www.bourns.com/docs/product-datasheets/cfn-a.pdf"
			(at 0 0 270)
			(layer "F.Fab")
			(hide yes)
			(effects
				(font
					(size 1.27 1.27)
					(thickness 0.15)
				)
			)
		)
		(property "Description" "SMD Chip Resistor, 10 mohm, ± 1%, 0.5 W, 0603 [1608 Metric], Metal Foil, Current Sensing"
			(at 0 0 270)
			(layer "F.Fab")
			(hide yes)
			(effects
				(font
					(size 1.27 1.27)
					(thickness 0.15)
				)
			)
		)
		(property "Author" "Antmicro"
			(at 31.91 321.31 0)
			(layer "B.Fab")
			(hide yes)
			(effects
				(font
					(size 1 1)
					(thickness 0.15)
				)
				(justify mirror)
			)
		)
		(property "License" "Apache-2.0"
			(at 31.91 321.31 0)
			(layer "B.Fab")
			(hide yes)
			(effects
				(font
					(size 1 1)
					(thickness 0.15)
				)
				(justify mirror)
			)
		)
		(property "MPN" "CFN0603AFZ-R010ELF"
			(at 31.91 321.31 0)
			(layer "B.Fab")
			(hide yes)
			(effects
				(font
					(size 1 1)
					(thickness 0.15)
				)
				(justify mirror)
			)
		)
		(property "Manufacturer" "Bourns"
			(at 31.91 321.31 0)
			(layer "B.Fab")
			(hide yes)
			(effects
				(font
					(size 1 1)
					(thickness 0.15)
				)
				(justify mirror)
			)
		)
		(property "Public" ""
			(at 31.91 321.31 0)
			(layer "B.Fab")
			(hide yes)
			(effects
				(font
					(size 1 1)
					(thickness 0.15)
				)
				(justify mirror)
			)
		)
		(property "Tolerance" "1%"
			(at 31.91 321.31 0)
			(layer "B.Fab")
			(hide yes)
			(effects
				(font
					(size 1 1)
					(thickness 0.15)
				)
				(justify mirror)
			)
		)
		(property "Val" "0R01"
			(at 31.91 321.31 0)
			(layer "B.Fab")
			(hide yes)
			(effects
				(font
					(size 1 1)
					(thickness 0.15)
				)
				(justify mirror)
			)
		)
		(sheetname "/Supply/")
		(sheetfile "supply.kicad_sch")
		(attr smd)
		(fp_line
			(start -0.15 0.4)
			(end 0.15 0.4)
			(stroke
				(width 0.15)
				(type solid)
			)
			(layer "B.SilkS")
		)
		(fp_line
			(start -0.15 -0.4)
			(end 0.15 -0.4)
			(stroke
				(width 0.15)
				(type solid)
			)
			(layer "B.SilkS")
		)
		(fp_rect
			(start -1.25 0.65)
			(end 1.25 -0.65)
			(stroke
				(width 0.05)
				(type solid)
			)
			(fill no)
			(layer "B.CrtYd")
		)
		(fp_rect
			(start -0.8 0.4)
			(end 0.8 -0.4)
			(stroke
				(width 0.15)
				(type solid)
			)
			(fill no)
			(layer "B.Fab")
		)
		(fp_text user "Author: Antmicro"
			(at -1.25 -4.9 90)
			(layer "B.Fab")
			(effects
				(font
					(size 0.7 0.7)
					(thickness 0.15)
				)
				(justify left bottom mirror)
			)
		)
		(fp_text user "License: Apache-2.0"
			(at -1.25 -5.9 90)
			(layer "B.Fab")
			(effects
				(font
					(size 0.7 0.7)
					(thickness 0.15)
				)
				(justify left bottom mirror)
			)
		)
		(fp_text user "${REFERENCE}"
			(at -1.25 -3.898 90)
			(layer "B.Fab")
			(effects
				(font
					(size 0.7 0.7)
					(thickness 0.15)
				)
				(justify left bottom mirror)
			)
		)
		(pad "1" smd roundrect
			(at -0.7 0 270)
			(size 0.8 1)
			(layers "B.Cu" "B.Mask" "B.Paste")
			(roundrect_rratio 0.2)
			(net 406 "/Supply/SENSE2_P")
			(pintype "passive")
		)
		(pad "2" smd roundrect
			(at 0.7 0 270)
			(size 0.8 1)
			(layers "B.Cu" "B.Mask" "B.Paste")
			(roundrect_rratio 0.2)
			(net 48 "+1V8")
			(pintype "passive")
		)
	)
	(footprint "antmicro-footprints:C_0402_1005Metric"
		(layer "B.Cu")
		(at 213.861 121.754 180)
		(descr "Capacitor SMD 0402")
		(tags "capacitor SMD 0402")
		(property "Reference" "C252"
			(at -15.364 -13.121 0)
			(layer "B.SilkS")
			(effects
				(font
					(size 0.7 0.7)
					(thickness 0.15)
				)
				(justify left bottom mirror)
			)
		)
		(property "Value" "C_100n_0402"
			(at -1.022927 -2.155213 0)
			(layer "B.Fab")
			(hide yes)
			(effects
				(font
					(size 0.7 0.7)
					(thickness 0.15)
				)
				(justify left bottom mirror)
			)
		)
		(property "Datasheet" "https://www.murata.com/products/productdetail?partno=GRM155R61H104KE14%23"
			(at 0 0 180)
			(layer "F.Fab")
			(hide yes)
			(effects
				(font
					(size 1.27 1.27)
					(thickness 0.15)
				)
			)
		)
		(property "Description" "SMD Multilayer Ceramic Capacitor, 0.1 µF, 50 V, 0402 [1005 Metric], ± 10%, X5R, GRM Series"
			(at 0 0 180)
			(layer "F.Fab")
			(hide yes)
			(effects
				(font
					(size 1.27 1.27)
					(thickness 0.15)
				)
			)
		)
		(property "Author" "Antmicro"
			(at 427.722 243.508 0)
			(layer "B.Fab")
			(hide yes)
			(effects
				(font
					(size 1 1)
					(thickness 0.15)
				)
				(justify mirror)
			)
		)
		(property "Dielectric" "X5R"
			(at 427.722 243.508 0)
			(layer "B.Fab")
			(hide yes)
			(effects
				(font
					(size 1 1)
					(thickness 0.15)
				)
				(justify mirror)
			)
		)
		(property "License" "Apache-2.0"
			(at 427.722 243.508 0)
			(layer "B.Fab")
			(hide yes)
			(effects
				(font
					(size 1 1)
					(thickness 0.15)
				)
				(justify mirror)
			)
		)
		(property "MPN" "GRM155R61H104KE14D"
			(at 427.722 243.508 0)
			(layer "B.Fab")
			(hide yes)
			(effects
				(font
					(size 1 1)
					(thickness 0.15)
				)
				(justify mirror)
			)
		)
		(property "Manufacturer" "Murata"
			(at 427.722 243.508 0)
			(layer "B.Fab")
			(hide yes)
			(effects
				(font
					(size 1 1)
					(thickness 0.15)
				)
				(justify mirror)
			)
		)
		(property "Public" ""
			(at 427.722 243.508 0)
			(layer "B.Fab")
			(hide yes)
			(effects
				(font
					(size 1 1)
					(thickness 0.15)
				)
				(justify mirror)
			)
		)
		(property "Val" "100n"
			(at 427.722 243.508 0)
			(layer "B.Fab")
			(hide yes)
			(effects
				(font
					(size 1 1)
					(thickness 0.15)
				)
				(justify mirror)
			)
		)
		(property "Voltage" "50V"
			(at 427.722 243.508 0)
			(layer "B.Fab")
			(hide yes)
			(effects
				(font
					(size 1 1)
					(thickness 0.15)
				)
				(justify mirror)
			)
		)
		(sheetname "/Ethernet/")
		(sheetfile "ethernet.kicad_sch")
		(attr smd)
		(fp_rect
			(start -0.925 0.47)
			(end 0.925 -0.47)
			(stroke
				(width 0.05)
				(type default)
			)
			(fill no)
			(layer "B.CrtYd")
		)
		(fp_line
			(start 0.504 0.25)
			(end 0.504 -0.248)
			(stroke
				(width 0.15)
				(type solid)
			)
			(layer "B.Fab")
		)
		(fp_line
			(start 0.504 -0.248)
			(end -0.494 -0.248)
			(stroke
				(width 0.15)
				(type solid)
			)
			(layer "B.Fab")
		)
		(fp_line
			(start -0.494 0.25)
			(end 0.504 0.25)
			(stroke
				(width 0.15)
				(type solid)
			)
			(layer "B.Fab")
		)
		(fp_line
			(start -0.494 -0.248)
			(end -0.494 0.25)
			(stroke
				(width 0.15)
				(type solid)
			)
			(layer "B.Fab")
		)
		(fp_text user "Author: Antmicro"
			(at -0.939 -3.399 0)
			(layer "B.Fab")
			(effects
				(font
					(size 0.7 0.7)
					(thickness 0.15)
				)
				(justify left bottom mirror)
			)
		)
		(fp_text user "${REFERENCE}"
			(at -0.939 -4.599 0)
			(layer "B.Fab")
			(effects
				(font
					(size 0.7 0.7)
					(thickness 0.15)
				)
				(justify left bottom mirror)
			)
		)
		(fp_text user "License: Apache-2.0"
			(at -0.939 -5.799 0)
			(layer "B.Fab")
			(effects
				(font
					(size 0.7 0.7)
					(thickness 0.15)
				)
				(justify left bottom mirror)
			)
		)
		(pad "1" smd roundrect
			(at -0.48 0 180)
			(size 0.59 0.64)
			(layers "B.Cu" "B.Mask" "B.Paste")
			(roundrect_rratio 0.25)
			(net 417 "GND")
			(pintype "passive")
		)
		(pad "2" smd roundrect
			(at 0.48 0 180)
			(size 0.59 0.64)
			(layers "B.Cu" "B.Mask" "B.Paste")
			(roundrect_rratio 0.25)
			(net 47 "+1V05")
			(pintype "passive")
		)
	)
	(footprint "antmicro-footprints:C_Array_0508_1220Metric"
		(layer "B.Cu")
		(at 196.34 142.85 180)
		(property "Reference" "C172"
			(at 1.18 1.59 90)
			(layer "B.SilkS")
			(effects
				(font
					(size 0.7 0.7)
					(thickness 0.15)
				)
				(justify left bottom mirror)
			)
		)
		(property "Value" "C_4x100nF_0508_1220Metric_array"
			(at 0 -2.8 0)
			(layer "B.Fab")
			(hide yes)
			(effects
				(font
					(size 0.7 0.7)
					(thickness 0.15)
				)
				(justify left bottom mirror)
			)
		)
		(property "Datasheet" "https://spicat.kyocera-avx.com/product/mlcc/chartview/W2A4YC104MAT2A/"
			(at 0 0 180)
			(layer "F.Fab")
			(hide yes)
			(effects
				(font
					(size 1.27 1.27)
					(thickness 0.15)
				)
			)
		)
		(property "Description" "4x0.1µF isolated capacitor array 16 V X7R 0508 (1220 Metric)"
			(at 0 0 180)
			(layer "F.Fab")
			(hide yes)
			(effects
				(font
					(size 1.27 1.27)
					(thickness 0.15)
				)
			)
		)
		(property "Author" "Antmicro"
			(at 392.68 285.7 0)
			(layer "B.Fab")
			(hide yes)
			(effects
				(font
					(size 1 1)
					(thickness 0.15)
				)
				(justify mirror)
			)
		)
		(property "Dielectric" "X7R"
			(at 392.68 285.7 0)
			(layer "B.Fab")
			(hide yes)
			(effects
				(font
					(size 1 1)
					(thickness 0.15)
				)
				(justify mirror)
			)
		)
		(property "License" "Apache-2.0"
			(at 392.68 285.7 0)
			(layer "B.Fab")
			(hide yes)
			(effects
				(font
					(size 1 1)
					(thickness 0.15)
				)
				(justify mirror)
			)
		)
		(property "MPN" "W2A4YC104MAT2A"
			(at 392.68 285.7 0)
			(layer "B.Fab")
			(hide yes)
			(effects
				(font
					(size 1 1)
					(thickness 0.15)
				)
				(justify mirror)
			)
		)
		(property "Manufacturer" "KYOCERA AVX"
			(at 392.68 285.7 0)
			(layer "B.Fab")
			(hide yes)
			(effects
				(font
					(size 1 1)
					(thickness 0.15)
				)
				(justify mirror)
			)
		)
		(property "Val" "4x100nF"
			(at 392.68 285.7 0)
			(layer "B.Fab")
			(hide yes)
			(effects
				(font
					(size 1 1)
					(thickness 0.15)
				)
				(justify mirror)
			)
		)
		(property "Voltage" "16V"
			(at 392.68 285.7 0)
			(layer "B.Fab")
			(hide yes)
			(effects
				(font
					(size 1 1)
					(thickness 0.15)
				)
				(justify mirror)
			)
		)
		(sheetname "/PCIe/")
		(sheetfile "pcie.kicad_sch")
		(attr smd)
		(fp_circle
			(center -1.21 0.75)
			(end -1.16 0.75)
			(stroke
				(width 0.15)
				(type solid)
			)
			(fill yes)
			(layer "B.SilkS")
		)
		(fp_rect
			(start -1.09 1.2)
			(end 1.09 -1.2)
			(stroke
				(width 0.05)
				(type solid)
			)
			(fill no)
			(layer "B.CrtYd")
		)
		(fp_line
			(start 0.65 1.05)
			(end 0.65 -1.05)
			(stroke
				(width 0.15)
				(type solid)
			)
			(layer "B.Fab")
		)
		(fp_line
			(start 0.65 -1.05)
			(end -0.65 -1.05)
			(stroke
				(width 0.15)
				(type solid)
			)
			(layer "B.Fab")
		)
		(fp_line
			(start -0.65 1.05)
			(end 0.65 1.05)
			(stroke
				(width 0.15)
				(type solid)
			)
			(layer "B.Fab")
		)
		(fp_line
			(start -0.65 -1.05)
			(end -0.65 1.05)
			(stroke
				(width 0.15)
				(type solid)
			)
			(layer "B.Fab")
		)
		(fp_text user "Author: Antmicro"
			(at -1.26 -7.2 0)
			(layer "B.Fab")
			(effects
				(font
					(size 0.7 0.7)
					(thickness 0.15)
				)
				(justify left bottom mirror)
			)
		)
		(fp_text user "${REFERENCE}"
			(at -1.26 -6 0)
			(layer "B.Fab")
			(effects
				(font
					(size 0.7 0.7)
					(thickness 0.15)
				)
				(justify left bottom mirror)
			)
		)
		(fp_text user "License: Apache-2.0"
			(at -1.26 -4.8 0)
			(layer "B.Fab")
			(effects
				(font
					(size 0.7 0.7)
					(thickness 0.15)
				)
				(justify left bottom mirror)
			)
		)
		(pad "1" smd roundrect
			(at -0.66 0.75 270)
			(size 0.3 0.56)
			(layers "B.Cu" "B.Mask" "B.Paste")
			(roundrect_rratio 0.25)
			(net 37 "/Bottom Connector/PCIE.TXD2_P")
			(pinfunction "R1.1")
			(pintype "passive")
		)
		(pad "2" smd roundrect
			(at -0.66 0.25 270)
			(size 0.3 0.56)
			(layers "B.Cu" "B.Mask" "B.Paste")
			(roundrect_rratio 0.25)
			(net 38 "/Bottom Connector/PCIE.TXD2_N")
			(pinfunction "R2.1")
			(pintype "passive")
		)
		(pad "3" smd roundrect
			(at -0.66 -0.25 270)
			(size 0.3 0.56)
			(layers "B.Cu" "B.Mask" "B.Paste")
			(roundrect_rratio 0.25)
			(net 39 "/Bottom Connector/PCIE.TXD3_P")
			(pinfunction "R3.1")
			(pintype "passive")
		)
		(pad "4" smd roundrect
			(at -0.66 -0.75 270)
			(size 0.3 0.56)
			(layers "B.Cu" "B.Mask" "B.Paste")
			(roundrect_rratio 0.25)
			(net 40 "/Bottom Connector/PCIE.TXD3_N")
			(pinfunction "R4.1")
			(pintype "passive")
		)
		(pad "5" smd roundrect
			(at 0.66 -0.75 270)
			(size 0.3 0.56)
			(layers "B.Cu" "B.Mask" "B.Paste")
			(roundrect_rratio 0.25)
			(net 66 "/PCIe/XCVR_TX3_N")
			(pinfunction "R4.2")
			(pintype "passive")
		)
		(pad "6" smd roundrect
			(at 0.66 -0.25 270)
			(size 0.3 0.56)
			(layers "B.Cu" "B.Mask" "B.Paste")
			(roundrect_rratio 0.25)
			(net 91 "/PCIe/XCVR_TX3_P")
			(pinfunction "R3.2")
			(pintype "passive")
		)
		(pad "7" smd roundrect
			(at 0.66 0.25 270)
			(size 0.3 0.56)
			(layers "B.Cu" "B.Mask" "B.Paste")
			(roundrect_rratio 0.25)
			(net 93 "/PCIe/XCVR_TX2_N")
			(pinfunction "R2.2")
			(pintype "passive")
		)
		(pad "8" smd roundrect
			(at 0.66 0.75 270)
			(size 0.3 0.56)
			(layers "B.Cu" "B.Mask" "B.Paste")
			(roundrect_rratio 0.25)
			(net 95 "/PCIe/XCVR_TX2_P")
			(pinfunction "R1.2")
			(pintype "passive")
		)
	)
	(footprint "antmicro-footprints:C_0402_1005Metric"
		(layer "B.Cu")
		(at 219.911 119.7234)
		(descr "Capacitor SMD 0402")
		(tags "capacitor SMD 0402")
		(property "Reference" "C192"
			(at 6.539 4.2266 0)
			(layer "B.SilkS")
			(effects
				(font
					(size 0.7 0.7)
					(thickness 0.15)
				)
				(justify right bottom mirror)
			)
		)
		(property "Value" "C_10u_0402"
			(at -1.022927 -2.155213 0)
			(layer "B.Fab")
			(hide yes)
			(effects
				(font
					(size 0.7 0.7)
					(thickness 0.15)
				)
				(justify right bottom mirror)
			)
		)
		(property "Datasheet" "https://www.yageo.com/en/Chart/Download/pdf/CC0402MRX5R5BB106"
			(at 0 0 0)
			(layer "F.Fab")
			(hide yes)
			(effects
				(font
					(size 1.27 1.27)
					(thickness 0.15)
				)
			)
		)
		(property "Description" "SMD Multilayer Ceramic Capacitor, 10 µF, 6.3 V, 0402 [1005 Metric], ± 20%, X5R, CC Series"
			(at 0 0 0)
			(layer "F.Fab")
			(hide yes)
			(effects
				(font
					(size 1.27 1.27)
					(thickness 0.15)
				)
			)
		)
		(property "Author" "Antmicro"
			(at 0 0 0)
			(layer "B.Fab")
			(hide yes)
			(effects
				(font
					(size 1 1)
					(thickness 0.15)
				)
				(justify mirror)
			)
		)
		(property "Dielectric" ""
			(at 0 0 0)
			(layer "B.Fab")
			(hide yes)
			(effects
				(font
					(size 1 1)
					(thickness 0.15)
				)
				(justify mirror)
			)
		)
		(property "License" "Apache-2.0"
			(at 0 0 0)
			(layer "B.Fab")
			(hide yes)
			(effects
				(font
					(size 1 1)
					(thickness 0.15)
				)
				(justify mirror)
			)
		)
		(property "MPN" "CC0402MRX5R5BB106"
			(at 0 0 0)
			(layer "B.Fab")
			(hide yes)
			(effects
				(font
					(size 1 1)
					(thickness 0.15)
				)
				(justify mirror)
			)
		)
		(property "Manufacturer" "YAGEO"
			(at 0 0 0)
			(layer "B.Fab")
			(hide yes)
			(effects
				(font
					(size 1 1)
					(thickness 0.15)
				)
				(justify mirror)
			)
		)
		(property "Public" ""
			(at 0 0 0)
			(layer "B.Fab")
			(hide yes)
			(effects
				(font
					(size 1 1)
					(thickness 0.15)
				)
				(justify mirror)
			)
		)
		(property "Val" "10u"
			(at 0 0 0)
			(layer "B.Fab")
			(hide yes)
			(effects
				(font
					(size 1 1)
					(thickness 0.15)
				)
				(justify mirror)
			)
		)
		(property "Voltage" ""
			(at 0 0 0)
			(layer "B.Fab")
			(hide yes)
			(effects
				(font
					(size 1 1)
					(thickness 0.15)
				)
				(justify mirror)
			)
		)
		(sheetname "/Ethernet/")
		(sheetfile "ethernet.kicad_sch")
		(attr smd)
		(fp_rect
			(start -0.925 0.47)
			(end 0.925 -0.47)
			(stroke
				(width 0.05)
				(type default)
			)
			(fill no)
			(layer "B.CrtYd")
		)
		(fp_line
			(start -0.494 -0.248)
			(end -0.494 0.25)
			(stroke
				(width 0.15)
				(type solid)
			)
			(layer "B.Fab")
		)
		(fp_line
			(start -0.494 0.25)
			(end 0.504 0.25)
			(stroke
				(width 0.15)
				(type solid)
			)
			(layer "B.Fab")
		)
		(fp_line
			(start 0.504 -0.248)
			(end -0.494 -0.248)
			(stroke
				(width 0.15)
				(type solid)
			)
			(layer "B.Fab")
		)
		(fp_line
			(start 0.504 0.25)
			(end 0.504 -0.248)
			(stroke
				(width 0.15)
				(type solid)
			)
			(layer "B.Fab")
		)
		(fp_text user "License: Apache-2.0"
			(at -0.939 -5.799 180)
			(layer "B.Fab")
			(effects
				(font
					(size 0.7 0.7)
					(thickness 0.15)
				)
				(justify left bottom mirror)
			)
		)
		(fp_text user "${REFERENCE}"
			(at -0.939 -4.599 180)
			(layer "B.Fab")
			(effects
				(font
					(size 0.7 0.7)
					(thickness 0.15)
				)
				(justify left bottom mirror)
			)
		)
		(fp_text user "Author: Antmicro"
			(at -0.939 -3.399 180)
			(layer "B.Fab")
			(effects
				(font
					(size 0.7 0.7)
					(thickness 0.15)
				)
				(justify left bottom mirror)
			)
		)
		(pad "1" smd roundrect
			(at -0.48 0)
			(size 0.59 0.64)
			(layers "B.Cu" "B.Mask" "B.Paste")
			(roundrect_rratio 0.25)
			(net 417 "GND")
			(pintype "passive")
		)
		(pad "2" smd roundrect
			(at 0.48 0)
			(size 0.59 0.64)
			(layers "B.Cu" "B.Mask" "B.Paste")
			(roundrect_rratio 0.25)
			(net 418 "+2V5")
			(pintype "passive")
		)
	)
	(footprint "antmicro-footprints:R_0402_1005Metric"
		(layer "B.Cu")
		(at 225.6 145.345 180)
		(descr "Resistor SMD 0402")
		(tags "resistor SMD 0402")
		(property "Reference" "R151"
			(at -3.8 -0.405 0)
			(layer "B.SilkS")
			(effects
				(font
					(size 0.7 0.7)
					(thickness 0.15)
				)
				(justify left bottom mirror)
			)
		)
		(property "Value" "R_10k_0402"
			(at -1.011843 -1.772047 0)
			(layer "B.Fab")
			(hide yes)
			(effects
				(font
					(size 0.7 0.7)
					(thickness 0.15)
				)
				(justify left bottom mirror)
			)
		)
		(property "Datasheet" "https://www.bourns.com/docs/product-datasheets/cr.pdf"
			(at 0 0 180)
			(layer "F.Fab")
			(hide yes)
			(effects
				(font
					(size 1.27 1.27)
					(thickness 0.15)
				)
			)
		)
		(property "Description" "SMD Chip Resistor, 10 kohm, ± 1%, 62.5 mW, 0402 [1005 Metric], Thick Film, General Purpose"
			(at 0 0 180)
			(layer "F.Fab")
			(hide yes)
			(effects
				(font
					(size 1.27 1.27)
					(thickness 0.15)
				)
			)
		)
		(property "Author" "Antmicro"
			(at 451.2 290.69 0)
			(layer "B.Fab")
			(hide yes)
			(effects
				(font
					(size 1 1)
					(thickness 0.15)
				)
				(justify mirror)
			)
		)
		(property "License" "Apache-2.0"
			(at 451.2 290.69 0)
			(layer "B.Fab")
			(hide yes)
			(effects
				(font
					(size 1 1)
					(thickness 0.15)
				)
				(justify mirror)
			)
		)
		(property "MPN" "CR0402-FX-1002GLF"
			(at 451.2 290.69 0)
			(layer "B.Fab")
			(hide yes)
			(effects
				(font
					(size 1 1)
					(thickness 0.15)
				)
				(justify mirror)
			)
		)
		(property "Manufacturer" "Bourns"
			(at 451.2 290.69 0)
			(layer "B.Fab")
			(hide yes)
			(effects
				(font
					(size 1 1)
					(thickness 0.15)
				)
				(justify mirror)
			)
		)
		(property "Public" ""
			(at 451.2 290.69 0)
			(layer "B.Fab")
			(hide yes)
			(effects
				(font
					(size 1 1)
					(thickness 0.15)
				)
				(justify mirror)
			)
		)
		(property "Tolerance" "1%"
			(at 451.2 290.69 0)
			(layer "B.Fab")
			(hide yes)
			(effects
				(font
					(size 1 1)
					(thickness 0.15)
				)
				(justify mirror)
			)
		)
		(property "Val" "10k"
			(at 451.2 290.69 0)
			(layer "B.Fab")
			(hide yes)
			(effects
				(font
					(size 1 1)
					(thickness 0.15)
				)
				(justify mirror)
			)
		)
		(sheetname "/WiFi_Bluetooth/")
		(sheetfile "wifi_bt.kicad_sch")
		(attr smd)
		(fp_rect
			(start -0.925 0.47)
			(end 0.925 -0.47)
			(stroke
				(width 0.05)
				(type default)
			)
			(fill no)
			(layer "B.CrtYd")
		)
		(fp_rect
			(start -0.5 0.25)
			(end 0.5 -0.25)
			(stroke
				(width 0.15)
				(type solid)
			)
			(fill no)
			(layer "B.Fab")
		)
		(fp_text user "Author: Antmicro"
			(at -0.95 -4.169 0)
			(layer "B.Fab")
			(effects
				(font
					(size 0.7 0.7)
					(thickness 0.15)
				)
				(justify left bottom mirror)
			)
		)
		(fp_text user "${REFERENCE}"
			(at -0.95 -3.168 0)
			(layer "B.Fab")
			(effects
				(font
					(size 0.7 0.7)
					(thickness 0.15)
				)
				(justify left bottom mirror)
			)
		)
		(fp_text user "License: Apache-2.0"
			(at -0.95 -5.169 0)
			(layer "B.Fab")
			(effects
				(font
					(size 0.7 0.7)
					(thickness 0.15)
				)
				(justify left bottom mirror)
			)
		)
		(pad "1" smd roundrect
			(at -0.48 0 180)
			(size 0.59 0.64)
			(layers "B.Cu" "B.Mask" "B.Paste")
			(roundrect_rratio 0.25)
			(net 417 "GND")
			(pintype "passive")
		)
		(pad "2" smd roundrect
			(at 0.48 0 180)
			(size 0.59 0.64)
			(layers "B.Cu" "B.Mask" "B.Paste")
			(roundrect_rratio 0.25)
			(net 424 "/WiFi_Bluetooth/JTAG_SEL")
			(pintype "passive")
		)
	)
	(footprint "antmicro-footprints:TP_SMD_0.75mm"
		(layer "B.Cu")
		(at 197.75 145.15 180)
		(property "Reference" "TP24"
			(at -2.175 -1.15 135)
			(layer "B.SilkS")
			(hide yes)
			(effects
				(font
					(size 0.7 0.7)
					(thickness 0.15)
				)
				(justify left bottom mirror)
			)
		)
		(property "Value" "TP_0.75mm_SMD"
			(at 0 -1.2 0)
			(layer "B.Fab")
			(hide yes)
			(effects
				(font
					(size 0.7 0.7)
					(thickness 0.15)
				)
				(justify left bottom mirror)
			)
		)
		(property "Description" "SMT test point"
			(at 0 0 0)
			(layer "B.Fab")
			(hide yes)
			(effects
				(font
					(size 1.27 1.27)
					(thickness 0.15)
				)
				(justify mirror)
			)
		)
		(property "MPN" ""
			(at 0 0 0)
			(unlocked yes)
			(layer "B.Fab")
			(hide yes)
			(effects
				(font
					(size 1 1)
					(thickness 0.15)
				)
				(justify mirror)
			)
		)
		(property "Manufacturer" ""
			(at 0 0 0)
			(unlocked yes)
			(layer "B.Fab")
			(hide yes)
			(effects
				(font
					(size 1 1)
					(thickness 0.15)
				)
				(justify mirror)
			)
		)
		(property "Author" "Antmicro"
			(at 0 0 0)
			(unlocked yes)
			(layer "B.Fab")
			(hide yes)
			(effects
				(font
					(size 1 1)
					(thickness 0.15)
				)
				(justify mirror)
			)
		)
		(property "License" "Apache-2.0"
			(at 0 0 0)
			(unlocked yes)
			(layer "B.Fab")
			(hide yes)
			(effects
				(font
					(size 1 1)
					(thickness 0.15)
				)
				(justify mirror)
			)
		)
		(property "Public" "False"
			(at 0 0 0)
			(unlocked yes)
			(layer "B.Fab")
			(hide yes)
			(effects
				(font
					(size 1 1)
					(thickness 0.15)
				)
				(justify mirror)
			)
		)
		(sheetname "/Supply/")
		(sheetfile "supply.kicad_sch")
		(attr exclude_from_pos_files exclude_from_bom)
		(fp_circle
			(center 0 0)
			(end 0.475 0)
			(stroke
				(width 0.05)
				(type default)
			)
			(fill no)
			(layer "B.CrtYd")
		)
		(fp_text user "Author: Antmicro"
			(at -0.4 -3.901 0)
			(layer "B.Fab")
			(effects
				(font
					(size 0.7 0.7)
					(thickness 0.15)
				)
				(justify left bottom mirror)
			)
		)
		(fp_text user "License: Apache-2.0"
			(at -0.4 -5.101 0)
			(layer "B.Fab")
			(effects
				(font
					(size 0.7 0.7)
					(thickness 0.15)
				)
				(justify left bottom mirror)
			)
		)
		(fp_text user "${REFERENCE}"
			(at -0.4 -2.7 0)
			(layer "B.Fab")
			(effects
				(font
					(size 0.7 0.7)
					(thickness 0.15)
				)
				(justify left bottom mirror)
			)
		)
		(pad "1" smd circle
			(at 0 0 180)
			(size 0.75 0.75)
			(layers "B.Cu" "B.Mask")
			(net 90 "+5V")
			(pinfunction "1")
			(pintype "passive")
		)
	)
	(footprint "antmicro-footprints:R_0402_1005Metric"
		(layer "B.Cu")
		(at 184.75 120.85 90)
		(descr "Resistor SMD 0402")
		(tags "resistor SMD 0402")
		(property "Reference" "R7"
			(at 0.4 -1.5 270)
			(layer "B.SilkS")
			(effects
				(font
					(size 0.7 0.7)
					(thickness 0.15)
				)
				(justify left bottom mirror)
			)
		)
		(property "Value" "R_0R_0402"
			(at -1.011843 -1.772047 270)
			(layer "B.Fab")
			(hide yes)
			(effects
				(font
					(size 0.7 0.7)
					(thickness 0.15)
				)
				(justify left bottom mirror)
			)
		)
		(property "Datasheet" "https://industrial.panasonic.com/cdbs/www-data/pdf/RDA0000/AOA0000C301.pdf"
			(at 0 0 90)
			(layer "F.Fab")
			(hide yes)
			(effects
				(font
					(size 1.27 1.27)
					(thickness 0.15)
				)
			)
		)
		(property "Description" "SMD Chip Resistor, Jumper, 0 ohm, 100 mW, 0402 [1005 Metric], Thick Film, General Purpose"
			(at 0 0 90)
			(layer "F.Fab")
			(hide yes)
			(effects
				(font
					(size 1.27 1.27)
					(thickness 0.15)
				)
			)
		)
		(property "Author" "Antmicro"
			(at 305.6 -63.9 0)
			(layer "B.Fab")
			(hide yes)
			(effects
				(font
					(size 1 1)
					(thickness 0.15)
				)
				(justify mirror)
			)
		)
		(property "Current" "1A"
			(at 305.6 -63.9 0)
			(layer "B.Fab")
			(hide yes)
			(effects
				(font
					(size 1 1)
					(thickness 0.15)
				)
				(justify mirror)
			)
		)
		(property "License" "Apache-2.0"
			(at 305.6 -63.9 0)
			(layer "B.Fab")
			(hide yes)
			(effects
				(font
					(size 1 1)
					(thickness 0.15)
				)
				(justify mirror)
			)
		)
		(property "MPN" "ERJ2GE0R00X"
			(at 305.6 -63.9 0)
			(layer "B.Fab")
			(hide yes)
			(effects
				(font
					(size 1 1)
					(thickness 0.15)
				)
				(justify mirror)
			)
		)
		(property "Manufacturer" "Panasonic"
			(at 305.6 -63.9 0)
			(layer "B.Fab")
			(hide yes)
			(effects
				(font
					(size 1 1)
					(thickness 0.15)
				)
				(justify mirror)
			)
		)
		(property "Public" ""
			(at 305.6 -63.9 0)
			(layer "B.Fab")
			(hide yes)
			(effects
				(font
					(size 1 1)
					(thickness 0.15)
				)
				(justify mirror)
			)
		)
		(property "Tolerance" "~"
			(at 305.6 -63.9 0)
			(layer "B.Fab")
			(hide yes)
			(effects
				(font
					(size 1 1)
					(thickness 0.15)
				)
				(justify mirror)
			)
		)
		(property "Val" "0R"
			(at 305.6 -63.9 0)
			(layer "B.Fab")
			(hide yes)
			(effects
				(font
					(size 1 1)
					(thickness 0.15)
				)
				(justify mirror)
			)
		)
		(sheetname "/Supply/")
		(sheetfile "supply.kicad_sch")
		(attr smd)
		(fp_rect
			(start -0.925 0.47)
			(end 0.925 -0.47)
			(stroke
				(width 0.05)
				(type default)
			)
			(fill no)
			(layer "B.CrtYd")
		)
		(fp_rect
			(start -0.5 0.25)
			(end 0.5 -0.25)
			(stroke
				(width 0.15)
				(type solid)
			)
			(fill no)
			(layer "B.Fab")
		)
		(fp_text user "${REFERENCE}"
			(at -0.95 -3.168 270)
			(layer "B.Fab")
			(effects
				(font
					(size 0.7 0.7)
					(thickness 0.15)
				)
				(justify left bottom mirror)
			)
		)
		(fp_text user "Author: Antmicro"
			(at -0.95 -4.169 270)
			(layer "B.Fab")
			(effects
				(font
					(size 0.7 0.7)
					(thickness 0.15)
				)
				(justify left bottom mirror)
			)
		)
		(fp_text user "License: Apache-2.0"
			(at -0.95 -5.169 270)
			(layer "B.Fab")
			(effects
				(font
					(size 0.7 0.7)
					(thickness 0.15)
				)
				(justify left bottom mirror)
			)
		)
		(pad "1" smd roundrect
			(at -0.48 0 90)
			(size 0.59 0.64)
			(layers "B.Cu" "B.Mask" "B.Paste")
			(roundrect_rratio 0.25)
			(net 187 "/Supply/PWRON")
			(pintype "passive")
		)
		(pad "2" smd roundrect
			(at 0.48 0 90)
			(size 0.59 0.64)
			(layers "B.Cu" "B.Mask" "B.Paste")
			(roundrect_rratio 0.25)
			(net 212 "GLOBAL_EN")
			(pintype "passive")
		)
	)
	(footprint "antmicro-footprints:R_0402_1005Metric"
		(layer "B.Cu")
		(at 226.63 128.2 180)
		(descr "Resistor SMD 0402")
		(tags "resistor SMD 0402")
		(property "Reference" "R70"
			(at -2.92 -0.45 180)
			(layer "B.SilkS")
			(effects
				(font
					(size 0.7 0.7)
					(thickness 0.15)
				)
				(justify left bottom mirror)
			)
		)
		(property "Value" "R_590R_0402"
			(at -1.011843 -1.772047 0)
			(layer "B.Fab")
			(hide yes)
			(effects
				(font
					(size 0.7 0.7)
					(thickness 0.15)
				)
				(justify left bottom mirror)
			)
		)
		(property "Datasheet" "https://www.bourns.com/docs/product-datasheets/cr.pdf"
			(at 0 0 180)
			(layer "F.Fab")
			(hide yes)
			(effects
				(font
					(size 1.27 1.27)
					(thickness 0.15)
				)
			)
		)
		(property "Description" "SMD Chip Resistor, 590 ohm, ± 1%, 100 mW, 0402 [1005 Metric], Thick Film, Precision"
			(at 0 0 180)
			(layer "F.Fab")
			(hide yes)
			(effects
				(font
					(size 1.27 1.27)
					(thickness 0.15)
				)
			)
		)
		(property "Author" "Antmicro"
			(at 453.26 256.4 0)
			(layer "B.Fab")
			(hide yes)
			(effects
				(font
					(size 1 1)
					(thickness 0.15)
				)
				(justify mirror)
			)
		)
		(property "License" "Apache-2.0"
			(at 453.26 256.4 0)
			(layer "B.Fab")
			(hide yes)
			(effects
				(font
					(size 1 1)
					(thickness 0.15)
				)
				(justify mirror)
			)
		)
		(property "MPN" "CR0402-FX-5900GLF"
			(at 453.26 256.4 0)
			(layer "B.Fab")
			(hide yes)
			(effects
				(font
					(size 1 1)
					(thickness 0.15)
				)
				(justify mirror)
			)
		)
		(property "Manufacturer" "Bourns"
			(at 453.26 256.4 0)
			(layer "B.Fab")
			(hide yes)
			(effects
				(font
					(size 1 1)
					(thickness 0.15)
				)
				(justify mirror)
			)
		)
		(property "Public" ""
			(at 453.26 256.4 0)
			(layer "B.Fab")
			(hide yes)
			(effects
				(font
					(size 1 1)
					(thickness 0.15)
				)
				(justify mirror)
			)
		)
		(property "Tolerance" "1%"
			(at 453.26 256.4 0)
			(layer "B.Fab")
			(hide yes)
			(effects
				(font
					(size 1 1)
					(thickness 0.15)
				)
				(justify mirror)
			)
		)
		(property "Val" "590R"
			(at 453.26 256.4 0)
			(layer "B.Fab")
			(hide yes)
			(effects
				(font
					(size 1 1)
					(thickness 0.15)
				)
				(justify mirror)
			)
		)
		(sheetname "/FPGA GPIO/")
		(sheetfile "fpga-gpio.kicad_sch")
		(attr smd)
		(fp_rect
			(start -0.925 0.47)
			(end 0.925 -0.47)
			(stroke
				(width 0.05)
				(type default)
			)
			(fill no)
			(layer "B.CrtYd")
		)
		(fp_rect
			(start -0.5 0.25)
			(end 0.5 -0.25)
			(stroke
				(width 0.15)
				(type solid)
			)
			(fill no)
			(layer "B.Fab")
		)
		(fp_text user "License: Apache-2.0"
			(at -0.95 -5.169 0)
			(layer "B.Fab")
			(effects
				(font
					(size 0.7 0.7)
					(thickness 0.15)
				)
				(justify left bottom mirror)
			)
		)
		(fp_text user "${REFERENCE}"
			(at -0.95 -3.168 0)
			(layer "B.Fab")
			(effects
				(font
					(size 0.7 0.7)
					(thickness 0.15)
				)
				(justify left bottom mirror)
			)
		)
		(fp_text user "Author: Antmicro"
			(at -0.95 -4.169 0)
			(layer "B.Fab")
			(effects
				(font
					(size 0.7 0.7)
					(thickness 0.15)
				)
				(justify left bottom mirror)
			)
		)
		(pad "1" smd roundrect
			(at -0.48 0 180)
			(size 0.59 0.64)
			(layers "B.Cu" "B.Mask" "B.Paste")
			(roundrect_rratio 0.25)
			(net 542 "Net-(Q8-D)")
			(pintype "passive")
		)
		(pad "2" smd roundrect
			(at 0.48 0 180)
			(size 0.59 0.64)
			(layers "B.Cu" "B.Mask" "B.Paste")
			(roundrect_rratio 0.25)
			(net 385 "Net-(D6-C_{R})")
			(pintype "passive")
		)
	)
	(footprint "antmicro-footprints:R_0402_1005Metric"
		(layer "B.Cu")
		(at 211.5 147 -90)
		(descr "Resistor SMD 0402")
		(tags "resistor SMD 0402")
		(property "Reference" "R85"
			(at 0.9 -0.27 90)
			(layer "B.SilkS")
			(effects
				(font
					(size 0.7 0.7)
					(thickness 0.15)
				)
				(justify left bottom mirror)
			)
		)
		(property "Value" "R_10k_0402"
			(at -1.011843 -1.772047 90)
			(layer "B.Fab")
			(hide yes)
			(effects
				(font
					(size 0.7 0.7)
					(thickness 0.15)
				)
				(justify left bottom mirror)
			)
		)
		(property "Datasheet" "https://www.bourns.com/docs/product-datasheets/cr.pdf"
			(at 0 0 270)
			(layer "F.Fab")
			(hide yes)
			(effects
				(font
					(size 1.27 1.27)
					(thickness 0.15)
				)
			)
		)
		(property "Description" "SMD Chip Resistor, 10 kohm, ± 1%, 62.5 mW, 0402 [1005 Metric], Thick Film, General Purpose"
			(at 0 0 270)
			(layer "F.Fab")
			(hide yes)
			(effects
				(font
					(size 1.27 1.27)
					(thickness 0.15)
				)
			)
		)
		(property "Author" "Antmicro"
			(at 64.5 358.5 0)
			(layer "B.Fab")
			(hide yes)
			(effects
				(font
					(size 1 1)
					(thickness 0.15)
				)
				(justify mirror)
			)
		)
		(property "License" "Apache-2.0"
			(at 64.5 358.5 0)
			(layer "B.Fab")
			(hide yes)
			(effects
				(font
					(size 1 1)
					(thickness 0.15)
				)
				(justify mirror)
			)
		)
		(property "MPN" "CR0402-FX-1002GLF"
			(at 64.5 358.5 0)
			(layer "B.Fab")
			(hide yes)
			(effects
				(font
					(size 1 1)
					(thickness 0.15)
				)
				(justify mirror)
			)
		)
		(property "Manufacturer" "Bourns"
			(at 64.5 358.5 0)
			(layer "B.Fab")
			(hide yes)
			(effects
				(font
					(size 1 1)
					(thickness 0.15)
				)
				(justify mirror)
			)
		)
		(property "Public" ""
			(at 64.5 358.5 0)
			(layer "B.Fab")
			(hide yes)
			(effects
				(font
					(size 1 1)
					(thickness 0.15)
				)
				(justify mirror)
			)
		)
		(property "Tolerance" "1%"
			(at 64.5 358.5 0)
			(layer "B.Fab")
			(hide yes)
			(effects
				(font
					(size 1 1)
					(thickness 0.15)
				)
				(justify mirror)
			)
		)
		(property "Val" "10k"
			(at 64.5 358.5 0)
			(layer "B.Fab")
			(hide yes)
			(effects
				(font
					(size 1 1)
					(thickness 0.15)
				)
				(justify mirror)
			)
		)
		(sheetname "/USB/")
		(sheetfile "usb.kicad_sch")
		(attr smd)
		(fp_rect
			(start -0.925 0.47)
			(end 0.925 -0.47)
			(stroke
				(width 0.05)
				(type default)
			)
			(fill no)
			(layer "B.CrtYd")
		)
		(fp_rect
			(start -0.5 0.25)
			(end 0.5 -0.25)
			(stroke
				(width 0.15)
				(type solid)
			)
			(fill no)
			(layer "B.Fab")
		)
		(fp_text user "Author: Antmicro"
			(at -0.95 -4.169 90)
			(layer "B.Fab")
			(effects
				(font
					(size 0.7 0.7)
					(thickness 0.15)
				)
				(justify left bottom mirror)
			)
		)
		(fp_text user "License: Apache-2.0"
			(at -0.95 -5.169 90)
			(layer "B.Fab")
			(effects
				(font
					(size 0.7 0.7)
					(thickness 0.15)
				)
				(justify left bottom mirror)
			)
		)
		(fp_text user "${REFERENCE}"
			(at -0.95 -3.168 90)
			(layer "B.Fab")
			(effects
				(font
					(size 0.7 0.7)
					(thickness 0.15)
				)
				(justify left bottom mirror)
			)
		)
		(pad "1" smd roundrect
			(at -0.48 0 270)
			(size 0.59 0.64)
			(layers "B.Cu" "B.Mask" "B.Paste")
			(roundrect_rratio 0.25)
			(net 379 "/USB/RESETB")
			(pintype "passive")
		)
		(pad "2" smd roundrect
			(at 0.48 0 270)
			(size 0.59 0.64)
			(layers "B.Cu" "B.Mask" "B.Paste")
			(roundrect_rratio 0.25)
			(net 649 "VDD")
			(pintype "passive")
		)
	)
	(footprint "antmicro-footprints:C_0402_1005Metric"
		(layer "B.Cu")
		(at 215.6925 132.197 -90)
		(descr "Capacitor SMD 0402")
		(tags "capacitor SMD 0402")
		(property "Reference" "C73"
			(at -0.437 -2.1375 90)
			(layer "B.SilkS")
			(effects
				(font
					(size 0.7 0.7)
					(thickness 0.15)
				)
				(justify left bottom mirror)
			)
		)
		(property "Value" "C_100n_0402"
			(at -1.022927 -2.155213 90)
			(layer "B.Fab")
			(hide yes)
			(effects
				(font
					(size 0.7 0.7)
					(thickness 0.15)
				)
				(justify left bottom mirror)
			)
		)
		(property "Datasheet" "https://www.murata.com/products/productdetail?partno=GRM155R61H104KE14%23"
			(at 0 0 270)
			(layer "F.Fab")
			(hide yes)
			(effects
				(font
					(size 1.27 1.27)
					(thickness 0.15)
				)
			)
		)
		(property "Description" "SMD Multilayer Ceramic Capacitor, 0.1 µF, 50 V, 0402 [1005 Metric], ± 10%, X5R, GRM Series"
			(at 0 0 270)
			(layer "F.Fab")
			(hide yes)
			(effects
				(font
					(size 1.27 1.27)
					(thickness 0.15)
				)
			)
		)
		(property "Author" "Antmicro"
			(at 83.4955 347.8895 0)
			(layer "B.Fab")
			(hide yes)
			(effects
				(font
					(size 1 1)
					(thickness 0.15)
				)
				(justify mirror)
			)
		)
		(property "Dielectric" "X5R"
			(at 83.4955 347.8895 0)
			(layer "B.Fab")
			(hide yes)
			(effects
				(font
					(size 1 1)
					(thickness 0.15)
				)
				(justify mirror)
			)
		)
		(property "License" "Apache-2.0"
			(at 83.4955 347.8895 0)
			(layer "B.Fab")
			(hide yes)
			(effects
				(font
					(size 1 1)
					(thickness 0.15)
				)
				(justify mirror)
			)
		)
		(property "MPN" "GRM155R61H104KE14D"
			(at 83.4955 347.8895 0)
			(layer "B.Fab")
			(hide yes)
			(effects
				(font
					(size 1 1)
					(thickness 0.15)
				)
				(justify mirror)
			)
		)
		(property "Manufacturer" "Murata"
			(at 83.4955 347.8895 0)
			(layer "B.Fab")
			(hide yes)
			(effects
				(font
					(size 1 1)
					(thickness 0.15)
				)
				(justify mirror)
			)
		)
		(property "Public" ""
			(at 83.4955 347.8895 0)
			(layer "B.Fab")
			(hide yes)
			(effects
				(font
					(size 1 1)
					(thickness 0.15)
				)
				(justify mirror)
			)
		)
		(property "Val" "100n"
			(at 83.4955 347.8895 0)
			(layer "B.Fab")
			(hide yes)
			(effects
				(font
					(size 1 1)
					(thickness 0.15)
				)
				(justify mirror)
			)
		)
		(property "Voltage" "50V"
			(at 83.4955 347.8895 0)
			(layer "B.Fab")
			(hide yes)
			(effects
				(font
					(size 1 1)
					(thickness 0.15)
				)
				(justify mirror)
			)
		)
		(sheetname "/Memory/")
		(sheetfile "memory.kicad_sch")
		(attr smd)
		(fp_rect
			(start -0.925 0.47)
			(end 0.925 -0.47)
			(stroke
				(width 0.05)
				(type default)
			)
			(fill no)
			(layer "B.CrtYd")
		)
		(fp_line
			(start -0.494 0.25)
			(end 0.504 0.25)
			(stroke
				(width 0.15)
				(type solid)
			)
			(layer "B.Fab")
		)
		(fp_line
			(start 0.504 0.25)
			(end 0.504 -0.248)
			(stroke
				(width 0.15)
				(type solid)
			)
			(layer "B.Fab")
		)
		(fp_line
			(start -0.494 -0.248)
			(end -0.494 0.25)
			(stroke
				(width 0.15)
				(type solid)
			)
			(layer "B.Fab")
		)
		(fp_line
			(start 0.504 -0.248)
			(end -0.494 -0.248)
			(stroke
				(width 0.15)
				(type solid)
			)
			(layer "B.Fab")
		)
		(fp_text user "Author: Antmicro"
			(at -0.939 -3.399 90)
			(layer "B.Fab")
			(effects
				(font
					(size 0.7 0.7)
					(thickness 0.15)
				)
				(justify left bottom mirror)
			)
		)
		(fp_text user "License: Apache-2.0"
			(at -0.939 -5.799 90)
			(layer "B.Fab")
			(effects
				(font
					(size 0.7 0.7)
					(thickness 0.15)
				)
				(justify left bottom mirror)
			)
		)
		(fp_text user "${REFERENCE}"
			(at -0.939 -4.599 90)
			(layer "B.Fab")
			(effects
				(font
					(size 0.7 0.7)
					(thickness 0.15)
				)
				(justify left bottom mirror)
			)
		)
		(pad "1" smd roundrect
			(at -0.48 0 270)
			(size 0.59 0.64)
			(layers "B.Cu" "B.Mask" "B.Paste")
			(roundrect_rratio 0.25)
			(net 417 "GND")
			(pintype "passive")
		)
		(pad "2" smd roundrect
			(at 0.48 0 270)
			(size 0.59 0.64)
			(layers "B.Cu" "B.Mask" "B.Paste")
			(roundrect_rratio 0.25)
			(net 50 "+3V3")
			(pintype "passive")
		)
	)
	(footprint "antmicro-footprints:SOT-363"
		(layer "B.Cu")
		(at 186.075 152.127 90)
		(property "Reference" "Q3"
			(at 1.317 -1.415 180)
			(layer "B.SilkS")
			(effects
				(font
					(size 0.7 0.7)
					(thickness 0.15)
				)
				(justify right bottom mirror)
			)
		)
		(property "Value" "DZDH0401DW"
			(at 0 -2.2 90)
			(layer "B.Fab")
			(hide yes)
			(effects
				(font
					(size 0.7 0.7)
					(thickness 0.15)
				)
				(justify right bottom mirror)
			)
		)
		(property "Datasheet" "https://www.mouser.com/datasheet/2/115/DIOD_S_A0011803041_1-2543705.pdf"
			(at 0 0 90)
			(layer "F.Fab")
			(hide yes)
			(effects
				(font
					(size 1.27 1.27)
					(thickness 0.15)
				)
			)
		)
		(property "Description" "OR Controller N+1 ORing Controller P-Channel 1:1 SOT-363"
			(at 0 0 90)
			(layer "F.Fab")
			(hide yes)
			(effects
				(font
					(size 1.27 1.27)
					(thickness 0.15)
				)
			)
		)
		(property "Author" "Antmicro"
			(at 338.202 -33.948 0)
			(layer "B.Fab")
			(hide yes)
			(effects
				(font
					(size 1 1)
					(thickness 0.15)
				)
				(justify mirror)
			)
		)
		(property "License" "Apache-2.0"
			(at 338.202 -33.948 0)
			(layer "B.Fab")
			(hide yes)
			(effects
				(font
					(size 1 1)
					(thickness 0.15)
				)
				(justify mirror)
			)
		)
		(property "MPN" "DZDH0401DW"
			(at 338.202 -33.948 0)
			(layer "B.Fab")
			(hide yes)
			(effects
				(font
					(size 1 1)
					(thickness 0.15)
				)
				(justify mirror)
			)
		)
		(property "Manufacturer" "Diodes Incorporated"
			(at 338.202 -33.948 0)
			(layer "B.Fab")
			(hide yes)
			(effects
				(font
					(size 1 1)
					(thickness 0.15)
				)
				(justify mirror)
			)
		)
		(sheetname "/Bottom Connector/")
		(sheetfile "bottom-connector.kicad_sch")
		(attr smd)
		(fp_line
			(start -0.8 -1.223)
			(end 0.803 -1.223)
			(stroke
				(width 0.15)
				(type solid)
			)
			(layer "B.SilkS")
		)
		(fp_line
			(start 0.803 -1.146)
			(end 0.803 -1.223)
			(stroke
				(width 0.15)
				(type solid)
			)
			(layer "B.SilkS")
		)
		(fp_line
			(start -0.8 -1.146)
			(end -0.8 -1.223)
			(stroke
				(width 0.15)
				(type solid)
			)
			(layer "B.SilkS")
		)
		(fp_line
			(start 0.803 1.153)
			(end 0.803 1.228)
			(stroke
				(width 0.15)
				(type solid)
			)
			(layer "B.SilkS")
		)
		(fp_line
			(start -0.72 1.153)
			(end -0.72 1.228)
			(stroke
				(width 0.15)
				(type solid)
			)
			(layer "B.SilkS")
		)
		(fp_line
			(start 0.803 1.228)
			(end -0.72 1.228)
			(stroke
				(width 0.15)
				(type solid)
			)
			(layer "B.SilkS")
		)
		(fp_circle
			(center -0.978102 1.2)
			(end -0.928102 1.2)
			(stroke
				(width 0.15)
				(type solid)
			)
			(fill yes)
			(layer "B.SilkS")
		)
		(fp_rect
			(start 1.3 1.3)
			(end -1.3 -1.3)
			(stroke
				(width 0.05)
				(type solid)
			)
			(fill no)
			(layer "B.CrtYd")
		)
		(fp_line
			(start -0.1 1.1)
			(end -0.68 0.52)
			(stroke
				(width 0.15)
				(type solid)
			)
			(layer "B.Fab")
		)
		(fp_rect
			(start 0.68 -1.1)
			(end -0.68 1.1)
			(stroke
				(width 0.15)
				(type solid)
			)
			(fill no)
			(layer "B.Fab")
		)
		(fp_text user "License: Apache-2.0"
			(at -1.3 -5.2 270)
			(layer "B.Fab")
			(effects
				(font
					(size 0.7 0.7)
					(thickness 0.15)
				)
				(justify left bottom mirror)
			)
		)
		(fp_text user "Author: Antmicro"
			(at -1.3 -6.4 270)
			(layer "B.Fab")
			(effects
				(font
					(size 0.7 0.7)
					(thickness 0.15)
				)
				(justify left bottom mirror)
			)
		)
		(fp_text user "${REFERENCE}"
			(at -1.3 -4 270)
			(layer "B.Fab")
			(effects
				(font
					(size 0.7 0.7)
					(thickness 0.15)
				)
				(justify left bottom mirror)
			)
		)
		(pad "1" smd custom
			(at -0.948 0.752 180)
			(size 0.6 0.6)
			(layers "B.Cu" "B.Mask" "B.Paste")
			(net 653 "unconnected-(Q3-NC-Pad1)")
			(pinfunction "NC")
			(pintype "no_connect")
			(options
				(clearance outline)
				(anchor rect)
			)
			(primitives)
		)
		(pad "2" smd rect
			(at -0.948 0.002 180)
			(size 0.4 0.6)
			(layers "B.Cu" "B.Mask" "B.Paste")
			(net 275 "Net-(Q3-REF)")
			(pinfunction "REF")
			(pintype "input")
		)
		(pad "3" smd custom
			(at -0.948 -0.745 180)
			(size 0.6 0.6)
			(layers "B.Cu" "B.Mask" "B.Paste")
			(net 411 "Net-(Q3-BIAS)")
			(pinfunction "BIAS")
			(pintype "output")
			(options
				(clearance outline)
				(anchor rect)
			)
			(primitives)
		)
		(pad "4" smd custom
			(at 0.951 -0.745 180)
			(size 0.6 0.6)
			(layers "B.Cu" "B.Mask" "B.Paste")
			(net 90 "+5V")
			(pinfunction "S")
			(pintype "power_in")
			(options
				(clearance outline)
				(anchor rect)
			)
			(primitives)
		)
		(pad "5" smd rect
			(at 0.951 0.002 180)
			(size 0.4 0.6)
			(layers "B.Cu" "B.Mask" "B.Paste")
			(net 654 "unconnected-(Q3-NC-Pad5)")
			(pinfunction "NC")
			(pintype "no_connect")
		)
		(pad "6" smd custom
			(at 0.951 0.752 180)
			(size 0.6 0.6)
			(layers "B.Cu" "B.Mask" "B.Paste")
			(net 410 "Net-(Q3-D)")
			(pinfunction "D")
			(pintype "power_in")
			(options
				(clearance outline)
				(anchor rect)
			)
			(primitives)
		)
	)
	(footprint "antmicro-footprints:R_0402_1005Metric"
		(layer "B.Cu")
		(at 182.92 144.97 135)
		(descr "Resistor SMD 0402")
		(tags "resistor SMD 0402")
		(property "Reference" "R98"
			(at -0.749533 1.838478 315)
			(layer "B.SilkS")
			(effects
				(font
					(size 0.7 0.7)
					(thickness 0.15)
				)
				(justify right bottom mirror)
			)
		)
		(property "Value" "R_0R_0402"
			(at -1.011843 -1.772046 135)
			(layer "B.Fab")
			(hide yes)
			(effects
				(font
					(size 0.7 0.7)
					(thickness 0.15)
				)
				(justify right bottom mirror)
			)
		)
		(property "Datasheet" "https://industrial.panasonic.com/cdbs/www-data/pdf/RDA0000/AOA0000C301.pdf"
			(at 0 0 135)
			(layer "F.Fab")
			(hide yes)
			(effects
				(font
					(size 1.27 1.27)
					(thickness 0.15)
				)
			)
		)
		(property "Description" "SMD Chip Resistor, Jumper, 0 ohm, 100 mW, 0402 [1005 Metric], Thick Film, General Purpose"
			(at 0 0 135)
			(layer "F.Fab")
			(hide yes)
			(effects
				(font
					(size 1.27 1.27)
					(thickness 0.15)
				)
			)
		)
		(property "Author" "Antmicro"
			(at 414.773242 118.135298 0)
			(layer "B.Fab")
			(hide yes)
			(effects
				(font
					(size 1 1)
					(thickness 0.15)
				)
				(justify mirror)
			)
		)
		(property "Current" "1A"
			(at 414.773242 118.135298 0)
			(layer "B.Fab")
			(hide yes)
			(effects
				(font
					(size 1 1)
					(thickness 0.15)
				)
				(justify mirror)
			)
		)
		(property "License" "Apache-2.0"
			(at 414.773242 118.135298 0)
			(layer "B.Fab")
			(hide yes)
			(effects
				(font
					(size 1 1)
					(thickness 0.15)
				)
				(justify mirror)
			)
		)
		(property "MPN" "ERJ2GE0R00X"
			(at 414.773242 118.135298 0)
			(layer "B.Fab")
			(hide yes)
			(effects
				(font
					(size 1 1)
					(thickness 0.15)
				)
				(justify mirror)
			)
		)
		(property "Manufacturer" "Panasonic"
			(at 414.773242 118.135298 0)
			(layer "B.Fab")
			(hide yes)
			(effects
				(font
					(size 1 1)
					(thickness 0.15)
				)
				(justify mirror)
			)
		)
		(property "Public" ""
			(at 414.773242 118.135298 0)
			(layer "B.Fab")
			(hide yes)
			(effects
				(font
					(size 1 1)
					(thickness 0.15)
				)
				(justify mirror)
			)
		)
		(property "Tolerance" "~"
			(at 414.773242 118.135298 0)
			(layer "B.Fab")
			(hide yes)
			(effects
				(font
					(size 1 1)
					(thickness 0.15)
				)
				(justify mirror)
			)
		)
		(property "Val" "0R"
			(at 414.773242 118.135298 0)
			(layer "B.Fab")
			(hide yes)
			(effects
				(font
					(size 1 1)
					(thickness 0.15)
				)
				(justify mirror)
			)
		)
		(sheetname "/Supply/")
		(sheetfile "supply.kicad_sch")
		(attr smd)
		(fp_poly
			(pts
				(xy -0.925 0.47) (xy 0.925 0.47) (xy 0.925 -0.47) (xy -0.925 -0.47)
			)
			(stroke
				(width 0.05)
				(type default)
			)
			(fill no)
			(layer "B.CrtYd")
		)
		(fp_poly
			(pts
				(xy -0.5 0.25) (xy 0.5 0.25) (xy 0.5 -0.25) (xy -0.5 -0.25)
			)
			(stroke
				(width 0.15)
				(type solid)
			)
			(fill no)
			(layer "B.Fab")
		)
		(fp_text user "${REFERENCE}"
			(at -0.95 -3.168 315)
			(layer "B.Fab")
			(effects
				(font
					(size 0.7 0.7)
					(thickness 0.15)
				)
				(justify left bottom mirror)
			)
		)
		(fp_text user "License: Apache-2.0"
			(at -0.949999 -5.169 315)
			(layer "B.Fab")
			(effects
				(font
					(size 0.7 0.7)
					(thickness 0.15)
				)
				(justify left bottom mirror)
			)
		)
		(fp_text user "Author: Antmicro"
			(at -0.95 -4.169 315)
			(layer "B.Fab")
			(effects
				(font
					(size 0.7 0.7)
					(thickness 0.15)
				)
				(justify left bottom mirror)
			)
		)
		(pad "1" smd roundrect
			(at -0.48 0 135)
			(size 0.59 0.64)
			(layers "B.Cu" "B.Mask" "B.Paste")
			(roundrect_rratio 0.25)
			(net 409 "/Supply/SENSE4_P")
			(pintype "passive")
		)
		(pad "2" smd roundrect
			(at 0.48 0 135)
			(size 0.59 0.64)
			(layers "B.Cu" "B.Mask" "B.Paste")
			(roundrect_rratio 0.25)
			(net 579 "Net-(U6-SENSE4+)")
			(pintype "passive")
		)
	)
	(footprint "antmicro-footprints:C_Array_0508_1220Metric"
		(layer "B.Cu")
		(at 199.84 142.84)
		(property "Reference" "C171"
			(at -1.35 1.27 90)
			(layer "B.SilkS")
			(effects
				(font
					(size 0.7 0.7)
					(thickness 0.15)
				)
				(justify right bottom mirror)
			)
		)
		(property "Value" "C_4x100nF_0508_1220Metric_array"
			(at 0 -2.8 0)
			(layer "B.Fab")
			(hide yes)
			(effects
				(font
					(size 0.7 0.7)
					(thickness 0.15)
				)
				(justify right bottom mirror)
			)
		)
		(property "Datasheet" "https://spicat.kyocera-avx.com/product/mlcc/chartview/W2A4YC104MAT2A/"
			(at 0 0 0)
			(layer "F.Fab")
			(hide yes)
			(effects
				(font
					(size 1.27 1.27)
					(thickness 0.15)
				)
			)
		)
		(property "Description" "4x0.1µF isolated capacitor array 16 V X7R 0508 (1220 Metric)"
			(at 0 0 0)
			(layer "F.Fab")
			(hide yes)
			(effects
				(font
					(size 1.27 1.27)
					(thickness 0.15)
				)
			)
		)
		(property "Author" "Antmicro"
			(at 0 0 0)
			(layer "B.Fab")
			(hide yes)
			(effects
				(font
					(size 1 1)
					(thickness 0.15)
				)
				(justify mirror)
			)
		)
		(property "Dielectric" "X7R"
			(at 0 0 0)
			(layer "B.Fab")
			(hide yes)
			(effects
				(font
					(size 1 1)
					(thickness 0.15)
				)
				(justify mirror)
			)
		)
		(property "License" "Apache-2.0"
			(at 0 0 0)
			(layer "B.Fab")
			(hide yes)
			(effects
				(font
					(size 1 1)
					(thickness 0.15)
				)
				(justify mirror)
			)
		)
		(property "MPN" "W2A4YC104MAT2A"
			(at 0 0 0)
			(layer "B.Fab")
			(hide yes)
			(effects
				(font
					(size 1 1)
					(thickness 0.15)
				)
				(justify mirror)
			)
		)
		(property "Manufacturer" "KYOCERA AVX"
			(at 0 0 0)
			(layer "B.Fab")
			(hide yes)
			(effects
				(font
					(size 1 1)
					(thickness 0.15)
				)
				(justify mirror)
			)
		)
		(property "Val" "4x100nF"
			(at 0 0 0)
			(layer "B.Fab")
			(hide yes)
			(effects
				(font
					(size 1 1)
					(thickness 0.15)
				)
				(justify mirror)
			)
		)
		(property "Voltage" "16V"
			(at 0 0 0)
			(layer "B.Fab")
			(hide yes)
			(effects
				(font
					(size 1 1)
					(thickness 0.15)
				)
				(justify mirror)
			)
		)
		(sheetname "/PCIe/")
		(sheetfile "pcie.kicad_sch")
		(attr smd)
		(fp_circle
			(center -1.21 0.75)
			(end -1.16 0.75)
			(stroke
				(width 0.15)
				(type solid)
			)
			(fill yes)
			(layer "B.SilkS")
		)
		(fp_rect
			(start -1.09 1.2)
			(end 1.09 -1.2)
			(stroke
				(width 0.05)
				(type solid)
			)
			(fill no)
			(layer "B.CrtYd")
		)
		(fp_line
			(start -0.65 -1.05)
			(end -0.65 1.05)
			(stroke
				(width 0.15)
				(type solid)
			)
			(layer "B.Fab")
		)
		(fp_line
			(start -0.65 1.05)
			(end 0.65 1.05)
			(stroke
				(width 0.15)
				(type solid)
			)
			(layer "B.Fab")
		)
		(fp_line
			(start 0.65 -1.05)
			(end -0.65 -1.05)
			(stroke
				(width 0.15)
				(type solid)
			)
			(layer "B.Fab")
		)
		(fp_line
			(start 0.65 1.05)
			(end 0.65 -1.05)
			(stroke
				(width 0.15)
				(type solid)
			)
			(layer "B.Fab")
		)
		(fp_text user "${REFERENCE}"
			(at -1.26 -6 180)
			(layer "B.Fab")
			(effects
				(font
					(size 0.7 0.7)
					(thickness 0.15)
				)
				(justify left bottom mirror)
			)
		)
		(fp_text user "License: Apache-2.0"
			(at -1.26 -4.8 180)
			(layer "B.Fab")
			(effects
				(font
					(size 0.7 0.7)
					(thickness 0.15)
				)
				(justify left bottom mirror)
			)
		)
		(fp_text user "Author: Antmicro"
			(at -1.26 -7.2 180)
			(layer "B.Fab")
			(effects
				(font
					(size 0.7 0.7)
					(thickness 0.15)
				)
				(justify left bottom mirror)
			)
		)
		(pad "1" smd roundrect
			(at -0.66 0.75 90)
			(size 0.3 0.56)
			(layers "B.Cu" "B.Mask" "B.Paste")
			(roundrect_rratio 0.25)
			(net 19 "/Bottom Connector/PCIE.TXD0_P")
			(pinfunction "R1.1")
			(pintype "passive")
		)
		(pad "2" smd roundrect
			(at -0.66 0.25 90)
			(size 0.3 0.56)
			(layers "B.Cu" "B.Mask" "B.Paste")
			(roundrect_rratio 0.25)
			(net 33 "/Bottom Connector/PCIE.TXD0_N")
			(pinfunction "R2.1")
			(pintype "passive")
		)
		(pad "3" smd roundrect
			(at -0.66 -0.25 90)
			(size 0.3 0.56)
			(layers "B.Cu" "B.Mask" "B.Paste")
			(roundrect_rratio 0.25)
			(net 35 "/Bottom Connector/PCIE.TXD1_P")
			(pinfunction "R3.1")
			(pintype "passive")
		)
		(pad "4" smd roundrect
			(at -0.66 -0.75 90)
			(size 0.3 0.56)
			(layers "B.Cu" "B.Mask" "B.Paste")
			(roundrect_rratio 0.25)
			(net 36 "/Bottom Connector/PCIE.TXD1_N")
			(pinfunction "R4.1")
			(pintype "passive")
		)
		(pad "5" smd roundrect
			(at 0.66 -0.75 90)
			(size 0.3 0.56)
			(layers "B.Cu" "B.Mask" "B.Paste")
			(roundrect_rratio 0.25)
			(net 46 "/PCIe/XCVR_TX1_N")
			(pinfunction "R4.2")
			(pintype "passive")
		)
		(pad "6" smd roundrect
			(at 0.66 -0.25 90)
			(size 0.3 0.56)
			(layers "B.Cu" "B.Mask" "B.Paste")
			(roundrect_rratio 0.25)
			(net 51 "/PCIe/XCVR_TX1_P")
			(pinfunction "R3.2")
			(pintype "passive")
		)
		(pad "7" smd roundrect
			(at 0.66 0.25 90)
			(size 0.3 0.56)
			(layers "B.Cu" "B.Mask" "B.Paste")
			(roundrect_rratio 0.25)
			(net 53 "/PCIe/XCVR_TX0_N")
			(pinfunction "R2.2")
			(pintype "passive")
		)
		(pad "8" smd roundrect
			(at 0.66 0.75 90)
			(size 0.3 0.56)
			(layers "B.Cu" "B.Mask" "B.Paste")
			(roundrect_rratio 0.25)
			(net 64 "/PCIe/XCVR_TX0_P")
			(pinfunction "R1.2")
			(pintype "passive")
		)
	)
	(footprint "antmicro-footprints:R_Array_4x0201_Panasonic_EXB18V"
		(layer "B.Cu")
		(at 203.24884 121.65 -90)
		(property "Reference" "R23"
			(at 1.15 -1.50116 90)
			(layer "B.SilkS")
			(effects
				(font
					(size 0.7 0.7)
					(thickness 0.15)
				)
				(justify right bottom mirror)
			)
		)
		(property "Value" "R_4x0R_0201_array"
			(at -1.1 -1.8 90)
			(layer "B.Fab")
			(hide yes)
			(effects
				(font
					(size 0.7 0.7)
					(thickness 0.15)
				)
				(justify left bottom mirror)
			)
		)
		(property "Datasheet" "http://industrial.panasonic.com/cdbs/www-data/pdf/AOC0000/AOC0000C14.pdf"
			(at 0 0 270)
			(layer "F.Fab")
			(hide yes)
			(effects
				(font
					(size 1.27 1.27)
					(thickness 0.15)
				)
			)
		)
		(property "Description" "Zero Ohm Network Resistor, Jumper, 0201 [0603 Metric], Thick Film, Isolated, Flat, 4 Resistors"
			(at 0 0 270)
			(layer "F.Fab")
			(hide yes)
			(effects
				(font
					(size 1.27 1.27)
					(thickness 0.15)
				)
			)
		)
		(property "Author" "Antmicro"
			(at 81.59884 324.89884 0)
			(layer "B.Fab")
			(hide yes)
			(effects
				(font
					(size 1 1)
					(thickness 0.15)
				)
				(justify mirror)
			)
		)
		(property "License" "Apache-2.0"
			(at 81.59884 324.89884 0)
			(layer "B.Fab")
			(hide yes)
			(effects
				(font
					(size 1 1)
					(thickness 0.15)
				)
				(justify mirror)
			)
		)
		(property "MPN" "EXB-18VR000X"
			(at 81.59884 324.89884 0)
			(layer "B.Fab")
			(hide yes)
			(effects
				(font
					(size 1 1)
					(thickness 0.15)
				)
				(justify mirror)
			)
		)
		(property "Manufacturer" "Panasonic"
			(at 81.59884 324.89884 0)
			(layer "B.Fab")
			(hide yes)
			(effects
				(font
					(size 1 1)
					(thickness 0.15)
				)
				(justify mirror)
			)
		)
		(property "Val" "4x0R_0201"
			(at 81.59884 324.89884 0)
			(layer "B.Fab")
			(hide yes)
			(effects
				(font
					(size 1 1)
					(thickness 0.15)
				)
				(justify mirror)
			)
		)
		(sheetname "/FPGA MSSIO/")
		(sheetfile "fpga-mssio.kicad_sch")
		(attr smd)
		(fp_line
			(start -0.8 0.45)
			(end -0.8 -0.45)
			(stroke
				(width 0.12)
				(type solid)
			)
			(layer "B.SilkS")
		)
		(fp_line
			(start 0.8 0.45)
			(end 0.8 -0.45)
			(stroke
				(width 0.12)
				(type solid)
			)
			(layer "B.SilkS")
		)
		(fp_rect
			(start -0.898 0.66)
			(end 0.898 -0.65)
			(stroke
				(width 0.05)
				(type solid)
			)
			(fill no)
			(layer "B.CrtYd")
		)
		(fp_text user "Author: Antmicro"
			(at -1.051 -4.599 90)
			(layer "B.Fab")
			(effects
				(font
					(size 0.7 0.7)
					(thickness 0.15)
				)
				(justify left bottom mirror)
			)
		)
		(fp_text user "${REFERENCE}"
			(at -1.051 -3.2 90)
			(layer "B.Fab")
			(effects
				(font
					(size 0.7 0.7)
					(thickness 0.15)
				)
				(justify left bottom mirror)
			)
		)
		(fp_text user "License: Apache-2.0"
			(at -1.051 -6 90)
			(layer "B.Fab")
			(effects
				(font
					(size 0.7 0.7)
					(thickness 0.15)
				)
				(justify left bottom mirror)
			)
		)
		(pad "1" smd roundrect
			(at -0.6 -0.298 270)
			(size 0.2 0.4)
			(layers "B.Cu" "B.Mask" "B.Paste")
			(roundrect_rratio 0.25)
			(net 243 "/FPGA MSSIO/EMMC.DAT1")
			(pinfunction "R1.1")
			(pintype "passive")
		)
		(pad "2" smd roundrect
			(at -0.202 -0.298 270)
			(size 0.2 0.4)
			(layers "B.Cu" "B.Mask" "B.Paste")
			(roundrect_rratio 0.25)
			(net 248 "/FPGA MSSIO/EMMC.DAT2")
			(pinfunction "R2.1")
			(pintype "passive")
		)
		(pad "3" smd roundrect
			(at 0.2 -0.298 270)
			(size 0.2 0.4)
			(layers "B.Cu" "B.Mask" "B.Paste")
			(roundrect_rratio 0.25)
			(net 249 "/FPGA MSSIO/EMMC.DAT6")
			(pinfunction "R3.1")
			(pintype "passive")
		)
		(pad "4" smd roundrect
			(at 0.598 -0.298 270)
			(size 0.2 0.4)
			(layers "B.Cu" "B.Mask" "B.Paste")
			(roundrect_rratio 0.25)
			(net 250 "/FPGA MSSIO/EMMC.DAT4")
			(pinfunction "R4.1")
			(pintype "passive")
		)
		(pad "5" smd roundrect
			(at 0.598 0.3 270)
			(size 0.2 0.4)
			(layers "B.Cu" "B.Mask" "B.Paste")
			(roundrect_rratio 0.25)
			(net 251 "/FPGA MSSIO/MEM.DAT4")
			(pinfunction "R4.2")
			(pintype "passive")
		)
		(pad "6" smd roundrect
			(at 0.2 0.3 270)
			(size 0.2 0.4)
			(layers "B.Cu" "B.Mask" "B.Paste")
			(roundrect_rratio 0.25)
			(net 252 "/FPGA MSSIO/MEM.DAT6")
			(pinfunction "R3.2")
			(pintype "passive")
		)
		(pad "7" smd roundrect
			(at -0.202 0.3 270)
			(size 0.2 0.4)
			(layers "B.Cu" "B.Mask" "B.Paste")
			(roundrect_rratio 0.25)
			(net 261 "/FPGA MSSIO/MEM.DAT2")
			(pinfunction "R2.2")
			(pintype "passive")
		)
		(pad "8" smd roundrect
			(at -0.6 0.3 270)
			(size 0.2 0.4)
			(layers "B.Cu" "B.Mask" "B.Paste")
			(roundrect_rratio 0.25)
			(net 262 "/FPGA MSSIO/MEM.DAT1")
			(pinfunction "R1.2")
			(pintype "passive")
		)
	)
	(footprint "antmicro-footprints:R_0402_1005Metric"
		(layer "B.Cu")
		(at 177.75 145.46 -90)
		(descr "Resistor SMD 0402")
		(tags "resistor SMD 0402")
		(property "Reference" "R94"
			(at 0.885 -1.36 90)
			(layer "B.SilkS")
			(effects
				(font
					(size 0.7 0.7)
					(thickness 0.15)
				)
				(justify left bottom mirror)
			)
		)
		(property "Value" "R_0R_0402"
			(at -1.011843 -1.772047 90)
			(layer "B.Fab")
			(hide yes)
			(effects
				(font
					(size 0.7 0.7)
					(thickness 0.15)
				)
				(justify left bottom mirror)
			)
		)
		(property "Datasheet" "https://industrial.panasonic.com/cdbs/www-data/pdf/RDA0000/AOA0000C301.pdf"
			(at 0 0 270)
			(layer "F.Fab")
			(hide yes)
			(effects
				(font
					(size 1.27 1.27)
					(thickness 0.15)
				)
			)
		)
		(property "Description" "SMD Chip Resistor, Jumper, 0 ohm, 100 mW, 0402 [1005 Metric], Thick Film, General Purpose"
			(at 0 0 270)
			(layer "F.Fab")
			(hide yes)
			(effects
				(font
					(size 1.27 1.27)
					(thickness 0.15)
				)
			)
		)
		(property "Author" "Antmicro"
			(at 32.29 323.21 0)
			(layer "B.Fab")
			(hide yes)
			(effects
				(font
					(size 1 1)
					(thickness 0.15)
				)
				(justify mirror)
			)
		)
		(property "Current" "1A"
			(at 32.29 323.21 0)
			(layer "B.Fab")
			(hide yes)
			(effects
				(font
					(size 1 1)
					(thickness 0.15)
				)
				(justify mirror)
			)
		)
		(property "License" "Apache-2.0"
			(at 32.29 323.21 0)
			(layer "B.Fab")
			(hide yes)
			(effects
				(font
					(size 1 1)
					(thickness 0.15)
				)
				(justify mirror)
			)
		)
		(property "MPN" "ERJ2GE0R00X"
			(at 32.29 323.21 0)
			(layer "B.Fab")
			(hide yes)
			(effects
				(font
					(size 1 1)
					(thickness 0.15)
				)
				(justify mirror)
			)
		)
		(property "Manufacturer" "Panasonic"
			(at 32.29 323.21 0)
			(layer "B.Fab")
			(hide yes)
			(effects
				(font
					(size 1 1)
					(thickness 0.15)
				)
				(justify mirror)
			)
		)
		(property "Public" ""
			(at 32.29 323.21 0)
			(layer "B.Fab")
			(hide yes)
			(effects
				(font
					(size 1 1)
					(thickness 0.15)
				)
				(justify mirror)
			)
		)
		(property "Tolerance" "~"
			(at 32.29 323.21 0)
			(layer "B.Fab")
			(hide yes)
			(effects
				(font
					(size 1 1)
					(thickness 0.15)
				)
				(justify mirror)
			)
		)
		(property "Val" "0R"
			(at 32.29 323.21 0)
			(layer "B.Fab")
			(hide yes)
			(effects
				(font
					(size 1 1)
					(thickness 0.15)
				)
				(justify mirror)
			)
		)
		(sheetname "/Supply/")
		(sheetfile "supply.kicad_sch")
		(attr smd)
		(fp_rect
			(start -0.925 0.47)
			(end 0.925 -0.47)
			(stroke
				(width 0.05)
				(type default)
			)
			(fill no)
			(layer "B.CrtYd")
		)
		(fp_rect
			(start -0.5 0.25)
			(end 0.5 -0.25)
			(stroke
				(width 0.15)
				(type solid)
			)
			(fill no)
			(layer "B.Fab")
		)
		(fp_text user "License: Apache-2.0"
			(at -0.95 -5.169 90)
			(layer "B.Fab")
			(effects
				(font
					(size 0.7 0.7)
					(thickness 0.15)
				)
				(justify left bottom mirror)
			)
		)
		(fp_text user "${REFERENCE}"
			(at -0.95 -3.168 90)
			(layer "B.Fab")
			(effects
				(font
					(size 0.7 0.7)
					(thickness 0.15)
				)
				(justify left bottom mirror)
			)
		)
		(fp_text user "Author: Antmicro"
			(at -0.95 -4.169 90)
			(layer "B.Fab")
			(effects
				(font
					(size 0.7 0.7)
					(thickness 0.15)
				)
				(justify left bottom mirror)
			)
		)
		(pad "1" smd roundrect
			(at -0.48 0 270)
			(size 0.59 0.64)
			(layers "B.Cu" "B.Mask" "B.Paste")
			(roundrect_rratio 0.25)
			(net 406 "/Supply/SENSE2_P")
			(pintype "passive")
		)
		(pad "2" smd roundrect
			(at 0.48 0 270)
			(size 0.59 0.64)
			(layers "B.Cu" "B.Mask" "B.Paste")
			(roundrect_rratio 0.25)
			(net 577 "Net-(U6-SENSE2+)")
			(pintype "passive")
		)
	)
	(footprint "antmicro-footprints:C_0402_1005Metric"
		(layer "B.Cu")
		(at 224.15 141.53 90)
		(descr "Capacitor SMD 0402")
		(tags "capacitor SMD 0402")
		(property "Reference" "C81"
			(at 0.58 0.4 90)
			(layer "B.SilkS")
			(hide yes)
			(effects
				(font
					(size 0.7 0.7)
					(thickness 0.15)
				)
				(justify right bottom mirror)
			)
		)
		(property "Value" "C_100n_0402"
			(at -1.022927 -2.155213 90)
			(layer "B.Fab")
			(hide yes)
			(effects
				(font
					(size 0.7 0.7)
					(thickness 0.15)
				)
				(justify right bottom mirror)
			)
		)
		(property "Datasheet" "https://www.murata.com/products/productdetail?partno=GRM155R61H104KE14%23"
			(at 0 0 90)
			(layer "F.Fab")
			(hide yes)
			(effects
				(font
					(size 1.27 1.27)
					(thickness 0.15)
				)
			)
		)
		(property "Description" "SMD Multilayer Ceramic Capacitor, 0.1 µF, 50 V, 0402 [1005 Metric], ± 10%, X5R, GRM Series"
			(at 0 0 90)
			(layer "F.Fab")
			(hide yes)
			(effects
				(font
					(size 1.27 1.27)
					(thickness 0.15)
				)
			)
		)
		(property "Author" "Antmicro"
			(at 365.68 -82.62 0)
			(layer "B.Fab")
			(hide yes)
			(effects
				(font
					(size 1 1)
					(thickness 0.15)
				)
				(justify mirror)
			)
		)
		(property "Dielectric" "X5R"
			(at 365.68 -82.62 0)
			(layer "B.Fab")
			(hide yes)
			(effects
				(font
					(size 1 1)
					(thickness 0.15)
				)
				(justify mirror)
			)
		)
		(property "License" "Apache-2.0"
			(at 365.68 -82.62 0)
			(layer "B.Fab")
			(hide yes)
			(effects
				(font
					(size 1 1)
					(thickness 0.15)
				)
				(justify mirror)
			)
		)
		(property "MPN" "GRM155R61H104KE14D"
			(at 365.68 -82.62 0)
			(layer "B.Fab")
			(hide yes)
			(effects
				(font
					(size 1 1)
					(thickness 0.15)
				)
				(justify mirror)
			)
		)
		(property "Manufacturer" "Murata"
			(at 365.68 -82.62 0)
			(layer "B.Fab")
			(hide yes)
			(effects
				(font
					(size 1 1)
					(thickness 0.15)
				)
				(justify mirror)
			)
		)
		(property "Public" ""
			(at 365.68 -82.62 0)
			(layer "B.Fab")
			(hide yes)
			(effects
				(font
					(size 1 1)
					(thickness 0.15)
				)
				(justify mirror)
			)
		)
		(property "Val" "100n"
			(at 365.68 -82.62 0)
			(layer "B.Fab")
			(hide yes)
			(effects
				(font
					(size 1 1)
					(thickness 0.15)
				)
				(justify mirror)
			)
		)
		(property "Voltage" "50V"
			(at 365.68 -82.62 0)
			(layer "B.Fab")
			(hide yes)
			(effects
				(font
					(size 1 1)
					(thickness 0.15)
				)
				(justify mirror)
			)
		)
		(sheetname "/FPGA GPIO/")
		(sheetfile "fpga-gpio.kicad_sch")
		(attr smd)
		(fp_rect
			(start -0.925 0.47)
			(end 0.925 -0.47)
			(stroke
				(width 0.05)
				(type default)
			)
			(fill no)
			(layer "B.CrtYd")
		)
		(fp_line
			(start 0.504 -0.248)
			(end -0.494 -0.248)
			(stroke
				(width 0.15)
				(type solid)
			)
			(layer "B.Fab")
		)
		(fp_line
			(start -0.494 -0.248)
			(end -0.494 0.25)
			(stroke
				(width 0.15)
				(type solid)
			)
			(layer "B.Fab")
		)
		(fp_line
			(start 0.504 0.25)
			(end 0.504 -0.248)
			(stroke
				(width 0.15)
				(type solid)
			)
			(layer "B.Fab")
		)
		(fp_line
			(start -0.494 0.25)
			(end 0.504 0.25)
			(stroke
				(width 0.15)
				(type solid)
			)
			(layer "B.Fab")
		)
		(fp_text user "81"
			(at 1.43 -0.025 90)
			(unlocked yes)
			(layer "B.SilkS")
			(effects
				(font
					(size 0.7 0.7)
					(thickness 0.15)
				)
				(justify mirror)
			)
		)
		(fp_text user "${REFERENCE}"
			(at -0.939 -4.599 270)
			(layer "B.Fab")
			(effects
				(font
					(size 0.7 0.7)
					(thickness 0.15)
				)
				(justify left bottom mirror)
			)
		)
		(fp_text user "License: Apache-2.0"
			(at -0.939 -5.799 270)
			(layer "B.Fab")
			(effects
				(font
					(size 0.7 0.7)
					(thickness 0.15)
				)
				(justify left bottom mirror)
			)
		)
		(fp_text user "Author: Antmicro"
			(at -0.939 -3.399 270)
			(layer "B.Fab")
			(effects
				(font
					(size 0.7 0.7)
					(thickness 0.15)
				)
				(justify left bottom mirror)
			)
		)
		(pad "1" smd roundrect
			(at -0.48 0 90)
			(size 0.59 0.64)
			(layers "B.Cu" "B.Mask" "B.Paste")
			(roundrect_rratio 0.25)
			(net 50 "+3V3")
			(pintype "passive")
		)
		(pad "2" smd roundrect
			(at 0.48 0 90)
			(size 0.59 0.64)
			(layers "B.Cu" "B.Mask" "B.Paste")
			(roundrect_rratio 0.25)
			(net 417 "GND")
			(pintype "passive")
		)
	)
	(footprint "antmicro-footprints:R_Array_4x0201_Panasonic_EXB18V"
		(layer "B.Cu")
		(at 206.993002 121.65 -90)
		(property "Reference" "R22"
			(at 1.13 0.743002 90)
			(layer "B.SilkS")
			(effects
				(font
					(size 0.7 0.7)
					(thickness 0.15)
				)
				(justify right bottom mirror)
			)
		)
		(property "Value" "R_4x0R_0201_array"
			(at -1.1 -1.8 90)
			(layer "B.Fab")
			(hide yes)
			(effects
				(font
					(size 0.7 0.7)
					(thickness 0.15)
				)
				(justify left bottom mirror)
			)
		)
		(property "Datasheet" "http://industrial.panasonic.com/cdbs/www-data/pdf/AOC0000/AOC0000C14.pdf"
			(at 0 0 270)
			(layer "F.Fab")
			(hide yes)
			(effects
				(font
					(size 1.27 1.27)
					(thickness 0.15)
				)
			)
		)
		(property "Description" "Zero Ohm Network Resistor, Jumper, 0201 [0603 Metric], Thick Film, Isolated, Flat, 4 Resistors"
			(at 0 0 270)
			(layer "F.Fab")
			(hide yes)
			(effects
				(font
					(size 1.27 1.27)
					(thickness 0.15)
				)
			)
		)
		(property "Author" "Antmicro"
			(at 85.343002 328.643002 0)
			(layer "B.Fab")
			(hide yes)
			(effects
				(font
					(size 1 1)
					(thickness 0.15)
				)
				(justify mirror)
			)
		)
		(property "License" "Apache-2.0"
			(at 85.343002 328.643002 0)
			(layer "B.Fab")
			(hide yes)
			(effects
				(font
					(size 1 1)
					(thickness 0.15)
				)
				(justify mirror)
			)
		)
		(property "MPN" "EXB-18VR000X"
			(at 85.343002 328.643002 0)
			(layer "B.Fab")
			(hide yes)
			(effects
				(font
					(size 1 1)
					(thickness 0.15)
				)
				(justify mirror)
			)
		)
		(property "Manufacturer" "Panasonic"
			(at 85.343002 328.643002 0)
			(layer "B.Fab")
			(hide yes)
			(effects
				(font
					(size 1 1)
					(thickness 0.15)
				)
				(justify mirror)
			)
		)
		(property "Val" "4x0R_0201"
			(at 85.343002 328.643002 0)
			(layer "B.Fab")
			(hide yes)
			(effects
				(font
					(size 1 1)
					(thickness 0.15)
				)
				(justify mirror)
			)
		)
		(sheetname "/FPGA MSSIO/")
		(sheetfile "fpga-mssio.kicad_sch")
		(attr smd)
		(fp_line
			(start -0.8 0.45)
			(end -0.8 -0.45)
			(stroke
				(width 0.12)
				(type solid)
			)
			(layer "B.SilkS")
		)
		(fp_line
			(start 0.8 0.45)
			(end 0.8 -0.45)
			(stroke
				(width 0.12)
				(type solid)
			)
			(layer "B.SilkS")
		)
		(fp_rect
			(start -0.898 0.66)
			(end 0.898 -0.65)
			(stroke
				(width 0.05)
				(type solid)
			)
			(fill no)
			(layer "B.CrtYd")
		)
		(fp_text user "${REFERENCE}"
			(at -1.051 -3.2 90)
			(layer "B.Fab")
			(effects
				(font
					(size 0.7 0.7)
					(thickness 0.15)
				)
				(justify left bottom mirror)
			)
		)
		(fp_text user "License: Apache-2.0"
			(at -1.051 -6 90)
			(layer "B.Fab")
			(effects
				(font
					(size 0.7 0.7)
					(thickness 0.15)
				)
				(justify left bottom mirror)
			)
		)
		(fp_text user "Author: Antmicro"
			(at -1.051 -4.599 90)
			(layer "B.Fab")
			(effects
				(font
					(size 0.7 0.7)
					(thickness 0.15)
				)
				(justify left bottom mirror)
			)
		)
		(pad "1" smd roundrect
			(at -0.6 -0.298 270)
			(size 0.2 0.4)
			(layers "B.Cu" "B.Mask" "B.Paste")
			(roundrect_rratio 0.25)
			(net 207 "/FPGA MSSIO/EMMC.DAT3")
			(pinfunction "R1.1")
			(pintype "passive")
		)
		(pad "2" smd roundrect
			(at -0.202 -0.298 270)
			(size 0.2 0.4)
			(layers "B.Cu" "B.Mask" "B.Paste")
			(roundrect_rratio 0.25)
			(net 208 "/FPGA MSSIO/EMMC.DAT0")
			(pinfunction "R2.1")
			(pintype "passive")
		)
		(pad "3" smd roundrect
			(at 0.2 -0.298 270)
			(size 0.2 0.4)
			(layers "B.Cu" "B.Mask" "B.Paste")
			(roundrect_rratio 0.25)
			(net 213 "/FPGA MSSIO/EMMC.DAT5")
			(pinfunction "R3.1")
			(pintype "passive")
		)
		(pad "4" smd roundrect
			(at 0.598 -0.298 270)
			(size 0.2 0.4)
			(layers "B.Cu" "B.Mask" "B.Paste")
			(roundrect_rratio 0.25)
			(net 214 "/FPGA MSSIO/EMMC.DAT7")
			(pinfunction "R4.1")
			(pintype "passive")
		)
		(pad "5" smd roundrect
			(at 0.598 0.3 270)
			(size 0.2 0.4)
			(layers "B.Cu" "B.Mask" "B.Paste")
			(roundrect_rratio 0.25)
			(net 215 "/FPGA MSSIO/MEM.DAT7")
			(pinfunction "R4.2")
			(pintype "passive")
		)
		(pad "6" smd roundrect
			(at 0.2 0.3 270)
			(size 0.2 0.4)
			(layers "B.Cu" "B.Mask" "B.Paste")
			(roundrect_rratio 0.25)
			(net 216 "/FPGA MSSIO/MEM.DAT5")
			(pinfunction "R3.2")
			(pintype "passive")
		)
		(pad "7" smd roundrect
			(at -0.202 0.3 270)
			(size 0.2 0.4)
			(layers "B.Cu" "B.Mask" "B.Paste")
			(roundrect_rratio 0.25)
			(net 235 "/FPGA MSSIO/MEM.DAT0")
			(pinfunction "R2.2")
			(pintype "passive")
		)
		(pad "8" smd roundrect
			(at -0.6 0.3 270)
			(size 0.2 0.4)
			(layers "B.Cu" "B.Mask" "B.Paste")
			(roundrect_rratio 0.25)
			(net 236 "/FPGA MSSIO/MEM.DAT3")
			(pinfunction "R1.2")
			(pintype "passive")
		)
	)
	(footprint "antmicro-footprints:C_0402_1005Metric"
		(layer "B.Cu")
		(at 197.04 132.79 90)
		(descr "Capacitor SMD 0402")
		(tags "capacitor SMD 0402")
		(property "Reference" "C28"
			(at 7.79 -9.615 270)
			(layer "B.SilkS")
			(effects
				(font
					(size 0.7 0.7)
					(thickness 0.15)
				)
				(justify left bottom mirror)
			)
		)
		(property "Value" "C_22n_0402"
			(at -1.022927 -2.155213 270)
			(layer "B.Fab")
			(hide yes)
			(effects
				(font
					(size 0.7 0.7)
					(thickness 0.15)
				)
				(justify left bottom mirror)
			)
		)
		(property "Datasheet" "https://www.murata.com/products/productdetail?partno=GCM155R71H223MA55%23"
			(at 0 0 90)
			(layer "F.Fab")
			(hide yes)
			(effects
				(font
					(size 1.27 1.27)
					(thickness 0.15)
				)
			)
		)
		(property "Description" "SMD Multilayer Ceramic Capacitors, 0.022 µF, 50 V, 20%, 0402 [1005 Metric], X7R"
			(at 0 0 90)
			(layer "F.Fab")
			(hide yes)
			(effects
				(font
					(size 1.27 1.27)
					(thickness 0.15)
				)
			)
		)
		(property "Author" "Antmicro"
			(at 329.83 -64.25 0)
			(layer "B.Fab")
			(hide yes)
			(effects
				(font
					(size 1 1)
					(thickness 0.15)
				)
				(justify mirror)
			)
		)
		(property "Dielectric" ""
			(at 329.83 -64.25 0)
			(layer "B.Fab")
			(hide yes)
			(effects
				(font
					(size 1 1)
					(thickness 0.15)
				)
				(justify mirror)
			)
		)
		(property "License" "Apache-2.0"
			(at 329.83 -64.25 0)
			(layer "B.Fab")
			(hide yes)
			(effects
				(font
					(size 1 1)
					(thickness 0.15)
				)
				(justify mirror)
			)
		)
		(property "MPN" "GCM155R71H223MA55D"
			(at 329.83 -64.25 0)
			(layer "B.Fab")
			(hide yes)
			(effects
				(font
					(size 1 1)
					(thickness 0.15)
				)
				(justify mirror)
			)
		)
		(property "Manufacturer" "Murata"
			(at 329.83 -64.25 0)
			(layer "B.Fab")
			(hide yes)
			(effects
				(font
					(size 1 1)
					(thickness 0.15)
				)
				(justify mirror)
			)
		)
		(property "Public" ""
			(at 329.83 -64.25 0)
			(layer "B.Fab")
			(hide yes)
			(effects
				(font
					(size 1 1)
					(thickness 0.15)
				)
				(justify mirror)
			)
		)
		(property "Val" "22n"
			(at 329.83 -64.25 0)
			(layer "B.Fab")
			(hide yes)
			(effects
				(font
					(size 1 1)
					(thickness 0.15)
				)
				(justify mirror)
			)
		)
		(property "Voltage" ""
			(at 329.83 -64.25 0)
			(layer "B.Fab")
			(hide yes)
			(effects
				(font
					(size 1 1)
					(thickness 0.15)
				)
				(justify mirror)
			)
		)
		(sheetname "/FPGA Supply/")
		(sheetfile "fpga-supply.kicad_sch")
		(attr smd)
		(fp_rect
			(start -0.925 0.47)
			(end 0.925 -0.47)
			(stroke
				(width 0.05)
				(type default)
			)
			(fill no)
			(layer "B.CrtYd")
		)
		(fp_line
			(start 0.504 -0.248)
			(end -0.494 -0.248)
			(stroke
				(width 0.15)
				(type solid)
			)
			(layer "B.Fab")
		)
		(fp_line
			(start -0.494 -0.248)
			(end -0.494 0.25)
			(stroke
				(width 0.15)
				(type solid)
			)
			(layer "B.Fab")
		)
		(fp_line
			(start 0.504 0.25)
			(end 0.504 -0.248)
			(stroke
				(width 0.15)
				(type solid)
			)
			(layer "B.Fab")
		)
		(fp_line
			(start -0.494 0.25)
			(end 0.504 0.25)
			(stroke
				(width 0.15)
				(type solid)
			)
			(layer "B.Fab")
		)
		(fp_text user "License: Apache-2.0"
			(at -0.939 -5.799 270)
			(layer "B.Fab")
			(effects
				(font
					(size 0.7 0.7)
					(thickness 0.15)
				)
				(justify left bottom mirror)
			)
		)
		(fp_text user "Author: Antmicro"
			(at -0.939 -3.399 270)
			(layer "B.Fab")
			(effects
				(font
					(size 0.7 0.7)
					(thickness 0.15)
				)
				(justify left bottom mirror)
			)
		)
		(fp_text user "${REFERENCE}"
			(at -0.939 -4.599 270)
			(layer "B.Fab")
			(effects
				(font
					(size 0.7 0.7)
					(thickness 0.15)
				)
				(justify left bottom mirror)
			)
		)
		(pad "1" smd roundrect
			(at -0.48 0 90)
			(size 0.59 0.64)
			(layers "B.Cu" "B.Mask" "B.Paste")
			(roundrect_rratio 0.25)
			(net 417 "GND")
			(pintype "passive")
		)
		(pad "2" smd roundrect
			(at 0.48 0 90)
			(size 0.59 0.64)
			(layers "B.Cu" "B.Mask" "B.Paste")
			(roundrect_rratio 0.25)
			(net 47 "+1V05")
			(pintype "passive")
		)
	)
	(footprint "antmicro-footprints:C_0402_1005Metric"
		(layer "B.Cu")
		(at 191 142.811 -90)
		(descr "Capacitor SMD 0402")
		(tags "capacitor SMD 0402")
		(property "Reference" "C178"
			(at 2.239 -0.95 90)
			(layer "B.SilkS")
			(effects
				(font
					(size 0.7 0.7)
					(thickness 0.15)
				)
				(justify left bottom mirror)
			)
		)
		(property "Value" "C_100n_0402"
			(at -1.022927 -2.155213 90)
			(layer "B.Fab")
			(hide yes)
			(effects
				(font
					(size 0.7 0.7)
					(thickness 0.15)
				)
				(justify left bottom mirror)
			)
		)
		(property "Datasheet" "https://www.murata.com/products/productdetail?partno=GRM155R61H104KE14%23"
			(at 0 0 270)
			(layer "F.Fab")
			(hide yes)
			(effects
				(font
					(size 1.27 1.27)
					(thickness 0.15)
				)
			)
		)
		(property "Description" "SMD Multilayer Ceramic Capacitor, 0.1 µF, 50 V, 0402 [1005 Metric], ± 10%, X5R, GRM Series"
			(at 0 0 270)
			(layer "F.Fab")
			(hide yes)
			(effects
				(font
					(size 1.27 1.27)
					(thickness 0.15)
				)
			)
		)
		(property "Author" "Antmicro"
			(at 48.189 333.811 0)
			(layer "B.Fab")
			(hide yes)
			(effects
				(font
					(size 1 1)
					(thickness 0.15)
				)
				(justify mirror)
			)
		)
		(property "Dielectric" "X5R"
			(at 48.189 333.811 0)
			(layer "B.Fab")
			(hide yes)
			(effects
				(font
					(size 1 1)
					(thickness 0.15)
				)
				(justify mirror)
			)
		)
		(property "License" "Apache-2.0"
			(at 48.189 333.811 0)
			(layer "B.Fab")
			(hide yes)
			(effects
				(font
					(size 1 1)
					(thickness 0.15)
				)
				(justify mirror)
			)
		)
		(property "MPN" "GRM155R61H104KE14D"
			(at 48.189 333.811 0)
			(layer "B.Fab")
			(hide yes)
			(effects
				(font
					(size 1 1)
					(thickness 0.15)
				)
				(justify mirror)
			)
		)
		(property "Manufacturer" "Murata"
			(at 48.189 333.811 0)
			(layer "B.Fab")
			(hide yes)
			(effects
				(font
					(size 1 1)
					(thickness 0.15)
				)
				(justify mirror)
			)
		)
		(property "Public" ""
			(at 48.189 333.811 0)
			(layer "B.Fab")
			(hide yes)
			(effects
				(font
					(size 1 1)
					(thickness 0.15)
				)
				(justify mirror)
			)
		)
		(property "Val" "100n"
			(at 48.189 333.811 0)
			(layer "B.Fab")
			(hide yes)
			(effects
				(font
					(size 1 1)
					(thickness 0.15)
				)
				(justify mirror)
			)
		)
		(property "Voltage" "50V"
			(at 48.189 333.811 0)
			(layer "B.Fab")
			(hide yes)
			(effects
				(font
					(size 1 1)
					(thickness 0.15)
				)
				(justify mirror)
			)
		)
		(sheetname "/FPGA GPIO/")
		(sheetfile "fpga-gpio.kicad_sch")
		(attr smd)
		(fp_rect
			(start -0.925 0.47)
			(end 0.925 -0.47)
			(stroke
				(width 0.05)
				(type default)
			)
			(fill no)
			(layer "B.CrtYd")
		)
		(fp_line
			(start -0.494 0.25)
			(end 0.504 0.25)
			(stroke
				(width 0.15)
				(type solid)
			)
			(layer "B.Fab")
		)
		(fp_line
			(start 0.504 0.25)
			(end 0.504 -0.248)
			(stroke
				(width 0.15)
				(type solid)
			)
			(layer "B.Fab")
		)
		(fp_line
			(start -0.494 -0.248)
			(end -0.494 0.25)
			(stroke
				(width 0.15)
				(type solid)
			)
			(layer "B.Fab")
		)
		(fp_line
			(start 0.504 -0.248)
			(end -0.494 -0.248)
			(stroke
				(width 0.15)
				(type solid)
			)
			(layer "B.Fab")
		)
		(fp_text user "License: Apache-2.0"
			(at -0.939 -5.799 90)
			(layer "B.Fab")
			(effects
				(font
					(size 0.7 0.7)
					(thickness 0.15)
				)
				(justify left bottom mirror)
			)
		)
		(fp_text user "${REFERENCE}"
			(at -0.939 -4.599 90)
			(layer "B.Fab")
			(effects
				(font
					(size 0.7 0.7)
					(thickness 0.15)
				)
				(justify left bottom mirror)
			)
		)
		(fp_text user "Author: Antmicro"
			(at -0.939 -3.399 90)
			(layer "B.Fab")
			(effects
				(font
					(size 0.7 0.7)
					(thickness 0.15)
				)
				(justify left bottom mirror)
			)
		)
		(pad "1" smd roundrect
			(at -0.48 0 270)
			(size 0.59 0.64)
			(layers "B.Cu" "B.Mask" "B.Paste")
			(roundrect_rratio 0.25)
			(net 649 "VDD")
			(pintype "passive")
		)
		(pad "2" smd roundrect
			(at 0.48 0 270)
			(size 0.59 0.64)
			(layers "B.Cu" "B.Mask" "B.Paste")
			(roundrect_rratio 0.25)
			(net 417 "GND")
			(pintype "passive")
		)
	)
	(footprint "antmicro-footprints:R_0402_1005Metric"
		(layer "B.Cu")
		(at 222.35 133.755 90)
		(descr "Resistor SMD 0402")
		(tags "resistor SMD 0402")
		(property "Reference" "R3"
			(at 0.28 1.3 270)
			(layer "B.SilkS")
			(effects
				(font
					(size 0.7 0.7)
					(thickness 0.15)
				)
				(justify left bottom mirror)
			)
		)
		(property "Value" "R_20k_0402"
			(at -1.011843 -1.772047 270)
			(layer "B.Fab")
			(hide yes)
			(effects
				(font
					(size 0.7 0.7)
					(thickness 0.15)
				)
				(justify left bottom mirror)
			)
		)
		(property "Datasheet" "https://www.bourns.com/docs/product-datasheets/cr.pdf"
			(at 0 0 90)
			(layer "F.Fab")
			(hide yes)
			(effects
				(font
					(size 1.27 1.27)
					(thickness 0.15)
				)
			)
		)
		(property "Description" "SMD Chip Resistor, 20 kohm, ± 1%, 62.5 mW, 0402 [1005 Metric], Thick Film, General Purpose"
			(at 0 0 90)
			(layer "F.Fab")
			(hide yes)
			(effects
				(font
					(size 1.27 1.27)
					(thickness 0.15)
				)
			)
		)
		(property "Author" "Antmicro"
			(at 356.105 -88.595 0)
			(layer "B.Fab")
			(hide yes)
			(effects
				(font
					(size 1 1)
					(thickness 0.15)
				)
				(justify mirror)
			)
		)
		(property "License" "Apache-2.0"
			(at 356.105 -88.595 0)
			(layer "B.Fab")
			(hide yes)
			(effects
				(font
					(size 1 1)
					(thickness 0.15)
				)
				(justify mirror)
			)
		)
		(property "MPN" "CR0402-FX-2002GLF"
			(at 356.105 -88.595 0)
			(layer "B.Fab")
			(hide yes)
			(effects
				(font
					(size 1 1)
					(thickness 0.15)
				)
				(justify mirror)
			)
		)
		(property "Manufacturer" "Bourns"
			(at 356.105 -88.595 0)
			(layer "B.Fab")
			(hide yes)
			(effects
				(font
					(size 1 1)
					(thickness 0.15)
				)
				(justify mirror)
			)
		)
		(property "Public" ""
			(at 356.105 -88.595 0)
			(layer "B.Fab")
			(hide yes)
			(effects
				(font
					(size 1 1)
					(thickness 0.15)
				)
				(justify mirror)
			)
		)
		(property "Tolerance" "1%"
			(at 356.105 -88.595 0)
			(layer "B.Fab")
			(hide yes)
			(effects
				(font
					(size 1 1)
					(thickness 0.15)
				)
				(justify mirror)
			)
		)
		(property "Val" "20k"
			(at 356.105 -88.595 0)
			(layer "B.Fab")
			(hide yes)
			(effects
				(font
					(size 1 1)
					(thickness 0.15)
				)
				(justify mirror)
			)
		)
		(sheetname "/Supply/")
		(sheetfile "supply.kicad_sch")
		(attr smd)
		(fp_rect
			(start -0.925 0.47)
			(end 0.925 -0.47)
			(stroke
				(width 0.05)
				(type default)
			)
			(fill no)
			(layer "B.CrtYd")
		)
		(fp_rect
			(start -0.5 0.25)
			(end 0.5 -0.25)
			(stroke
				(width 0.15)
				(type solid)
			)
			(fill no)
			(layer "B.Fab")
		)
		(fp_text user "License: Apache-2.0"
			(at -0.95 -5.169 270)
			(layer "B.Fab")
			(effects
				(font
					(size 0.7 0.7)
					(thickness 0.15)
				)
				(justify left bottom mirror)
			)
		)
		(fp_text user "Author: Antmicro"
			(at -0.95 -4.169 270)
			(layer "B.Fab")
			(effects
				(font
					(size 0.7 0.7)
					(thickness 0.15)
				)
				(justify left bottom mirror)
			)
		)
		(fp_text user "${REFERENCE}"
			(at -0.95 -3.168 270)
			(layer "B.Fab")
			(effects
				(font
					(size 0.7 0.7)
					(thickness 0.15)
				)
				(justify left bottom mirror)
			)
		)
		(pad "1" smd roundrect
			(at -0.48 0 90)
			(size 0.59 0.64)
			(layers "B.Cu" "B.Mask" "B.Paste")
			(roundrect_rratio 0.25)
			(net 417 "GND")
			(pintype "passive")
		)
		(pad "2" smd roundrect
			(at 0.48 0 90)
			(size 0.59 0.64)
			(layers "B.Cu" "B.Mask" "B.Paste")
			(roundrect_rratio 0.25)
			(net 186 "/Supply/PR")
			(pintype "passive")
		)
	)
	(footprint "antmicro-footprints:R_0402_1005Metric"
		(layer "B.Cu")
		(at 211.175 152.55 -90)
		(descr "Resistor SMD 0402")
		(tags "resistor SMD 0402")
		(property "Reference" "R77"
			(at 0.8 -0.425 90)
			(layer "B.SilkS")
			(effects
				(font
					(size 0.7 0.7)
					(thickness 0.15)
				)
				(justify left bottom mirror)
			)
		)
		(property "Value" "R_10k_0402"
			(at -1.011843 -1.772047 90)
			(layer "B.Fab")
			(hide yes)
			(effects
				(font
					(size 0.7 0.7)
					(thickness 0.15)
				)
				(justify left bottom mirror)
			)
		)
		(property "Datasheet" "https://www.bourns.com/docs/product-datasheets/cr.pdf"
			(at 0 0 270)
			(layer "F.Fab")
			(hide yes)
			(effects
				(font
					(size 1.27 1.27)
					(thickness 0.15)
				)
			)
		)
		(property "Description" "SMD Chip Resistor, 10 kohm, ± 1%, 62.5 mW, 0402 [1005 Metric], Thick Film, General Purpose"
			(at 0 0 270)
			(layer "F.Fab")
			(hide yes)
			(effects
				(font
					(size 1.27 1.27)
					(thickness 0.15)
				)
			)
		)
		(property "Author" "Antmicro"
			(at 58.625 363.725 0)
			(layer "B.Fab")
			(hide yes)
			(effects
				(font
					(size 1 1)
					(thickness 0.15)
				)
				(justify mirror)
			)
		)
		(property "License" "Apache-2.0"
			(at 58.625 363.725 0)
			(layer "B.Fab")
			(hide yes)
			(effects
				(font
					(size 1 1)
					(thickness 0.15)
				)
				(justify mirror)
			)
		)
		(property "MPN" "CR0402-FX-1002GLF"
			(at 58.625 363.725 0)
			(layer "B.Fab")
			(hide yes)
			(effects
				(font
					(size 1 1)
					(thickness 0.15)
				)
				(justify mirror)
			)
		)
		(property "Manufacturer" "Bourns"
			(at 58.625 363.725 0)
			(layer "B.Fab")
			(hide yes)
			(effects
				(font
					(size 1 1)
					(thickness 0.15)
				)
				(justify mirror)
			)
		)
		(property "Public" ""
			(at 58.625 363.725 0)
			(layer "B.Fab")
			(hide yes)
			(effects
				(font
					(size 1 1)
					(thickness 0.15)
				)
				(justify mirror)
			)
		)
		(property "Tolerance" "1%"
			(at 58.625 363.725 0)
			(layer "B.Fab")
			(hide yes)
			(effects
				(font
					(size 1 1)
					(thickness 0.15)
				)
				(justify mirror)
			)
		)
		(property "Val" "10k"
			(at 58.625 363.725 0)
			(layer "B.Fab")
			(hide yes)
			(effects
				(font
					(size 1 1)
					(thickness 0.15)
				)
				(justify mirror)
			)
		)
		(sheetname "/USB/")
		(sheetfile "usb.kicad_sch")
		(attr smd)
		(fp_rect
			(start -0.925 0.47)
			(end 0.925 -0.47)
			(stroke
				(width 0.05)
				(type default)
			)
			(fill no)
			(layer "B.CrtYd")
		)
		(fp_rect
			(start -0.5 0.25)
			(end 0.5 -0.25)
			(stroke
				(width 0.15)
				(type solid)
			)
			(fill no)
			(layer "B.Fab")
		)
		(fp_text user "Author: Antmicro"
			(at -0.95 -4.169 90)
			(layer "B.Fab")
			(effects
				(font
					(size 0.7 0.7)
					(thickness 0.15)
				)
				(justify left bottom mirror)
			)
		)
		(fp_text user "${REFERENCE}"
			(at -0.95 -3.168 90)
			(layer "B.Fab")
			(effects
				(font
					(size 0.7 0.7)
					(thickness 0.15)
				)
				(justify left bottom mirror)
			)
		)
		(fp_text user "License: Apache-2.0"
			(at -0.95 -5.169 90)
			(layer "B.Fab")
			(effects
				(font
					(size 0.7 0.7)
					(thickness 0.15)
				)
				(justify left bottom mirror)
			)
		)
		(pad "1" smd roundrect
			(at -0.48 0 270)
			(size 0.59 0.64)
			(layers "B.Cu" "B.Mask" "B.Paste")
			(roundrect_rratio 0.25)
			(net 62 "USB_OTG_ID")
			(pintype "passive")
		)
		(pad "2" smd roundrect
			(at 0.48 0 270)
			(size 0.59 0.64)
			(layers "B.Cu" "B.Mask" "B.Paste")
			(roundrect_rratio 0.25)
			(net 50 "+3V3")
			(pintype "passive")
		)
	)
	(footprint "antmicro-footprints:C_0402_1005Metric"
		(layer "B.Cu")
		(at 222.35 121.55 180)
		(descr "Capacitor SMD 0402")
		(tags "capacitor SMD 0402")
		(property "Reference" "C36"
			(at -1.05 1.95 0)
			(layer "B.SilkS")
			(effects
				(font
					(size 0.7 0.7)
					(thickness 0.15)
				)
				(justify left bottom mirror)
			)
		)
		(property "Value" "C_100n_0402"
			(at -1.022927 -2.155213 0)
			(layer "B.Fab")
			(hide yes)
			(effects
				(font
					(size 0.7 0.7)
					(thickness 0.15)
				)
				(justify left bottom mirror)
			)
		)
		(property "Datasheet" "https://www.murata.com/products/productdetail?partno=GRM155R61H104KE14%23"
			(at 0 0 180)
			(layer "F.Fab")
			(hide yes)
			(effects
				(font
					(size 1.27 1.27)
					(thickness 0.15)
				)
			)
		)
		(property "Description" "SMD Multilayer Ceramic Capacitor, 0.1 µF, 50 V, 0402 [1005 Metric], ± 10%, X5R, GRM Series"
			(at 0 0 180)
			(layer "F.Fab")
			(hide yes)
			(effects
				(font
					(size 1.27 1.27)
					(thickness 0.15)
				)
			)
		)
		(property "Author" "Antmicro"
			(at 444.7 243.1 0)
			(layer "B.Fab")
			(hide yes)
			(effects
				(font
					(size 1 1)
					(thickness 0.15)
				)
				(justify mirror)
			)
		)
		(property "Dielectric" "X5R"
			(at 444.7 243.1 0)
			(layer "B.Fab")
			(hide yes)
			(effects
				(font
					(size 1 1)
					(thickness 0.15)
				)
				(justify mirror)
			)
		)
		(property "License" "Apache-2.0"
			(at 444.7 243.1 0)
			(layer "B.Fab")
			(hide yes)
			(effects
				(font
					(size 1 1)
					(thickness 0.15)
				)
				(justify mirror)
			)
		)
		(property "MPN" "GRM155R61H104KE14D"
			(at 444.7 243.1 0)
			(layer "B.Fab")
			(hide yes)
			(effects
				(font
					(size 1 1)
					(thickness 0.15)
				)
				(justify mirror)
			)
		)
		(property "Manufacturer" "Murata"
			(at 444.7 243.1 0)
			(layer "B.Fab")
			(hide yes)
			(effects
				(font
					(size 1 1)
					(thickness 0.15)
				)
				(justify mirror)
			)
		)
		(property "Public" ""
			(at 444.7 243.1 0)
			(layer "B.Fab")
			(hide yes)
			(effects
				(font
					(size 1 1)
					(thickness 0.15)
				)
				(justify mirror)
			)
		)
		(property "Val" "100n"
			(at 444.7 243.1 0)
			(layer "B.Fab")
			(hide yes)
			(effects
				(font
					(size 1 1)
					(thickness 0.15)
				)
				(justify mirror)
			)
		)
		(property "Voltage" "50V"
			(at 444.7 243.1 0)
			(layer "B.Fab")
			(hide yes)
			(effects
				(font
					(size 1 1)
					(thickness 0.15)
				)
				(justify mirror)
			)
		)
		(sheetname "/FPGA GPIO/")
		(sheetfile "fpga-gpio.kicad_sch")
		(attr smd)
		(fp_rect
			(start -0.925 0.47)
			(end 0.925 -0.47)
			(stroke
				(width 0.05)
				(type default)
			)
			(fill no)
			(layer "B.CrtYd")
		)
		(fp_line
			(start 0.504 0.25)
			(end 0.504 -0.248)
			(stroke
				(width 0.15)
				(type solid)
			)
			(layer "B.Fab")
		)
		(fp_line
			(start 0.504 -0.248)
			(end -0.494 -0.248)
			(stroke
				(width 0.15)
				(type solid)
			)
			(layer "B.Fab")
		)
		(fp_line
			(start -0.494 0.25)
			(end 0.504 0.25)
			(stroke
				(width 0.15)
				(type solid)
			)
			(layer "B.Fab")
		)
		(fp_line
			(start -0.494 -0.248)
			(end -0.494 0.25)
			(stroke
				(width 0.15)
				(type solid)
			)
			(layer "B.Fab")
		)
		(fp_text user "${REFERENCE}"
			(at -0.939 -4.599 0)
			(layer "B.Fab")
			(effects
				(font
					(size 0.7 0.7)
					(thickness 0.15)
				)
				(justify left bottom mirror)
			)
		)
		(fp_text user "License: Apache-2.0"
			(at -0.939 -5.799 0)
			(layer "B.Fab")
			(effects
				(font
					(size 0.7 0.7)
					(thickness 0.15)
				)
				(justify left bottom mirror)
			)
		)
		(fp_text user "Author: Antmicro"
			(at -0.939 -3.399 0)
			(layer "B.Fab")
			(effects
				(font
					(size 0.7 0.7)
					(thickness 0.15)
				)
				(justify left bottom mirror)
			)
		)
		(pad "1" smd roundrect
			(at -0.48 0 180)
			(size 0.59 0.64)
			(layers "B.Cu" "B.Mask" "B.Paste")
			(roundrect_rratio 0.25)
			(net 649 "VDD")
			(pintype "passive")
		)
		(pad "2" smd roundrect
			(at 0.48 0 180)
			(size 0.59 0.64)
			(layers "B.Cu" "B.Mask" "B.Paste")
			(roundrect_rratio 0.25)
			(net 417 "GND")
			(pintype "passive")
		)
	)
	(footprint "antmicro-footprints:Conn_Plug_Hirose_DF40_2x50_DF40C-100DP-0.4V"
		(layer "B.Cu")
		(at 199.523 118.838 180)
		(property "Reference" "J1"
			(at -11.337 1.878 0)
			(layer "B.SilkS")
			(effects
				(font
					(size 0.7 0.7)
					(thickness 0.15)
				)
				(justify left bottom mirror)
			)
		)
		(property "Value" "Plug_Hirose_DF40_2x50_DF40C-100DP-0.4V"
			(at 0.001 -2.8 0)
			(layer "B.Fab")
			(hide yes)
			(effects
				(font
					(size 0.7 0.7)
					(thickness 0.15)
				)
				(justify left bottom mirror)
			)
		)
		(property "Datasheet" "https://www.hirose.com/en/product/document?clcode=CL0684-4032-1-51&productname=DF40C-100DP-0.4V(51)&series=DF40&documenttype=2DDrawing&lang=en&documentid=0001001212"
			(at 0 0 180)
			(layer "F.Fab")
			(hide yes)
			(effects
				(font
					(size 1.27 1.27)
					(thickness 0.15)
				)
			)
		)
		(property "Description" "Mezzanine Connector, Header, 0.4 mm, 2 Rows, 100 Contacts, Surface Mount, Phosphor Bronze"
			(at 0 0 180)
			(layer "F.Fab")
			(hide yes)
			(effects
				(font
					(size 1.27 1.27)
					(thickness 0.15)
				)
			)
		)
		(property "Author" "Antmicro"
			(at 399.046 237.676 0)
			(layer "B.Fab")
			(hide yes)
			(effects
				(font
					(size 1 1)
					(thickness 0.15)
				)
				(justify mirror)
			)
		)
		(property "License" "Apache-2.0"
			(at 399.046 237.676 0)
			(layer "B.Fab")
			(hide yes)
			(effects
				(font
					(size 1 1)
					(thickness 0.15)
				)
				(justify mirror)
			)
		)
		(property "MPN" "DF40C-100DP-0.4V(51)"
			(at 399.046 237.676 0)
			(layer "B.Fab")
			(hide yes)
			(effects
				(font
					(size 1 1)
					(thickness 0.15)
				)
				(justify mirror)
			)
		)
		(property "Manufacturer" "Hirose Electric"
			(at 399.046 237.676 0)
			(layer "B.Fab")
			(hide yes)
			(effects
				(font
					(size 1 1)
					(thickness 0.15)
				)
				(justify mirror)
			)
		)
		(property "Pitch" "0.4 mm"
			(at 399.046 237.676 0)
			(layer "B.Fab")
			(hide yes)
			(effects
				(font
					(size 1 1)
					(thickness 0.15)
				)
				(justify mirror)
			)
		)
		(sheetname "/Top Connector/")
		(sheetfile "top-connector.kicad_sch")
		(attr smd)
		(fp_line
			(start 10.76 0.946)
			(end 10.76 -0.9)
			(stroke
				(width 0.15)
				(type solid)
			)
			(layer "B.SilkS")
		)
		(fp_line
			(start -10.758 -0.9)
			(end -10.758 0.447)
			(stroke
				(width 0.15)
				(type solid)
			)
			(layer "B.SilkS")
		)
		(fp_circle
			(center -10 1.825)
			(end -9.95 1.825)
			(stroke
				(width 0.15)
				(type solid)
			)
			(fill yes)
			(layer "B.SilkS")
		)
		(fp_rect
			(start -11 1.9)
			(end 11.01 -1.8)
			(stroke
				(width 0.05)
				(type solid)
			)
			(fill no)
			(layer "B.CrtYd")
		)
		(fp_line
			(start 10.76 0.946)
			(end 10.76 -0.9)
			(stroke
				(width 0.15)
				(type solid)
			)
			(layer "B.Fab")
		)
		(fp_line
			(start 10.76 -0.9)
			(end -10.758 -0.9)
			(stroke
				(width 0.15)
				(type solid)
			)
			(layer "B.Fab")
		)
		(fp_line
			(start -10.258 0.946)
			(end 10.76 0.946)
			(stroke
				(width 0.15)
				(type solid)
			)
			(layer "B.Fab")
		)
		(fp_line
			(start -10.749 0.45)
			(end -10.258 0.946)
			(stroke
				(width 0.15)
				(type solid)
			)
			(layer "B.Fab")
		)
		(fp_line
			(start -10.758 -0.9)
			(end -10.749 0.45)
			(stroke
				(width 0.15)
				(type solid)
			)
			(layer "B.Fab")
		)
		(fp_text user "License: Apache-2.0"
			(at -11.76 -6.7 0)
			(layer "B.Fab")
			(effects
				(font
					(size 0.7 0.7)
					(thickness 0.15)
				)
				(justify left bottom mirror)
			)
		)
		(fp_text user "Author: Antmicro"
			(at -11.76 -5.5 0)
			(layer "B.Fab")
			(effects
				(font
					(size 0.7 0.7)
					(thickness 0.15)
				)
				(justify left bottom mirror)
			)
		)
		(fp_text user "${REFERENCE}"
			(at -11.76 -7.9 0)
			(layer "B.Fab")
			(effects
				(font
					(size 0.7 0.7)
					(thickness 0.15)
				)
				(justify left bottom mirror)
			)
		)
		(pad "1" smd rect
			(at -9.798 1.377 180)
			(size 0.23 0.66)
			(layers "B.Cu" "B.Mask" "B.Paste")
			(net 417 "GND")
			(pintype "passive")
		)
		(pad "2" smd rect
			(at -9.798 -1.333 180)
			(size 0.23 0.66)
			(layers "B.Cu" "B.Mask" "B.Paste")
			(net 417 "GND")
			(pintype "passive")
		)
		(pad "3" smd rect
			(at -9.399 1.377 180)
			(size 0.23 0.66)
			(layers "B.Cu" "B.Mask" "B.Paste")
			(net 70 "/Ethernet/ETH.TXRX_D_P")
			(pintype "passive")
		)
		(pad "4" smd rect
			(at -9.399 -1.333 180)
			(size 0.23 0.66)
			(layers "B.Cu" "B.Mask" "B.Paste")
			(net 71 "/Ethernet/ETH.TXRX_B_P")
			(pintype "passive")
		)
		(pad "5" smd rect
			(at -8.998 1.377 180)
			(size 0.23 0.66)
			(layers "B.Cu" "B.Mask" "B.Paste")
			(net 72 "/Ethernet/ETH.TXRX_D_N")
			(pintype "passive")
		)
		(pad "6" smd rect
			(at -8.998 -1.333 180)
			(size 0.23 0.66)
			(layers "B.Cu" "B.Mask" "B.Paste")
			(net 73 "/Ethernet/ETH.TXRX_B_N")
			(pintype "passive")
		)
		(pad "7" smd rect
			(at -8.598 1.377 180)
			(size 0.23 0.66)
			(layers "B.Cu" "B.Mask" "B.Paste")
			(net 417 "GND")
			(pintype "passive")
		)
		(pad "8" smd rect
			(at -8.598 -1.333 180)
			(size 0.23 0.66)
			(layers "B.Cu" "B.Mask" "B.Paste")
			(net 417 "GND")
			(pintype "passive")
		)
		(pad "9" smd rect
			(at -8.196 1.377 180)
			(size 0.23 0.66)
			(layers "B.Cu" "B.Mask" "B.Paste")
			(net 74 "/Ethernet/ETH.TXRX_C_N")
			(pintype "passive")
		)
		(pad "10" smd rect
			(at -8.196 -1.333 180)
			(size 0.23 0.66)
			(layers "B.Cu" "B.Mask" "B.Paste")
			(net 75 "/Ethernet/ETH.TXRX_A_N")
			(pintype "passive")
		)
		(pad "11" smd rect
			(at -7.798 1.377 180)
			(size 0.23 0.66)
			(layers "B.Cu" "B.Mask" "B.Paste")
			(net 76 "/Ethernet/ETH.TXRX_C_P")
			(pintype "passive")
		)
		(pad "12" smd rect
			(at -7.798 -1.333 180)
			(size 0.23 0.66)
			(layers "B.Cu" "B.Mask" "B.Paste")
			(net 77 "/Ethernet/ETH.TXRX_A_P")
			(pintype "passive")
		)
		(pad "13" smd rect
			(at -7.399 1.377 180)
			(size 0.23 0.66)
			(layers "B.Cu" "B.Mask" "B.Paste")
			(net 417 "GND")
			(pintype "passive")
		)
		(pad "14" smd rect
			(at -7.399 -1.333 180)
			(size 0.23 0.66)
			(layers "B.Cu" "B.Mask" "B.Paste")
			(net 417 "GND")
			(pintype "passive")
		)
		(pad "15" smd rect
			(at -6.998 1.377 180)
			(size 0.23 0.66)
			(layers "B.Cu" "B.Mask" "B.Paste")
			(net 78 "/Ethernet/ETH.LED2")
			(pintype "passive")
		)
		(pad "16" smd rect
			(at -6.998 -1.333 180)
			(size 0.23 0.66)
			(layers "B.Cu" "B.Mask" "B.Paste")
			(net 79 "/Ethernet/ETH.SYNC_IN")
			(pintype "passive")
		)
		(pad "17" smd rect
			(at -6.598 1.377 180)
			(size 0.23 0.66)
			(layers "B.Cu" "B.Mask" "B.Paste")
			(net 80 "/Ethernet/ETH.LED1")
			(pintype "passive")
		)
		(pad "18" smd rect
			(at -6.598 -1.333 180)
			(size 0.23 0.66)
			(layers "B.Cu" "B.Mask" "B.Paste")
			(net 81 "/Ethernet/ETH.SYNC_OUT")
			(pintype "passive")
		)
		(pad "19" smd rect
			(at -6.199 1.377 180)
			(size 0.23 0.66)
			(layers "B.Cu" "B.Mask" "B.Paste")
			(net 616 "unconnected-(J1-Pad19)")
			(pintype "passive+no_connect")
		)
		(pad "20" smd rect
			(at -6.199 -1.333 180)
			(size 0.23 0.66)
			(layers "B.Cu" "B.Mask" "B.Paste")
			(net 6 "unconnected-(J1-Pad20)")
			(pintype "passive+no_connect")
		)
		(pad "21" smd rect
			(at -5.798 1.377 180)
			(size 0.23 0.66)
			(layers "B.Cu" "B.Mask" "B.Paste")
			(net 7 "unconnected-(J1-Pad21)")
			(pintype "passive+no_connect")
		)
		(pad "22" smd rect
			(at -5.798 -1.333 180)
			(size 0.23 0.66)
			(layers "B.Cu" "B.Mask" "B.Paste")
			(net 417 "GND")
			(pintype "passive")
		)
		(pad "23" smd rect
			(at -5.399 1.377 180)
			(size 0.23 0.66)
			(layers "B.Cu" "B.Mask" "B.Paste")
			(net 417 "GND")
			(pintype "passive")
		)
		(pad "24" smd rect
			(at -5.399 -1.333 180)
			(size 0.23 0.66)
			(layers "B.Cu" "B.Mask" "B.Paste")
			(net 8 "GPIO26")
			(pintype "passive")
		)
		(pad "25" smd rect
			(at -4.998 1.377 180)
			(size 0.23 0.66)
			(layers "B.Cu" "B.Mask" "B.Paste")
			(net 20 "SPI6_SCLK{slash}RPI_GPIO21")
			(pintype "passive")
		)
		(pad "26" smd rect
			(at -4.998 -1.333 180)
			(size 0.23 0.66)
			(layers "B.Cu" "B.Mask" "B.Paste")
			(net 24 "SPI6_MISO{slash}RPI_GPIO19")
			(pintype "passive")
		)
		(pad "27" smd rect
			(at -4.598 1.377 180)
			(size 0.23 0.66)
			(layers "B.Cu" "B.Mask" "B.Paste")
			(net 25 "SPI6_MOSI{slash}RPI_GPIO20")
			(pintype "passive")
		)
		(pad "28" smd rect
			(at -4.598 -1.333 180)
			(size 0.23 0.66)
			(layers "B.Cu" "B.Mask" "B.Paste")
			(net 27 "UART5_TX{slash}RPI_GPIO13")
			(pintype "passive")
		)
		(pad "29" smd rect
			(at -4.199 1.377 180)
			(size 0.23 0.66)
			(layers "B.Cu" "B.Mask" "B.Paste")
			(net 11 "GPIO16")
			(pintype "passive")
		)
		(pad "30" smd rect
			(at -4.199 -1.333 180)
			(size 0.23 0.66)
			(layers "B.Cu" "B.Mask" "B.Paste")
			(net 12 "GPIO6")
			(pintype "passive")
		)
		(pad "31" smd rect
			(at -3.798 1.377 180)
			(size 0.23 0.66)
			(layers "B.Cu" "B.Mask" "B.Paste")
			(net 29 "UART5_TX{slash}RPI_GPIO12")
			(pintype "passive")
		)
		(pad "32" smd rect
			(at -3.798 -1.333 180)
			(size 0.23 0.66)
			(layers "B.Cu" "B.Mask" "B.Paste")
			(net 417 "GND")
			(pintype "passive")
		)
		(pad "33" smd rect
			(at -3.397 1.377 180)
			(size 0.23 0.66)
			(layers "B.Cu" "B.Mask" "B.Paste")
			(net 417 "GND")
			(pintype "passive")
		)
		(pad "34" smd rect
			(at -3.397 -1.333 180)
			(size 0.23 0.66)
			(layers "B.Cu" "B.Mask" "B.Paste")
			(net 30 "UART3_RX{slash}RPI_GPIO05")
			(pintype "passive")
		)
		(pad "35" smd rect
			(at -2.998 1.377 180)
			(size 0.23 0.66)
			(layers "B.Cu" "B.Mask" "B.Paste")
			(net 94 "/FPGA MSSIO/ID.SCL")
			(pintype "passive")
		)
		(pad "36" smd rect
			(at -2.998 -1.333 180)
			(size 0.23 0.66)
			(layers "B.Cu" "B.Mask" "B.Paste")
			(net 101 "/FPGA MSSIO/ID.SDA")
			(pintype "passive")
		)
		(pad "37" smd rect
			(at -2.597 1.377 180)
			(size 0.23 0.66)
			(layers "B.Cu" "B.Mask" "B.Paste")
			(net 17 "GPIO7")
			(pintype "passive")
		)
		(pad "38" smd rect
			(at -2.597 -1.333 180)
			(size 0.23 0.66)
			(layers "B.Cu" "B.Mask" "B.Paste")
			(net 18 "GPIO11")
			(pintype "passive")
		)
		(pad "39" smd rect
			(at -2.199 1.377 180)
			(size 0.23 0.66)
			(layers "B.Cu" "B.Mask" "B.Paste")
			(net 31 "UART4_TX{slash}RPI_GPIO08")
			(pintype "passive")
		)
		(pad "40" smd rect
			(at -2.199 -1.333 180)
			(size 0.23 0.66)
			(layers "B.Cu" "B.Mask" "B.Paste")
			(net 32 "UART4_RX{slash}RPI_GPIO09")
			(pintype "passive")
		)
		(pad "41" smd rect
			(at -1.798 1.377 180)
			(size 0.23 0.66)
			(layers "B.Cu" "B.Mask" "B.Paste")
			(net 21 "GPIO25")
			(pintype "passive")
		)
		(pad "42" smd rect
			(at -1.798 -1.333 180)
			(size 0.23 0.66)
			(layers "B.Cu" "B.Mask" "B.Paste")
			(net 417 "GND")
			(pintype "passive")
		)
		(pad "43" smd rect
			(at -1.397 1.377 180)
			(size 0.23 0.66)
			(layers "B.Cu" "B.Mask" "B.Paste")
			(net 34 "Net-(J1-Pad43)")
			(pintype "passive")
		)
		(pad "44" smd rect
			(at -1.397 -1.333 180)
			(size 0.23 0.66)
			(layers "B.Cu" "B.Mask" "B.Paste")
			(net 22 "GPIO10")
			(pintype "passive")
		)
		(pad "45" smd rect
			(at -0.998 1.377 180)
			(size 0.23 0.66)
			(layers "B.Cu" "B.Mask" "B.Paste")
			(net 23 "GPIO24")
			(pintype "passive")
		)
		(pad "46" smd rect
			(at -0.998 -1.333 180)
			(size 0.23 0.66)
			(layers "B.Cu" "B.Mask" "B.Paste")
			(net 63 "SDA6{slash}RPI_GPIO22")
			(pintype "passive")
		)
		(pad "47" smd rect
			(at -0.597 1.377 180)
			(size 0.23 0.66)
			(layers "B.Cu" "B.Mask" "B.Paste")
			(net 132 "SCL6{slash}RPI_GPIO23")
			(pintype "passive")
		)
		(pad "48" smd rect
			(at -0.597 -1.333 180)
			(size 0.23 0.66)
			(layers "B.Cu" "B.Mask" "B.Paste")
			(net 26 "GPIO27")
			(pintype "passive")
		)
		(pad "49" smd rect
			(at -0.199 1.377 180)
			(size 0.23 0.66)
			(layers "B.Cu" "B.Mask" "B.Paste")
			(net 133 "SPI6_CEO_N{slash}RPI_GPIO18")
			(pintype "passive")
		)
		(pad "50" smd rect
			(at -0.199 -1.333 180)
			(size 0.23 0.66)
			(layers "B.Cu" "B.Mask" "B.Paste")
			(net 245 "Net-(J1-Pad50)")
			(pintype "passive")
		)
		(pad "51" smd rect
			(at 0.201 1.377 180)
			(size 0.23 0.66)
			(layers "B.Cu" "B.Mask" "B.Paste")
			(net 134 "UART0_RX{slash}RPI_GPIO15")
			(pintype "passive")
		)
		(pad "52" smd rect
			(at 0.201 -1.333 180)
			(size 0.23 0.66)
			(layers "B.Cu" "B.Mask" "B.Paste")
			(net 417 "GND")
			(pintype "passive")
		)
		(pad "53" smd rect
			(at 0.6 1.377 180)
			(size 0.23 0.66)
			(layers "B.Cu" "B.Mask" "B.Paste")
			(net 417 "GND")
			(pintype "passive")
		)
		(pad "54" smd rect
			(at 0.6 -1.333 180)
			(size 0.23 0.66)
			(layers "B.Cu" "B.Mask" "B.Paste")
			(net 135 "UART3_TX{slash}RPI_GPIO04")
			(pintype "passive")
		)
		(pad "55" smd rect
			(at 1 1.377 180)
			(size 0.23 0.66)
			(layers "B.Cu" "B.Mask" "B.Paste")
			(net 173 "UART0_TX{slash}RPI_GPIO14")
			(pintype "passive")
		)
		(pad "56" smd rect
			(at 1 -1.333 180)
			(size 0.23 0.66)
			(layers "B.Cu" "B.Mask" "B.Paste")
			(net 174 "SCL1{slash}RPI_GPIO03")
			(pintype "passive")
		)
		(pad "57" smd rect
			(at 1.402 1.377 180)
			(size 0.23 0.66)
			(layers "B.Cu" "B.Mask" "B.Paste")
			(net 278 "/FPGA MSSIO/SD.CLK")
			(pintype "passive")
		)
		(pad "58" smd rect
			(at 1.402 -1.333 180)
			(size 0.23 0.66)
			(layers "B.Cu" "B.Mask" "B.Paste")
			(net 177 "SDA1{slash}RPI_GPIO02")
			(pintype "passive")
		)
		(pad "59" smd rect
			(at 1.802 1.377 180)
			(size 0.23 0.66)
			(layers "B.Cu" "B.Mask" "B.Paste")
			(net 417 "GND")
			(pintype "passive")
		)
		(pad "60" smd rect
			(at 1.802 -1.333 180)
			(size 0.23 0.66)
			(layers "B.Cu" "B.Mask" "B.Paste")
			(net 417 "GND")
			(pintype "passive")
		)
		(pad "61" smd rect
			(at 2.203 1.377 180)
			(size 0.23 0.66)
			(layers "B.Cu" "B.Mask" "B.Paste")
			(net 266 "/FPGA MSSIO/SD.DAT3")
			(pintype "passive")
		)
		(pad "62" smd rect
			(at 2.203 -1.333 180)
			(size 0.23 0.66)
			(layers "B.Cu" "B.Mask" "B.Paste")
			(net 388 "/FPGA MSSIO/SD.CMD")
			(pintype "passive")
		)
		(pad "63" smd rect
			(at 2.601 1.377 180)
			(size 0.23 0.66)
			(layers "B.Cu" "B.Mask" "B.Paste")
			(net 267 "/FPGA MSSIO/SD.DAT0")
			(pintype "passive")
		)
		(pad "64" smd rect
			(at 2.601 -1.333 180)
			(size 0.23 0.66)
			(layers "B.Cu" "B.Mask" "B.Paste")
			(net 268 "/FPGA MSSIO/SD.DAT5")
			(pintype "passive")
		)
		(pad "65" smd rect
			(at 3.001 1.377 180)
			(size 0.23 0.66)
			(layers "B.Cu" "B.Mask" "B.Paste")
			(net 417 "GND")
			(pintype "passive")
		)
		(pad "66" smd rect
			(at 3.001 -1.333 180)
			(size 0.23 0.66)
			(layers "B.Cu" "B.Mask" "B.Paste")
			(net 417 "GND")
			(pintype "passive")
		)
		(pad "67" smd rect
			(at 3.401 1.377 180)
			(size 0.23 0.66)
			(layers "B.Cu" "B.Mask" "B.Paste")
			(net 273 "/FPGA MSSIO/SD.DAT1")
			(pintype "passive")
		)
		(pad "68" smd rect
			(at 3.401 -1.333 180)
			(size 0.23 0.66)
			(layers "B.Cu" "B.Mask" "B.Paste")
			(net 277 "/FPGA MSSIO/SD.DAT4")
			(pintype "passive")
		)
		(pad "69" smd rect
			(at 3.802 1.377 180)
			(size 0.23 0.66)
			(layers "B.Cu" "B.Mask" "B.Paste")
			(net 274 "/FPGA MSSIO/SD.DAT2")
			(pintype "passive")
		)
		(pad "70" smd rect
			(at 3.802 -1.333 180)
			(size 0.23 0.66)
			(layers "B.Cu" "B.Mask" "B.Paste")
			(net 269 "/FPGA MSSIO/SD.DAT7")
			(pintype "passive")
		)
		(pad "71" smd rect
			(at 4.202 1.377 180)
			(size 0.23 0.66)
			(layers "B.Cu" "B.Mask" "B.Paste")
			(net 417 "GND")
			(pintype "passive")
		)
		(pad "72" smd rect
			(at 4.202 -1.333 180)
			(size 0.23 0.66)
			(layers "B.Cu" "B.Mask" "B.Paste")
			(net 276 "/FPGA MSSIO/SD.DAT6")
			(pintype "passive")
		)
		(pad "73" smd rect
			(at 4.6 1.377 180)
			(size 0.23 0.66)
			(layers "B.Cu" "B.Mask" "B.Paste")
			(net 246 "SD_VDD_OVERRIDE")
			(pintype "passive")
		)
		(pad "74" smd rect
			(at 4.6 -1.333 180)
			(size 0.23 0.66)
			(layers "B.Cu" "B.Mask" "B.Paste")
			(net 417 "GND")
			(pintype "passive")
		)
		(pad "75" smd rect
			(at 5.001 1.377 180)
			(size 0.23 0.66)
			(layers "B.Cu" "B.Mask" "B.Paste")
			(net 44 "SD_PWR_ON")
			(pintype "passive")
		)
		(pad "76" smd rect
			(at 5.001 -1.333 180)
			(size 0.23 0.66)
			(layers "B.Cu" "B.Mask" "B.Paste")
			(net 45 "unconnected-(J1-Pad76)")
			(pintype "passive+no_connect")
		)
		(pad "77" smd rect
			(at 5.401 1.377 180)
			(size 0.23 0.66)
			(layers "B.Cu" "B.Mask" "B.Paste")
			(net 90 "+5V")
			(pintype "passive")
		)
		(pad "78" smd rect
			(at 5.401 -1.333 180)
			(size 0.23 0.66)
			(layers "B.Cu" "B.Mask" "B.Paste")
			(net 333 "GPIO_VREF")
			(pintype "passive")
		)
		(pad "79" smd rect
			(at 5.802 1.377 180)
			(size 0.23 0.66)
			(layers "B.Cu" "B.Mask" "B.Paste")
			(net 90 "+5V")
			(pintype "passive")
		)
		(pad "80" smd rect
			(at 5.802 -1.333 180)
			(size 0.23 0.66)
			(layers "B.Cu" "B.Mask" "B.Paste")
			(net 623 "/FPGA GPIO/I^{2}C0.SCL")
			(pintype "passive")
		)
		(pad "81" smd rect
			(at 6.202 1.377 180)
			(size 0.23 0.66)
			(layers "B.Cu" "B.Mask" "B.Paste")
			(net 90 "+5V")
			(pintype "passive")
		)
		(pad "82" smd rect
			(at 6.202 -1.333 180)
			(size 0.23 0.66)
			(layers "B.Cu" "B.Mask" "B.Paste")
			(net 619 "/FPGA GPIO/I^{2}C0.SDA")
			(pintype "passive")
		)
		(pad "83" smd rect
			(at 6.6 1.377 180)
			(size 0.23 0.66)
			(layers "B.Cu" "B.Mask" "B.Paste")
			(net 90 "+5V")
			(pintype "passive")
		)
		(pad "84" smd rect
			(at 6.6 -1.333 180)
			(size 0.23 0.66)
			(layers "B.Cu" "B.Mask" "B.Paste")
			(net 50 "+3V3")
			(pintype "passive")
		)
		(pad "85" smd rect
			(at 7 1.377 180)
			(size 0.23 0.66)
			(layers "B.Cu" "B.Mask" "B.Paste")
			(net 90 "+5V")
			(pintype "passive")
		)
		(pad "86" smd rect
			(at 7 -1.333 180)
			(size 0.23 0.66)
			(layers "B.Cu" "B.Mask" "B.Paste")
			(net 50 "+3V3")
			(pintype "passive")
		)
		(pad "87" smd rect
			(at 7.401 1.377 180)
			(size 0.23 0.66)
			(layers "B.Cu" "B.Mask" "B.Paste")
			(net 90 "+5V")
			(pintype "passive")
		)
		(pad "88" smd rect
			(at 7.401 -1.333 180)
			(size 0.23 0.66)
			(layers "B.Cu" "B.Mask" "B.Paste")
			(net 48 "+1V8")
			(pintype "passive")
		)
		(pad "89" smd rect
			(at 7.802 1.377 180)
			(size 0.23 0.66)
			(layers "B.Cu" "B.Mask" "B.Paste")
			(net 171 "WL_REG_ON")
			(pintype "passive")
		)
		(pad "90" smd rect
			(at 7.802 -1.333 180)
			(size 0.23 0.66)
			(layers "B.Cu" "B.Mask" "B.Paste")
			(net 48 "+1V8")
			(pintype "passive")
		)
		(pad "91" smd rect
			(at 8.2 1.377 180)
			(size 0.23 0.66)
			(layers "B.Cu" "B.Mask" "B.Paste")
			(net 172 "BT_REG_ON")
			(pintype "passive")
		)
		(pad "92" smd rect
			(at 8.2 -1.333 180)
			(size 0.23 0.66)
			(layers "B.Cu" "B.Mask" "B.Paste")
			(net 54 "unconnected-(J1-Pad92)")
			(pintype "passive+no_connect")
		)
		(pad "93" smd rect
			(at 8.6 1.377 180)
			(size 0.23 0.66)
			(layers "B.Cu" "B.Mask" "B.Paste")
			(net 55 "unconnected-(J1-Pad93)")
			(pintype "passive+no_connect")
		)
		(pad "94" smd rect
			(at 8.6 -1.333 180)
			(size 0.23 0.66)
			(layers "B.Cu" "B.Mask" "B.Paste")
			(net 56 "unconnected-(J1-Pad94)")
			(pintype "passive+no_connect")
		)
		(pad "95" smd rect
			(at 9 1.377 180)
			(size 0.23 0.66)
			(layers "B.Cu" "B.Mask" "B.Paste")
			(net 98 "/Top Connector/PI_LED_nPWR")
			(pintype "passive")
		)
		(pad "96" smd rect
			(at 9 -1.333 180)
			(size 0.23 0.66)
			(layers "B.Cu" "B.Mask" "B.Paste")
			(net 58 "unconnected-(J1-Pad96)")
			(pintype "passive+no_connect")
		)
		(pad "97" smd rect
			(at 9.401 1.377 180)
			(size 0.23 0.66)
			(layers "B.Cu" "B.Mask" "B.Paste")
			(net 59 "unconnected-(J1-Pad97)")
			(pintype "passive+no_connect")
		)
		(pad "98" smd rect
			(at 9.401 -1.333 180)
			(size 0.23 0.66)
			(layers "B.Cu" "B.Mask" "B.Paste")
			(net 417 "GND")
			(pintype "passive")
		)
		(pad "99" smd rect
			(at 9.803 1.377 180)
			(size 0.23 0.66)
			(layers "B.Cu" "B.Mask" "B.Paste")
			(net 212 "GLOBAL_EN")
			(pintype "passive")
		)
		(pad "100" smd rect
			(at 9.803 -1.333 180)
			(size 0.23 0.66)
			(layers "B.Cu" "B.Mask" "B.Paste")
			(net 61 "unconnected-(J1-Pad100)")
			(pintype "passive+no_connect")
		)
		(pad "MP" smd rect
			(at -10.274 -1.333 180)
			(size 0.35 0.66)
			(layers "B.Cu" "B.Mask" "B.Paste")
			(net 417 "GND")
			(pinfunction "MP")
			(pintype "passive")
		)
		(pad "MP" smd rect
			(at -10.274 1.377 180)
			(size 0.35 0.66)
			(layers "B.Cu" "B.Mask" "B.Paste")
			(net 417 "GND")
			(pinfunction "MP")
			(pintype "passive")
		)
		(pad "MP" smd rect
			(at 10.276 -1.333 180)
			(size 0.35 0.66)
			(layers "B.Cu" "B.Mask" "B.Paste")
			(net 417 "GND")
			(pinfunction "MP")
			(pintype "passive")
		)
		(pad "MP" smd rect
			(at 10.276 1.377 180)
			(size 0.35 0.66)
			(layers "B.Cu" "B.Mask" "B.Paste")
			(net 417 "GND")
			(pinfunction "MP")
			(pintype "passive")
		)
	)
	(footprint "antmicro-footprints:C_0402_1005Metric"
		(layer "B.Cu")
		(at 213.361 123.254 -90)
		(descr "Capacitor SMD 0402")
		(tags "capacitor SMD 0402")
		(property "Reference" "C254"
			(at 1.886 -0.599 90)
			(layer "B.SilkS")
			(effects
				(font
					(size 0.7 0.7)
					(thickness 0.15)
				)
				(justify left bottom mirror)
			)
		)
		(property "Value" "C_10n_0402"
			(at -1.022927 -2.155213 90)
			(layer "B.Fab")
			(hide yes)
			(effects
				(font
					(size 0.7 0.7)
					(thickness 0.15)
				)
				(justify left bottom mirror)
			)
		)
		(property "Datasheet" "https://www.murata.com/products/productdetail?partno=GRM155R71H103KA88%23"
			(at 0 0 270)
			(layer "F.Fab")
			(hide yes)
			(effects
				(font
					(size 1.27 1.27)
					(thickness 0.15)
				)
			)
		)
		(property "Description" "SMD Multilayer Ceramic Capacitor, 10000 pF, 50 V, 0402 [1005 Metric], ± 10%, X7R, GRM Series"
			(at 0 0 270)
			(layer "F.Fab")
			(hide yes)
			(effects
				(font
					(size 1.27 1.27)
					(thickness 0.15)
				)
			)
		)
		(property "Author" "Antmicro"
			(at 90.107 336.615 0)
			(layer "B.Fab")
			(hide yes)
			(effects
				(font
					(size 1 1)
					(thickness 0.15)
				)
				(justify mirror)
			)
		)
		(property "Dielectric" "X7R"
			(at 90.107 336.615 0)
			(layer "B.Fab")
			(hide yes)
			(effects
				(font
					(size 1 1)
					(thickness 0.15)
				)
				(justify mirror)
			)
		)
		(property "License" "Apache-2.0"
			(at 90.107 336.615 0)
			(layer "B.Fab")
			(hide yes)
			(effects
				(font
					(size 1 1)
					(thickness 0.15)
				)
				(justify mirror)
			)
		)
		(property "MPN" "GRM155R71H103KA88D"
			(at 90.107 336.615 0)
			(layer "B.Fab")
			(hide yes)
			(effects
				(font
					(size 1 1)
					(thickness 0.15)
				)
				(justify mirror)
			)
		)
		(property "Manufacturer" "Murata"
			(at 90.107 336.615 0)
			(layer "B.Fab")
			(hide yes)
			(effects
				(font
					(size 1 1)
					(thickness 0.15)
				)
				(justify mirror)
			)
		)
		(property "Public" ""
			(at 90.107 336.615 0)
			(layer "B.Fab")
			(hide yes)
			(effects
				(font
					(size 1 1)
					(thickness 0.15)
				)
				(justify mirror)
			)
		)
		(property "Val" "10n"
			(at 90.107 336.615 0)
			(layer "B.Fab")
			(hide yes)
			(effects
				(font
					(size 1 1)
					(thickness 0.15)
				)
				(justify mirror)
			)
		)
		(property "Voltage" "50V"
			(at 90.107 336.615 0)
			(layer "B.Fab")
			(hide yes)
			(effects
				(font
					(size 1 1)
					(thickness 0.15)
				)
				(justify mirror)
			)
		)
		(sheetname "/Ethernet/")
		(sheetfile "ethernet.kicad_sch")
		(attr smd)
		(fp_rect
			(start -0.925 0.47)
			(end 0.925 -0.47)
			(stroke
				(width 0.05)
				(type default)
			)
			(fill no)
			(layer "B.CrtYd")
		)
		(fp_line
			(start -0.494 0.25)
			(end 0.504 0.25)
			(stroke
				(width 0.15)
				(type solid)
			)
			(layer "B.Fab")
		)
		(fp_line
			(start 0.504 0.25)
			(end 0.504 -0.248)
			(stroke
				(width 0.15)
				(type solid)
			)
			(layer "B.Fab")
		)
		(fp_line
			(start -0.494 -0.248)
			(end -0.494 0.25)
			(stroke
				(width 0.15)
				(type solid)
			)
			(layer "B.Fab")
		)
		(fp_line
			(start 0.504 -0.248)
			(end -0.494 -0.248)
			(stroke
				(width 0.15)
				(type solid)
			)
			(layer "B.Fab")
		)
		(fp_text user "${REFERENCE}"
			(at -0.939 -4.599 90)
			(layer "B.Fab")
			(effects
				(font
					(size 0.7 0.7)
					(thickness 0.15)
				)
				(justify left bottom mirror)
			)
		)
		(fp_text user "License: Apache-2.0"
			(at -0.939 -5.799 90)
			(layer "B.Fab")
			(effects
				(font
					(size 0.7 0.7)
					(thickness 0.15)
				)
				(justify left bottom mirror)
			)
		)
		(fp_text user "Author: Antmicro"
			(at -0.939 -3.399 90)
			(layer "B.Fab")
			(effects
				(font
					(size 0.7 0.7)
					(thickness 0.15)
				)
				(justify left bottom mirror)
			)
		)
		(pad "1" smd roundrect
			(at -0.48 0 270)
			(size 0.59 0.64)
			(layers "B.Cu" "B.Mask" "B.Paste")
			(roundrect_rratio 0.25)
			(net 417 "GND")
			(pintype "passive")
		)
		(pad "2" smd roundrect
			(at 0.48 0 270)
			(size 0.59 0.64)
			(layers "B.Cu" "B.Mask" "B.Paste")
			(roundrect_rratio 0.25)
			(net 50 "+3V3")
			(pintype "passive")
		)
	)
	(footprint "antmicro-footprints:R_0402_1005Metric"
		(layer "B.Cu")
		(at 187.875 154.42 -90)
		(descr "Resistor SMD 0402")
		(tags "resistor SMD 0402")
		(property "Reference" "R79"
			(at 1.08 -2.575 180)
			(layer "B.SilkS")
			(effects
				(font
					(size 0.7 0.7)
					(thickness 0.15)
				)
				(justify left bottom mirror)
			)
		)
		(property "Value" "R_2k2_0402"
			(at -1.011843 -1.772047 90)
			(layer "B.Fab")
			(hide yes)
			(effects
				(font
					(size 0.7 0.7)
					(thickness 0.15)
				)
				(justify left bottom mirror)
			)
		)
		(property "Datasheet" "https://www.bourns.com/docs/product-datasheets/cr.pdf"
			(at 0 0 270)
			(layer "F.Fab")
			(hide yes)
			(effects
				(font
					(size 1.27 1.27)
					(thickness 0.15)
				)
			)
		)
		(property "Description" "SMD Chip Resistor, 2.2 kohm, ± 1%, 62.5 mW, 0402 [1005 Metric], Thick Film, General Purpose"
			(at 0 0 270)
			(layer "F.Fab")
			(hide yes)
			(effects
				(font
					(size 1.27 1.27)
					(thickness 0.15)
				)
			)
		)
		(property "Author" "Antmicro"
			(at 33.455 342.295 0)
			(layer "B.Fab")
			(hide yes)
			(effects
				(font
					(size 1 1)
					(thickness 0.15)
				)
				(justify mirror)
			)
		)
		(property "License" "Apache-2.0"
			(at 33.455 342.295 0)
			(layer "B.Fab")
			(hide yes)
			(effects
				(font
					(size 1 1)
					(thickness 0.15)
				)
				(justify mirror)
			)
		)
		(property "MPN" "CR0402-FX-2201GLF"
			(at 33.455 342.295 0)
			(layer "B.Fab")
			(hide yes)
			(effects
				(font
					(size 1 1)
					(thickness 0.15)
				)
				(justify mirror)
			)
		)
		(property "Manufacturer" "Bourns"
			(at 33.455 342.295 0)
			(layer "B.Fab")
			(hide yes)
			(effects
				(font
					(size 1 1)
					(thickness 0.15)
				)
				(justify mirror)
			)
		)
		(property "Public" ""
			(at 33.455 342.295 0)
			(layer "B.Fab")
			(hide yes)
			(effects
				(font
					(size 1 1)
					(thickness 0.15)
				)
				(justify mirror)
			)
		)
		(property "Tolerance" "1%"
			(at 33.455 342.295 0)
			(layer "B.Fab")
			(hide yes)
			(effects
				(font
					(size 1 1)
					(thickness 0.15)
				)
				(justify mirror)
			)
		)
		(property "Val" "2k2"
			(at 33.455 342.295 0)
			(layer "B.Fab")
			(hide yes)
			(effects
				(font
					(size 1 1)
					(thickness 0.15)
				)
				(justify mirror)
			)
		)
		(sheetname "/HDMI/")
		(sheetfile "hdmi.kicad_sch")
		(attr smd)
		(fp_rect
			(start -0.925 0.47)
			(end 0.925 -0.47)
			(stroke
				(width 0.05)
				(type default)
			)
			(fill no)
			(layer "B.CrtYd")
		)
		(fp_rect
			(start -0.5 0.25)
			(end 0.5 -0.25)
			(stroke
				(width 0.15)
				(type solid)
			)
			(fill no)
			(layer "B.Fab")
		)
		(fp_text user "Author: Antmicro"
			(at -0.95 -4.169 90)
			(layer "B.Fab")
			(effects
				(font
					(size 0.7 0.7)
					(thickness 0.15)
				)
				(justify left bottom mirror)
			)
		)
		(fp_text user "${REFERENCE}"
			(at -0.95 -3.168 90)
			(layer "B.Fab")
			(effects
				(font
					(size 0.7 0.7)
					(thickness 0.15)
				)
				(justify left bottom mirror)
			)
		)
		(fp_text user "License: Apache-2.0"
			(at -0.95 -5.169 90)
			(layer "B.Fab")
			(effects
				(font
					(size 0.7 0.7)
					(thickness 0.15)
				)
				(justify left bottom mirror)
			)
		)
		(pad "1" smd roundrect
			(at -0.48 0 270)
			(size 0.59 0.64)
			(layers "B.Cu" "B.Mask" "B.Paste")
			(roundrect_rratio 0.25)
			(net 218 "/Bottom Connector/HDMI0.SCL")
			(pintype "passive")
		)
		(pad "2" smd roundrect
			(at 0.48 0 270)
			(size 0.59 0.64)
			(layers "B.Cu" "B.Mask" "B.Paste")
			(roundrect_rratio 0.25)
			(net 90 "+5V")
			(pintype "passive")
		)
	)
	(footprint "antmicro-footprints:C_0402_1005Metric"
		(layer "B.Cu")
		(at 184.975 142.9875 -90)
		(descr "Capacitor SMD 0402")
		(tags "capacitor SMD 0402")
		(property "Reference" "C109"
			(at 0.7125 -3.3 180)
			(layer "B.SilkS")
			(effects
				(font
					(size 0.7 0.7)
					(thickness 0.15)
				)
				(justify left bottom mirror)
			)
		)
		(property "Value" "C_22u_0402"
			(at -1.022927 -2.155213 90)
			(layer "B.Fab")
			(hide yes)
			(effects
				(font
					(size 0.7 0.7)
					(thickness 0.15)
				)
				(justify left bottom mirror)
			)
		)
		(property "Datasheet" "https://www.murata.com/products/productdetail?partno=GRM158R60J226ME01%23"
			(at 0 0 90)
			(layer "F.Fab")
			(hide yes)
			(effects
				(font
					(size 1.27 1.27)
					(thickness 0.15)
				)
			)
		)
		(property "Description" "SMD Multilayer Ceramic Capacitor, 22 uF, 4 V, 0402 [1005 Metric], X6S"
			(at 0 0 90)
			(layer "F.Fab")
			(hide yes)
			(effects
				(font
					(size 1.27 1.27)
					(thickness 0.15)
				)
			)
		)
		(property "Author" "Antmicro"
			(at 41.9875 327.9625 0)
			(layer "B.Fab")
			(hide yes)
			(effects
				(font
					(size 1 1)
					(thickness 0.15)
				)
				(justify mirror)
			)
		)
		(property "Dielectric" ""
			(at 41.9875 327.9625 0)
			(layer "B.Fab")
			(hide yes)
			(effects
				(font
					(size 1 1)
					(thickness 0.15)
				)
				(justify mirror)
			)
		)
		(property "License" "Apache-2.0"
			(at 41.9875 327.9625 0)
			(layer "B.Fab")
			(hide yes)
			(effects
				(font
					(size 1 1)
					(thickness 0.15)
				)
				(justify mirror)
			)
		)
		(property "MPN" "GRM158R60J226ME01D"
			(at 41.9875 327.9625 0)
			(layer "B.Fab")
			(hide yes)
			(effects
				(font
					(size 1 1)
					(thickness 0.15)
				)
				(justify mirror)
			)
		)
		(property "Manufacturer" "Murata"
			(at 41.9875 327.9625 0)
			(layer "B.Fab")
			(hide yes)
			(effects
				(font
					(size 1 1)
					(thickness 0.15)
				)
				(justify mirror)
			)
		)
		(property "Public" ""
			(at 41.9875 327.9625 0)
			(layer "B.Fab")
			(hide yes)
			(effects
				(font
					(size 1 1)
					(thickness 0.15)
				)
				(justify mirror)
			)
		)
		(property "Val" "22u"
			(at 41.9875 327.9625 0)
			(layer "B.Fab")
			(hide yes)
			(effects
				(font
					(size 1 1)
					(thickness 0.15)
				)
				(justify mirror)
			)
		)
		(property "Voltage" ""
			(at 41.9875 327.9625 0)
			(layer "B.Fab")
			(hide yes)
			(effects
				(font
					(size 1 1)
					(thickness 0.15)
				)
				(justify mirror)
			)
		)
		(sheetname "/Supply/")
		(sheetfile "supply.kicad_sch")
		(attr smd)
		(fp_rect
			(start -0.925 0.47)
			(end 0.925 -0.47)
			(stroke
				(width 0.05)
				(type default)
			)
			(fill no)
			(layer "B.CrtYd")
		)
		(fp_line
			(start -0.494 0.25)
			(end 0.504 0.25)
			(stroke
				(width 0.15)
				(type solid)
			)
			(layer "B.Fab")
		)
		(fp_line
			(start 0.504 0.25)
			(end 0.504 -0.248)
			(stroke
				(width 0.15)
				(type solid)
			)
			(layer "B.Fab")
		)
		(fp_line
			(start -0.494 -0.248)
			(end -0.494 0.25)
			(stroke
				(width 0.15)
				(type solid)
			)
			(layer "B.Fab")
		)
		(fp_line
			(start 0.504 -0.248)
			(end -0.494 -0.248)
			(stroke
				(width 0.15)
				(type solid)
			)
			(layer "B.Fab")
		)
		(fp_text user "${REFERENCE}"
			(at -0.939 -4.599 90)
			(layer "B.Fab")
			(effects
				(font
					(size 0.7 0.7)
					(thickness 0.15)
				)
				(justify left bottom mirror)
			)
		)
		(fp_text user "License: Apache-2.0"
			(at -0.939 -5.799 90)
			(layer "B.Fab")
			(effects
				(font
					(size 0.7 0.7)
					(thickness 0.15)
				)
				(justify left bottom mirror)
			)
		)
		(fp_text user "Author: Antmicro"
			(at -0.939 -3.399 90)
			(layer "B.Fab")
			(effects
				(font
					(size 0.7 0.7)
					(thickness 0.15)
				)
				(justify left bottom mirror)
			)
		)
		(pad "1" smd roundrect
			(at -0.48 0 270)
			(size 0.59 0.64)
			(layers "B.Cu" "B.Mask" "B.Paste")
			(roundrect_rratio 0.25)
			(net 417 "GND")
			(pintype "passive")
		)
		(pad "2" smd roundrect
			(at 0.48 0 270)
			(size 0.59 0.64)
			(layers "B.Cu" "B.Mask" "B.Paste")
			(roundrect_rratio 0.25)
			(net 409 "/Supply/SENSE4_P")
			(pintype "passive")
		)
	)
	(footprint "antmicro-footprints:R_0402_1005Metric"
		(layer "B.Cu")
		(at 187.875 152.47 90)
		(descr "Resistor SMD 0402")
		(tags "resistor SMD 0402")
		(property "Reference" "R73"
			(at 0.77 2.05 270)
			(layer "B.SilkS")
			(effects
				(font
					(size 0.7 0.7)
					(thickness 0.15)
				)
				(justify left bottom mirror)
			)
		)
		(property "Value" "R_2k2_0402"
			(at -1.011843 -1.772047 270)
			(layer "B.Fab")
			(hide yes)
			(effects
				(font
					(size 0.7 0.7)
					(thickness 0.15)
				)
				(justify left bottom mirror)
			)
		)
		(property "Datasheet" "https://www.bourns.com/docs/product-datasheets/cr.pdf"
			(at 0 0 90)
			(layer "F.Fab")
			(hide yes)
			(effects
				(font
					(size 1.27 1.27)
					(thickness 0.15)
				)
			)
		)
		(property "Description" "SMD Chip Resistor, 2.2 kohm, ± 1%, 62.5 mW, 0402 [1005 Metric], Thick Film, General Purpose"
			(at 0 0 90)
			(layer "F.Fab")
			(hide yes)
			(effects
				(font
					(size 1.27 1.27)
					(thickness 0.15)
				)
			)
		)
		(property "Author" "Antmicro"
			(at 340.345 -35.405 0)
			(layer "B.Fab")
			(hide yes)
			(effects
				(font
					(size 1 1)
					(thickness 0.15)
				)
				(justify mirror)
			)
		)
		(property "License" "Apache-2.0"
			(at 340.345 -35.405 0)
			(layer "B.Fab")
			(hide yes)
			(effects
				(font
					(size 1 1)
					(thickness 0.15)
				)
				(justify mirror)
			)
		)
		(property "MPN" "CR0402-FX-2201GLF"
			(at 340.345 -35.405 0)
			(layer "B.Fab")
			(hide yes)
			(effects
				(font
					(size 1 1)
					(thickness 0.15)
				)
				(justify mirror)
			)
		)
		(property "Manufacturer" "Bourns"
			(at 340.345 -35.405 0)
			(layer "B.Fab")
			(hide yes)
			(effects
				(font
					(size 1 1)
					(thickness 0.15)
				)
				(justify mirror)
			)
		)
		(property "Public" ""
			(at 340.345 -35.405 0)
			(layer "B.Fab")
			(hide yes)
			(effects
				(font
					(size 1 1)
					(thickness 0.15)
				)
				(justify mirror)
			)
		)
		(property "Tolerance" "1%"
			(at 340.345 -35.405 0)
			(layer "B.Fab")
			(hide yes)
			(effects
				(font
					(size 1 1)
					(thickness 0.15)
				)
				(justify mirror)
			)
		)
		(property "Val" "2k2"
			(at 340.345 -35.405 0)
			(layer "B.Fab")
			(hide yes)
			(effects
				(font
					(size 1 1)
					(thickness 0.15)
				)
				(justify mirror)
			)
		)
		(sheetname "/HDMI/")
		(sheetfile "hdmi.kicad_sch")
		(attr smd)
		(fp_rect
			(start -0.925 0.47)
			(end 0.925 -0.47)
			(stroke
				(width 0.05)
				(type default)
			)
			(fill no)
			(layer "B.CrtYd")
		)
		(fp_rect
			(start -0.5 0.25)
			(end 0.5 -0.25)
			(stroke
				(width 0.15)
				(type solid)
			)
			(fill no)
			(layer "B.Fab")
		)
		(fp_text user "${REFERENCE}"
			(at -0.95 -3.168 270)
			(layer "B.Fab")
			(effects
				(font
					(size 0.7 0.7)
					(thickness 0.15)
				)
				(justify left bottom mirror)
			)
		)
		(fp_text user "License: Apache-2.0"
			(at -0.95 -5.169 270)
			(layer "B.Fab")
			(effects
				(font
					(size 0.7 0.7)
					(thickness 0.15)
				)
				(justify left bottom mirror)
			)
		)
		(fp_text user "Author: Antmicro"
			(at -0.95 -4.169 270)
			(layer "B.Fab")
			(effects
				(font
					(size 0.7 0.7)
					(thickness 0.15)
				)
				(justify left bottom mirror)
			)
		)
		(pad "1" smd roundrect
			(at -0.48 0 90)
			(size 0.59 0.64)
			(layers "B.Cu" "B.Mask" "B.Paste")
			(roundrect_rratio 0.25)
			(net 206 "/Bottom Connector/HDMI0.SDA")
			(pintype "passive")
		)
		(pad "2" smd roundrect
			(at 0.48 0 90)
			(size 0.59 0.64)
			(layers "B.Cu" "B.Mask" "B.Paste")
			(roundrect_rratio 0.25)
			(net 90 "+5V")
			(pintype "passive")
		)
	)
	(footprint "antmicro-footprints:C_0402_1005Metric"
		(layer "B.Cu")
		(at 208.12 142.62 180)
		(descr "Capacitor SMD 0402")
		(tags "capacitor SMD 0402")
		(property "Reference" "C197"
			(at -1.43 0.52 0)
			(layer "B.SilkS")
			(effects
				(font
					(size 0.7 0.7)
					(thickness 0.15)
				)
				(justify left bottom mirror)
			)
		)
		(property "Value" "C_1u_0402"
			(at -1.022927 -2.155213 0)
			(layer "B.Fab")
			(hide yes)
			(effects
				(font
					(size 0.7 0.7)
					(thickness 0.15)
				)
				(justify left bottom mirror)
			)
		)
		(property "Datasheet" "https://product.tdk.com/en/search/capacitor/ceramic/mlcc/info?part_no=C1005X6S1A105K050BC"
			(at 0 0 180)
			(layer "F.Fab")
			(hide yes)
			(effects
				(font
					(size 1.27 1.27)
					(thickness 0.15)
				)
			)
		)
		(property "Description" "SMD Multilayer Ceramic Capacitor, 1 µF, 10 V, 0402 [1005 Metric], ± 10%, X6S, C"
			(at 0 0 180)
			(layer "F.Fab")
			(hide yes)
			(effects
				(font
					(size 1.27 1.27)
					(thickness 0.15)
				)
			)
		)
		(property "Author" "Antmicro"
			(at 416.24 285.24 0)
			(layer "B.Fab")
			(hide yes)
			(effects
				(font
					(size 1 1)
					(thickness 0.15)
				)
				(justify mirror)
			)
		)
		(property "Dielectric" ""
			(at 416.24 285.24 0)
			(layer "B.Fab")
			(hide yes)
			(effects
				(font
					(size 1 1)
					(thickness 0.15)
				)
				(justify mirror)
			)
		)
		(property "License" "Apache-2.0"
			(at 416.24 285.24 0)
			(layer "B.Fab")
			(hide yes)
			(effects
				(font
					(size 1 1)
					(thickness 0.15)
				)
				(justify mirror)
			)
		)
		(property "MPN" "C1005X6S1A105K050BC"
			(at 416.24 285.24 0)
			(layer "B.Fab")
			(hide yes)
			(effects
				(font
					(size 1 1)
					(thickness 0.15)
				)
				(justify mirror)
			)
		)
		(property "Manufacturer" "TDK"
			(at 416.24 285.24 0)
			(layer "B.Fab")
			(hide yes)
			(effects
				(font
					(size 1 1)
					(thickness 0.15)
				)
				(justify mirror)
			)
		)
		(property "Public" ""
			(at 416.24 285.24 0)
			(layer "B.Fab")
			(hide yes)
			(effects
				(font
					(size 1 1)
					(thickness 0.15)
				)
				(justify mirror)
			)
		)
		(property "Val" "1u"
			(at 416.24 285.24 0)
			(layer "B.Fab")
			(hide yes)
			(effects
				(font
					(size 1 1)
					(thickness 0.15)
				)
				(justify mirror)
			)
		)
		(property "Voltage" ""
			(at 416.24 285.24 0)
			(layer "B.Fab")
			(hide yes)
			(effects
				(font
					(size 1 1)
					(thickness 0.15)
				)
				(justify mirror)
			)
		)
		(sheetname "/MIPI CrossLink/")
		(sheetfile "crosslink.kicad_sch")
		(attr smd)
		(fp_rect
			(start -0.925 0.47)
			(end 0.925 -0.47)
			(stroke
				(width 0.05)
				(type default)
			)
			(fill no)
			(layer "B.CrtYd")
		)
		(fp_line
			(start 0.504 0.25)
			(end 0.504 -0.248)
			(stroke
				(width 0.15)
				(type solid)
			)
			(layer "B.Fab")
		)
		(fp_line
			(start 0.504 -0.248)
			(end -0.494 -0.248)
			(stroke
				(width 0.15)
				(type solid)
			)
			(layer "B.Fab")
		)
		(fp_line
			(start -0.494 0.25)
			(end 0.504 0.25)
			(stroke
				(width 0.15)
				(type solid)
			)
			(layer "B.Fab")
		)
		(fp_line
			(start -0.494 -0.248)
			(end -0.494 0.25)
			(stroke
				(width 0.15)
				(type solid)
			)
			(layer "B.Fab")
		)
		(fp_text user "${REFERENCE}"
			(at -0.939 -4.599 0)
			(layer "B.Fab")
			(effects
				(font
					(size 0.7 0.7)
					(thickness 0.15)
				)
				(justify left bottom mirror)
			)
		)
		(fp_text user "Author: Antmicro"
			(at -0.939 -3.399 0)
			(layer "B.Fab")
			(effects
				(font
					(size 0.7 0.7)
					(thickness 0.15)
				)
				(justify left bottom mirror)
			)
		)
		(fp_text user "License: Apache-2.0"
			(at -0.939 -5.799 0)
			(layer "B.Fab")
			(effects
				(font
					(size 0.7 0.7)
					(thickness 0.15)
				)
				(justify left bottom mirror)
			)
		)
		(pad "1" smd roundrect
			(at -0.48 0 180)
			(size 0.59 0.64)
			(layers "B.Cu" "B.Mask" "B.Paste")
			(roundrect_rratio 0.25)
			(net 417 "GND")
			(pintype "passive")
		)
		(pad "2" smd roundrect
			(at 0.48 0 180)
			(size 0.59 0.64)
			(layers "B.Cu" "B.Mask" "B.Paste")
			(roundrect_rratio 0.25)
			(net 180 "/MIPI CrossLink/CL_VCCGPLL")
			(pintype "passive")
		)
	)
	(footprint "antmicro-footprints:C_0402_1005Metric"
		(layer "B.Cu")
		(at 213.861 119.754 180)
		(descr "Capacitor SMD 0402")
		(tags "capacitor SMD 0402")
		(property "Reference" "C115"
			(at -15.389 -13.346 0)
			(layer "B.SilkS")
			(effects
				(font
					(size 0.7 0.7)
					(thickness 0.15)
				)
				(justify left bottom mirror)
			)
		)
		(property "Value" "C_1u_0402"
			(at -1.022927 -2.155213 0)
			(layer "B.Fab")
			(hide yes)
			(effects
				(font
					(size 0.7 0.7)
					(thickness 0.15)
				)
				(justify left bottom mirror)
			)
		)
		(property "Datasheet" "https://product.tdk.com/en/search/capacitor/ceramic/mlcc/info?part_no=C1005X6S1A105K050BC"
			(at 0 0 180)
			(layer "F.Fab")
			(hide yes)
			(effects
				(font
					(size 1.27 1.27)
					(thickness 0.15)
				)
			)
		)
		(property "Description" "SMD Multilayer Ceramic Capacitor, 1 µF, 10 V, 0402 [1005 Metric], ± 10%, X6S, C"
			(at 0 0 180)
			(layer "F.Fab")
			(hide yes)
			(effects
				(font
					(size 1.27 1.27)
					(thickness 0.15)
				)
			)
		)
		(property "Author" "Antmicro"
			(at 427.722 239.508 0)
			(layer "B.Fab")
			(hide yes)
			(effects
				(font
					(size 1 1)
					(thickness 0.15)
				)
				(justify mirror)
			)
		)
		(property "Dielectric" ""
			(at 427.722 239.508 0)
			(layer "B.Fab")
			(hide yes)
			(effects
				(font
					(size 1 1)
					(thickness 0.15)
				)
				(justify mirror)
			)
		)
		(property "License" "Apache-2.0"
			(at 427.722 239.508 0)
			(layer "B.Fab")
			(hide yes)
			(effects
				(font
					(size 1 1)
					(thickness 0.15)
				)
				(justify mirror)
			)
		)
		(property "MPN" "C1005X6S1A105K050BC"
			(at 427.722 239.508 0)
			(layer "B.Fab")
			(hide yes)
			(effects
				(font
					(size 1 1)
					(thickness 0.15)
				)
				(justify mirror)
			)
		)
		(property "Manufacturer" "TDK"
			(at 427.722 239.508 0)
			(layer "B.Fab")
			(hide yes)
			(effects
				(font
					(size 1 1)
					(thickness 0.15)
				)
				(justify mirror)
			)
		)
		(property "Public" ""
			(at 427.722 239.508 0)
			(layer "B.Fab")
			(hide yes)
			(effects
				(font
					(size 1 1)
					(thickness 0.15)
				)
				(justify mirror)
			)
		)
		(property "Val" "1u"
			(at 427.722 239.508 0)
			(layer "B.Fab")
			(hide yes)
			(effects
				(font
					(size 1 1)
					(thickness 0.15)
				)
				(justify mirror)
			)
		)
		(property "Voltage" ""
			(at 427.722 239.508 0)
			(layer "B.Fab")
			(hide yes)
			(effects
				(font
					(size 1 1)
					(thickness 0.15)
				)
				(justify mirror)
			)
		)
		(sheetname "/Ethernet/")
		(sheetfile "ethernet.kicad_sch")
		(attr smd)
		(fp_rect
			(start -0.925 0.47)
			(end 0.925 -0.47)
			(stroke
				(width 0.05)
				(type default)
			)
			(fill no)
			(layer "B.CrtYd")
		)
		(fp_line
			(start 0.504 0.25)
			(end 0.504 -0.248)
			(stroke
				(width 0.15)
				(type solid)
			)
			(layer "B.Fab")
		)
		(fp_line
			(start 0.504 -0.248)
			(end -0.494 -0.248)
			(stroke
				(width 0.15)
				(type solid)
			)
			(layer "B.Fab")
		)
		(fp_line
			(start -0.494 0.25)
			(end 0.504 0.25)
			(stroke
				(width 0.15)
				(type solid)
			)
			(layer "B.Fab")
		)
		(fp_line
			(start -0.494 -0.248)
			(end -0.494 0.25)
			(stroke
				(width 0.15)
				(type solid)
			)
			(layer "B.Fab")
		)
		(fp_text user "License: Apache-2.0"
			(at -0.939 -5.799 0)
			(layer "B.Fab")
			(effects
				(font
					(size 0.7 0.7)
					(thickness 0.15)
				)
				(justify left bottom mirror)
			)
		)
		(fp_text user "${REFERENCE}"
			(at -0.939 -4.599 0)
			(layer "B.Fab")
			(effects
				(font
					(size 0.7 0.7)
					(thickness 0.15)
				)
				(justify left bottom mirror)
			)
		)
		(fp_text user "Author: Antmicro"
			(at -0.939 -3.399 0)
			(layer "B.Fab")
			(effects
				(font
					(size 0.7 0.7)
					(thickness 0.15)
				)
				(justify left bottom mirror)
			)
		)
		(pad "1" smd roundrect
			(at -0.48 0 180)
			(size 0.59 0.64)
			(layers "B.Cu" "B.Mask" "B.Paste")
			(roundrect_rratio 0.25)
			(net 417 "GND")
			(pintype "passive")
		)
		(pad "2" smd roundrect
			(at 0.48 0 180)
			(size 0.59 0.64)
			(layers "B.Cu" "B.Mask" "B.Paste")
			(roundrect_rratio 0.25)
			(net 50 "+3V3")
			(pintype "passive")
		)
	)
	(footprint "antmicro-footprints:C_0402_1005Metric"
		(layer "B.Cu")
		(at 196.09 134.72 90)
		(descr "Capacitor SMD 0402")
		(tags "capacitor SMD 0402")
		(property "Reference" "C42"
			(at 5.32 -9.59 90)
			(layer "B.SilkS")
			(effects
				(font
					(size 0.7 0.7)
					(thickness 0.15)
				)
				(justify right bottom mirror)
			)
		)
		(property "Value" "C_10n_0402"
			(at -1.022927 -2.155213 90)
			(layer "B.Fab")
			(hide yes)
			(effects
				(font
					(size 0.7 0.7)
					(thickness 0.15)
				)
				(justify right bottom mirror)
			)
		)
		(property "Datasheet" "https://www.murata.com/products/productdetail?partno=GRM155R71H103KA88%23"
			(at 0 0 90)
			(layer "F.Fab")
			(hide yes)
			(effects
				(font
					(size 1.27 1.27)
					(thickness 0.15)
				)
			)
		)
		(property "Description" "SMD Multilayer Ceramic Capacitor, 10000 pF, 50 V, 0402 [1005 Metric], ± 10%, X7R, GRM Series"
			(at 0 0 90)
			(layer "F.Fab")
			(hide yes)
			(effects
				(font
					(size 1.27 1.27)
					(thickness 0.15)
				)
			)
		)
		(property "Author" "Antmicro"
			(at 330.81 -61.37 0)
			(layer "B.Fab")
			(hide yes)
			(effects
				(font
					(size 1 1)
					(thickness 0.15)
				)
				(justify mirror)
			)
		)
		(property "Dielectric" "X7R"
			(at 330.81 -61.37 0)
			(layer "B.Fab")
			(hide yes)
			(effects
				(font
					(size 1 1)
					(thickness 0.15)
				)
				(justify mirror)
			)
		)
		(property "License" "Apache-2.0"
			(at 330.81 -61.37 0)
			(layer "B.Fab")
			(hide yes)
			(effects
				(font
					(size 1 1)
					(thickness 0.15)
				)
				(justify mirror)
			)
		)
		(property "MPN" "GRM155R71H103KA88D"
			(at 330.81 -61.37 0)
			(layer "B.Fab")
			(hide yes)
			(effects
				(font
					(size 1 1)
					(thickness 0.15)
				)
				(justify mirror)
			)
		)
		(property "Manufacturer" "Murata"
			(at 330.81 -61.37 0)
			(layer "B.Fab")
			(hide yes)
			(effects
				(font
					(size 1 1)
					(thickness 0.15)
				)
				(justify mirror)
			)
		)
		(property "Public" ""
			(at 330.81 -61.37 0)
			(layer "B.Fab")
			(hide yes)
			(effects
				(font
					(size 1 1)
					(thickness 0.15)
				)
				(justify mirror)
			)
		)
		(property "Val" "10n"
			(at 330.81 -61.37 0)
			(layer "B.Fab")
			(hide yes)
			(effects
				(font
					(size 1 1)
					(thickness 0.15)
				)
				(justify mirror)
			)
		)
		(property "Voltage" "50V"
			(at 330.81 -61.37 0)
			(layer "B.Fab")
			(hide yes)
			(effects
				(font
					(size 1 1)
					(thickness 0.15)
				)
				(justify mirror)
			)
		)
		(sheetname "/FPGA Supply/")
		(sheetfile "fpga-supply.kicad_sch")
		(attr smd)
		(fp_rect
			(start -0.925 0.47)
			(end 0.925 -0.47)
			(stroke
				(width 0.05)
				(type default)
			)
			(fill no)
			(layer "B.CrtYd")
		)
		(fp_line
			(start 0.504 -0.248)
			(end -0.494 -0.248)
			(stroke
				(width 0.15)
				(type solid)
			)
			(layer "B.Fab")
		)
		(fp_line
			(start -0.494 -0.248)
			(end -0.494 0.25)
			(stroke
				(width 0.15)
				(type solid)
			)
			(layer "B.Fab")
		)
		(fp_line
			(start 0.504 0.25)
			(end 0.504 -0.248)
			(stroke
				(width 0.15)
				(type solid)
			)
			(layer "B.Fab")
		)
		(fp_line
			(start -0.494 0.25)
			(end 0.504 0.25)
			(stroke
				(width 0.15)
				(type solid)
			)
			(layer "B.Fab")
		)
		(fp_text user "Author: Antmicro"
			(at -0.939 -3.399 270)
			(layer "B.Fab")
			(effects
				(font
					(size 0.7 0.7)
					(thickness 0.15)
				)
				(justify left bottom mirror)
			)
		)
		(fp_text user "License: Apache-2.0"
			(at -0.939 -5.799 270)
			(layer "B.Fab")
			(effects
				(font
					(size 0.7 0.7)
					(thickness 0.15)
				)
				(justify left bottom mirror)
			)
		)
		(fp_text user "${REFERENCE}"
			(at -0.939 -4.599 270)
			(layer "B.Fab")
			(effects
				(font
					(size 0.7 0.7)
					(thickness 0.15)
				)
				(justify left bottom mirror)
			)
		)
		(pad "1" smd roundrect
			(at -0.48 0 90)
			(size 0.59 0.64)
			(layers "B.Cu" "B.Mask" "B.Paste")
			(roundrect_rratio 0.25)
			(net 417 "GND")
			(pintype "passive")
		)
		(pad "2" smd roundrect
			(at 0.48 0 90)
			(size 0.59 0.64)
			(layers "B.Cu" "B.Mask" "B.Paste")
			(roundrect_rratio 0.25)
			(net 48 "+1V8")
			(pintype "passive")
		)
	)
	(footprint "antmicro-footprints:R_0402_1005Metric"
		(layer "B.Cu")
		(at 225.6 144.345 180)
		(descr "Resistor SMD 0402")
		(tags "resistor SMD 0402")
		(property "Reference" "R146"
			(at -3.8 -0.405 0)
			(layer "B.SilkS")
			(effects
				(font
					(size 0.7 0.7)
					(thickness 0.15)
				)
				(justify left bottom mirror)
			)
		)
		(property "Value" "R_10k_0402"
			(at -1.011843 -1.772047 0)
			(layer "B.Fab")
			(hide yes)
			(effects
				(font
					(size 0.7 0.7)
					(thickness 0.15)
				)
				(justify left bottom mirror)
			)
		)
		(property "Datasheet" "https://www.bourns.com/docs/product-datasheets/cr.pdf"
			(at 0 0 180)
			(layer "F.Fab")
			(hide yes)
			(effects
				(font
					(size 1.27 1.27)
					(thickness 0.15)
				)
			)
		)
		(property "Description" "SMD Chip Resistor, 10 kohm, ± 1%, 62.5 mW, 0402 [1005 Metric], Thick Film, General Purpose"
			(at 0 0 180)
			(layer "F.Fab")
			(hide yes)
			(effects
				(font
					(size 1.27 1.27)
					(thickness 0.15)
				)
			)
		)
		(property "Author" "Antmicro"
			(at 451.2 288.69 0)
			(layer "B.Fab")
			(hide yes)
			(effects
				(font
					(size 1 1)
					(thickness 0.15)
				)
				(justify mirror)
			)
		)
		(property "License" "Apache-2.0"
			(at 451.2 288.69 0)
			(layer "B.Fab")
			(hide yes)
			(effects
				(font
					(size 1 1)
					(thickness 0.15)
				)
				(justify mirror)
			)
		)
		(property "MPN" "CR0402-FX-1002GLF"
			(at 451.2 288.69 0)
			(layer "B.Fab")
			(hide yes)
			(effects
				(font
					(size 1 1)
					(thickness 0.15)
				)
				(justify mirror)
			)
		)
		(property "Manufacturer" "Bourns"
			(at 451.2 288.69 0)
			(layer "B.Fab")
			(hide yes)
			(effects
				(font
					(size 1 1)
					(thickness 0.15)
				)
				(justify mirror)
			)
		)
		(property "Public" ""
			(at 451.2 288.69 0)
			(layer "B.Fab")
			(hide yes)
			(effects
				(font
					(size 1 1)
					(thickness 0.15)
				)
				(justify mirror)
			)
		)
		(property "Tolerance" "1%"
			(at 451.2 288.69 0)
			(layer "B.Fab")
			(hide yes)
			(effects
				(font
					(size 1 1)
					(thickness 0.15)
				)
				(justify mirror)
			)
		)
		(property "Val" "10k"
			(at 451.2 288.69 0)
			(layer "B.Fab")
			(hide yes)
			(effects
				(font
					(size 1 1)
					(thickness 0.15)
				)
				(justify mirror)
			)
		)
		(sheetname "/WiFi_Bluetooth/")
		(sheetfile "wifi_bt.kicad_sch")
		(attr smd)
		(fp_rect
			(start -0.925 0.47)
			(end 0.925 -0.47)
			(stroke
				(width 0.05)
				(type default)
			)
			(fill no)
			(layer "B.CrtYd")
		)
		(fp_rect
			(start -0.5 0.25)
			(end 0.5 -0.25)
			(stroke
				(width 0.15)
				(type solid)
			)
			(fill no)
			(layer "B.Fab")
		)
		(fp_text user "License: Apache-2.0"
			(at -0.95 -5.169 0)
			(layer "B.Fab")
			(effects
				(font
					(size 0.7 0.7)
					(thickness 0.15)
				)
				(justify left bottom mirror)
			)
		)
		(fp_text user "Author: Antmicro"
			(at -0.95 -4.169 0)
			(layer "B.Fab")
			(effects
				(font
					(size 0.7 0.7)
					(thickness 0.15)
				)
				(justify left bottom mirror)
			)
		)
		(fp_text user "${REFERENCE}"
			(at -0.95 -3.168 0)
			(layer "B.Fab")
			(effects
				(font
					(size 0.7 0.7)
					(thickness 0.15)
				)
				(justify left bottom mirror)
			)
		)
		(pad "1" smd roundrect
			(at -0.48 0 180)
			(size 0.59 0.64)
			(layers "B.Cu" "B.Mask" "B.Paste")
			(roundrect_rratio 0.25)
			(net 417 "GND")
			(pintype "passive")
		)
		(pad "2" smd roundrect
			(at 0.48 0 180)
			(size 0.59 0.64)
			(layers "B.Cu" "B.Mask" "B.Paste")
			(roundrect_rratio 0.25)
			(net 422 "/WiFi_Bluetooth/STRAP_1")
			(pintype "passive")
		)
	)
	(footprint "antmicro-footprints:TP_SMD_0.75mm"
		(layer "B.Cu")
		(at 181.8 137.8 180)
		(property "Reference" "TP6"
			(at 0.325 -0.5 0)
			(layer "B.SilkS")
			(hide yes)
			(effects
				(font
					(size 0.7 0.7)
					(thickness 0.15)
				)
				(justify left bottom mirror)
			)
		)
		(property "Value" "TP_0.75mm_SMD"
			(at 0 -1.2 0)
			(layer "B.Fab")
			(hide yes)
			(effects
				(font
					(size 0.7 0.7)
					(thickness 0.15)
				)
				(justify left bottom mirror)
			)
		)
		(property "Description" "SMT test point"
			(at 0 0 0)
			(layer "B.Fab")
			(hide yes)
			(effects
				(font
					(size 1.27 1.27)
					(thickness 0.15)
				)
				(justify mirror)
			)
		)
		(property "MPN" ""
			(at 0 0 0)
			(unlocked yes)
			(layer "B.Fab")
			(hide yes)
			(effects
				(font
					(size 1 1)
					(thickness 0.15)
				)
				(justify mirror)
			)
		)
		(property "Manufacturer" ""
			(at 0 0 0)
			(unlocked yes)
			(layer "B.Fab")
			(hide yes)
			(effects
				(font
					(size 1 1)
					(thickness 0.15)
				)
				(justify mirror)
			)
		)
		(property "Author" "Antmicro"
			(at 0 0 0)
			(unlocked yes)
			(layer "B.Fab")
			(hide yes)
			(effects
				(font
					(size 1 1)
					(thickness 0.15)
				)
				(justify mirror)
			)
		)
		(property "License" "Apache-2.0"
			(at 0 0 0)
			(unlocked yes)
			(layer "B.Fab")
			(hide yes)
			(effects
				(font
					(size 1 1)
					(thickness 0.15)
				)
				(justify mirror)
			)
		)
		(property "Public" "False"
			(at 0 0 0)
			(unlocked yes)
			(layer "B.Fab")
			(hide yes)
			(effects
				(font
					(size 1 1)
					(thickness 0.15)
				)
				(justify mirror)
			)
		)
		(sheetname "/Supply/")
		(sheetfile "supply.kicad_sch")
		(attr exclude_from_pos_files exclude_from_bom)
		(fp_circle
			(center 0 0)
			(end 0.475 0)
			(stroke
				(width 0.05)
				(type default)
			)
			(fill no)
			(layer "B.CrtYd")
		)
		(fp_text user "Author: Antmicro"
			(at -0.4 -3.901 0)
			(layer "B.Fab")
			(effects
				(font
					(size 0.7 0.7)
					(thickness 0.15)
				)
				(justify left bottom mirror)
			)
		)
		(fp_text user "License: Apache-2.0"
			(at -0.4 -5.101 0)
			(layer "B.Fab")
			(effects
				(font
					(size 0.7 0.7)
					(thickness 0.15)
				)
				(justify left bottom mirror)
			)
		)
		(fp_text user "${REFERENCE}"
			(at -0.4 -2.7 0)
			(layer "B.Fab")
			(effects
				(font
					(size 0.7 0.7)
					(thickness 0.15)
				)
				(justify left bottom mirror)
			)
		)
		(pad "1" smd circle
			(at 0 0 180)
			(size 0.75 0.75)
			(layers "B.Cu" "B.Mask")
			(net 632 "Net-(U7-OUT2)")
			(pinfunction "1")
			(pintype "passive")
		)
	)
	(footprint "antmicro-footprints:R_0402_1005Metric"
		(layer "B.Cu")
		(at 177.2 148.9 180)
		(descr "Resistor SMD 0402")
		(tags "resistor SMD 0402")
		(property "Reference" "R4"
			(at -0.95 -1.45 0)
			(layer "B.SilkS")
			(effects
				(font
					(size 0.7 0.7)
					(thickness 0.15)
				)
				(justify left bottom mirror)
			)
		)
		(property "Value" "R_0R_0402"
			(at -1.011843 -1.772047 0)
			(layer "B.Fab")
			(hide yes)
			(effects
				(font
					(size 0.7 0.7)
					(thickness 0.15)
				)
				(justify left bottom mirror)
			)
		)
		(property "Datasheet" "https://industrial.panasonic.com/cdbs/www-data/pdf/RDA0000/AOA0000C301.pdf"
			(at 0 0 180)
			(layer "F.Fab")
			(hide yes)
			(effects
				(font
					(size 1.27 1.27)
					(thickness 0.15)
				)
			)
		)
		(property "Description" "SMD Chip Resistor, Jumper, 0 ohm, 100 mW, 0402 [1005 Metric], Thick Film, General Purpose"
			(at 0 0 180)
			(layer "F.Fab")
			(hide yes)
			(effects
				(font
					(size 1.27 1.27)
					(thickness 0.15)
				)
			)
		)
		(property "Author" "Antmicro"
			(at 354.4 297.8 0)
			(layer "B.Fab")
			(hide yes)
			(effects
				(font
					(size 1 1)
					(thickness 0.15)
				)
				(justify mirror)
			)
		)
		(property "Current" "1A"
			(at 354.4 297.8 0)
			(layer "B.Fab")
			(hide yes)
			(effects
				(font
					(size 1 1)
					(thickness 0.15)
				)
				(justify mirror)
			)
		)
		(property "License" "Apache-2.0"
			(at 354.4 297.8 0)
			(layer "B.Fab")
			(hide yes)
			(effects
				(font
					(size 1 1)
					(thickness 0.15)
				)
				(justify mirror)
			)
		)
		(property "MPN" "ERJ2GE0R00X"
			(at 354.4 297.8 0)
			(layer "B.Fab")
			(hide yes)
			(effects
				(font
					(size 1 1)
					(thickness 0.15)
				)
				(justify mirror)
			)
		)
		(property "Manufacturer" "Panasonic"
			(at 354.4 297.8 0)
			(layer "B.Fab")
			(hide yes)
			(effects
				(font
					(size 1 1)
					(thickness 0.15)
				)
				(justify mirror)
			)
		)
		(property "Public" ""
			(at 354.4 297.8 0)
			(layer "B.Fab")
			(hide yes)
			(effects
				(font
					(size 1 1)
					(thickness 0.15)
				)
				(justify mirror)
			)
		)
		(property "Tolerance" "~"
			(at 354.4 297.8 0)
			(layer "B.Fab")
			(hide yes)
			(effects
				(font
					(size 1 1)
					(thickness 0.15)
				)
				(justify mirror)
			)
		)
		(property "Val" "0R"
			(at 354.4 297.8 0)
			(layer "B.Fab")
			(hide yes)
			(effects
				(font
					(size 1 1)
					(thickness 0.15)
				)
				(justify mirror)
			)
		)
		(sheetname "/Supply/")
		(sheetfile "supply.kicad_sch")
		(attr smd)
		(fp_rect
			(start -0.925 0.47)
			(end 0.925 -0.47)
			(stroke
				(width 0.05)
				(type default)
			)
			(fill no)
			(layer "B.CrtYd")
		)
		(fp_rect
			(start -0.5 0.25)
			(end 0.5 -0.25)
			(stroke
				(width 0.15)
				(type solid)
			)
			(fill no)
			(layer "B.Fab")
		)
		(fp_text user "Author: Antmicro"
			(at -0.95 -4.169 0)
			(layer "B.Fab")
			(effects
				(font
					(size 0.7 0.7)
					(thickness 0.15)
				)
				(justify left bottom mirror)
			)
		)
		(fp_text user "License: Apache-2.0"
			(at -0.95 -5.169 0)
			(layer "B.Fab")
			(effects
				(font
					(size 0.7 0.7)
					(thickness 0.15)
				)
				(justify left bottom mirror)
			)
		)
		(fp_text user "${REFERENCE}"
			(at -0.95 -3.168 0)
			(layer "B.Fab")
			(effects
				(font
					(size 0.7 0.7)
					(thickness 0.15)
				)
				(justify left bottom mirror)
			)
		)
		(pad "1" smd roundrect
			(at -0.48 0 180)
			(size 0.59 0.64)
			(layers "B.Cu" "B.Mask" "B.Paste")
			(roundrect_rratio 0.25)
			(net 417 "GND")
			(pintype "passive")
		)
		(pad "2" smd roundrect
			(at 0.48 0 180)
			(size 0.59 0.64)
			(layers "B.Cu" "B.Mask" "B.Paste")
			(roundrect_rratio 0.25)
			(net 260 "Net-(U6-ADDRSEL)")
			(pintype "passive")
		)
	)
	(footprint "antmicro-footprints:R_0402_1005Metric"
		(layer "B.Cu")
		(at 184.75 118.95 90)
		(descr "Resistor SMD 0402")
		(tags "resistor SMD 0402")
		(property "Reference" "R5"
			(at 2.375 0.4 270)
			(layer "B.SilkS")
			(effects
				(font
					(size 0.7 0.7)
					(thickness 0.15)
				)
				(justify left bottom mirror)
			)
		)
		(property "Value" "R_49k9_0402"
			(at -1.011843 -1.772047 270)
			(layer "B.Fab")
			(hide yes)
			(effects
				(font
					(size 0.7 0.7)
					(thickness 0.15)
				)
				(justify left bottom mirror)
			)
		)
		(property "Datasheet" "https://www.bourns.com/docs/product-datasheets/cr.pdf"
			(at 0 0 90)
			(layer "F.Fab")
			(hide yes)
			(effects
				(font
					(size 1.27 1.27)
					(thickness 0.15)
				)
			)
		)
		(property "Description" "SMD Chip Resistor, 49.9 kohm, ± 1%, 63 mW, 0402 [1005 Metric], Thick Film, General Purpose"
			(at 0 0 90)
			(layer "F.Fab")
			(hide yes)
			(effects
				(font
					(size 1.27 1.27)
					(thickness 0.15)
				)
			)
		)
		(property "Author" "Antmicro"
			(at 303.7 -65.8 0)
			(layer "B.Fab")
			(hide yes)
			(effects
				(font
					(size 1 1)
					(thickness 0.15)
				)
				(justify mirror)
			)
		)
		(property "License" "Apache-2.0"
			(at 303.7 -65.8 0)
			(layer "B.Fab")
			(hide yes)
			(effects
				(font
					(size 1 1)
					(thickness 0.15)
				)
				(justify mirror)
			)
		)
		(property "MPN" "CR0402-FX-4992GLF"
			(at 303.7 -65.8 0)
			(layer "B.Fab")
			(hide yes)
			(effects
				(font
					(size 1 1)
					(thickness 0.15)
				)
				(justify mirror)
			)
		)
		(property "Manufacturer" "Bourns"
			(at 303.7 -65.8 0)
			(layer "B.Fab")
			(hide yes)
			(effects
				(font
					(size 1 1)
					(thickness 0.15)
				)
				(justify mirror)
			)
		)
		(property "Public" ""
			(at 303.7 -65.8 0)
			(layer "B.Fab")
			(hide yes)
			(effects
				(font
					(size 1 1)
					(thickness 0.15)
				)
				(justify mirror)
			)
		)
		(property "Tolerance" "1%"
			(at 303.7 -65.8 0)
			(layer "B.Fab")
			(hide yes)
			(effects
				(font
					(size 1 1)
					(thickness 0.15)
				)
				(justify mirror)
			)
		)
		(property "Val" "49k9"
			(at 303.7 -65.8 0)
			(layer "B.Fab")
			(hide yes)
			(effects
				(font
					(size 1 1)
					(thickness 0.15)
				)
				(justify mirror)
			)
		)
		(sheetname "/Supply/")
		(sheetfile "supply.kicad_sch")
		(attr smd)
		(fp_rect
			(start -0.925 0.47)
			(end 0.925 -0.47)
			(stroke
				(width 0.05)
				(type default)
			)
			(fill no)
			(layer "B.CrtYd")
		)
		(fp_rect
			(start -0.5 0.25)
			(end 0.5 -0.25)
			(stroke
				(width 0.15)
				(type solid)
			)
			(fill no)
			(layer "B.Fab")
		)
		(fp_text user "License: Apache-2.0"
			(at -0.95 -5.169 270)
			(layer "B.Fab")
			(effects
				(font
					(size 0.7 0.7)
					(thickness 0.15)
				)
				(justify left bottom mirror)
			)
		)
		(fp_text user "Author: Antmicro"
			(at -0.95 -4.169 270)
			(layer "B.Fab")
			(effects
				(font
					(size 0.7 0.7)
					(thickness 0.15)
				)
				(justify left bottom mirror)
			)
		)
		(fp_text user "${REFERENCE}"
			(at -0.95 -3.168 270)
			(layer "B.Fab")
			(effects
				(font
					(size 0.7 0.7)
					(thickness 0.15)
				)
				(justify left bottom mirror)
			)
		)
		(pad "1" smd roundrect
			(at -0.48 0 90)
			(size 0.59 0.64)
			(layers "B.Cu" "B.Mask" "B.Paste")
			(roundrect_rratio 0.25)
			(net 212 "GLOBAL_EN")
			(pintype "passive")
		)
		(pad "2" smd roundrect
			(at 0.48 0 90)
			(size 0.59 0.64)
			(layers "B.Cu" "B.Mask" "B.Paste")
			(roundrect_rratio 0.25)
			(net 90 "+5V")
			(pintype "passive")
		)
	)
	(footprint "antmicro-footprints:C_0402_1005Metric"
		(layer "B.Cu")
		(at 175.27 128.8295 -90)
		(descr "Capacitor SMD 0402")
		(tags "capacitor SMD 0402")
		(property "Reference" "C146"
			(at -3.0095 -1.35 270)
			(layer "B.SilkS")
			(effects
				(font
					(size 0.7 0.7)
					(thickness 0.15)
				)
				(justify left bottom mirror)
			)
		)
		(property "Value" "C_1u_0402"
			(at -1.022927 -2.155213 90)
			(layer "B.Fab")
			(hide yes)
			(effects
				(font
					(size 0.7 0.7)
					(thickness 0.15)
				)
				(justify left bottom mirror)
			)
		)
		(property "Datasheet" "https://product.tdk.com/en/search/capacitor/ceramic/mlcc/info?part_no=C1005X6S1A105K050BC"
			(at 0 0 270)
			(layer "F.Fab")
			(hide yes)
			(effects
				(font
					(size 1.27 1.27)
					(thickness 0.15)
				)
			)
		)
		(property "Description" "SMD Multilayer Ceramic Capacitor, 1 µF, 10 V, 0402 [1005 Metric], ± 10%, X6S, C"
			(at 0 0 270)
			(layer "F.Fab")
			(hide yes)
			(effects
				(font
					(size 1.27 1.27)
					(thickness 0.15)
				)
			)
		)
		(property "Author" "Antmicro"
			(at 46.4405 304.0995 0)
			(layer "B.Fab")
			(hide yes)
			(effects
				(font
					(size 1 1)
					(thickness 0.15)
				)
				(justify mirror)
			)
		)
		(property "Dielectric" "X5R"
			(at 46.4405 304.0995 0)
			(layer "B.Fab")
			(hide yes)
			(effects
				(font
					(size 1 1)
					(thickness 0.15)
				)
				(justify mirror)
			)
		)
		(property "License" "Apache-2.0"
			(at 46.4405 304.0995 0)
			(layer "B.Fab")
			(hide yes)
			(effects
				(font
					(size 1 1)
					(thickness 0.15)
				)
				(justify mirror)
			)
		)
		(property "MPN" "C1005X6S1A105K050BC"
			(at 46.4405 304.0995 0)
			(layer "B.Fab")
			(hide yes)
			(effects
				(font
					(size 1 1)
					(thickness 0.15)
				)
				(justify mirror)
			)
		)
		(property "Manufacturer" "TDK"
			(at 46.4405 304.0995 0)
			(layer "B.Fab")
			(hide yes)
			(effects
				(font
					(size 1 1)
					(thickness 0.15)
				)
				(justify mirror)
			)
		)
		(property "Public" ""
			(at 46.4405 304.0995 0)
			(layer "B.Fab")
			(hide yes)
			(effects
				(font
					(size 1 1)
					(thickness 0.15)
				)
				(justify mirror)
			)
		)
		(property "Val" "1u"
			(at 46.4405 304.0995 0)
			(layer "B.Fab")
			(hide yes)
			(effects
				(font
					(size 1 1)
					(thickness 0.15)
				)
				(justify mirror)
			)
		)
		(property "Voltage" "16V"
			(at 46.4405 304.0995 0)
			(layer "B.Fab")
			(hide yes)
			(effects
				(font
					(size 1 1)
					(thickness 0.15)
				)
				(justify mirror)
			)
		)
		(sheetname "/LPDDR4/")
		(sheetfile "lpddr.kicad_sch")
		(attr smd)
		(fp_rect
			(start -0.925 0.47)
			(end 0.925 -0.47)
			(stroke
				(width 0.05)
				(type default)
			)
			(fill no)
			(layer "B.CrtYd")
		)
		(fp_line
			(start -0.494 0.25)
			(end 0.504 0.25)
			(stroke
				(width 0.15)
				(type solid)
			)
			(layer "B.Fab")
		)
		(fp_line
			(start 0.504 0.25)
			(end 0.504 -0.248)
			(stroke
				(width 0.15)
				(type solid)
			)
			(layer "B.Fab")
		)
		(fp_line
			(start -0.494 -0.248)
			(end -0.494 0.25)
			(stroke
				(width 0.15)
				(type solid)
			)
			(layer "B.Fab")
		)
		(fp_line
			(start 0.504 -0.248)
			(end -0.494 -0.248)
			(stroke
				(width 0.15)
				(type solid)
			)
			(layer "B.Fab")
		)
		(fp_text user "${REFERENCE}"
			(at -0.939 -4.599 90)
			(layer "B.Fab")
			(effects
				(font
					(size 0.7 0.7)
					(thickness 0.15)
				)
				(justify left bottom mirror)
			)
		)
		(fp_text user "Author: Antmicro"
			(at -0.939 -3.399 90)
			(layer "B.Fab")
			(effects
				(font
					(size 0.7 0.7)
					(thickness 0.15)
				)
				(justify left bottom mirror)
			)
		)
		(fp_text user "License: Apache-2.0"
			(at -0.939 -5.799 90)
			(layer "B.Fab")
			(effects
				(font
					(size 0.7 0.7)
					(thickness 0.15)
				)
				(justify left bottom mirror)
			)
		)
		(pad "1" smd roundrect
			(at -0.48 0 270)
			(size 0.59 0.64)
			(layers "B.Cu" "B.Mask" "B.Paste")
			(roundrect_rratio 0.25)
			(net 417 "GND")
			(pintype "passive")
		)
		(pad "2" smd roundrect
			(at 0.48 0 270)
			(size 0.59 0.64)
			(layers "B.Cu" "B.Mask" "B.Paste")
			(roundrect_rratio 0.25)
			(net 2 "+1V1")
			(pintype "passive")
		)
	)
	(footprint "antmicro-footprints:R_0402_1005Metric"
		(layer "B.Cu")
		(at 213.061 124.754 180)
		(descr "Resistor SMD 0402")
		(tags "resistor SMD 0402")
		(property "Reference" "R95"
			(at 0.936 -1.046 0)
			(layer "B.SilkS")
			(effects
				(font
					(size 0.7 0.7)
					(thickness 0.15)
				)
				(justify left bottom mirror)
			)
		)
		(property "Value" "R_4k7_0402"
			(at -1.011843 -1.772047 0)
			(layer "B.Fab")
			(hide yes)
			(effects
				(font
					(size 0.7 0.7)
					(thickness 0.15)
				)
				(justify left bottom mirror)
			)
		)
		(property "Datasheet" "https://www.bourns.com/docs/product-datasheets/cr.pdf"
			(at 0 0 180)
			(layer "F.Fab")
			(hide yes)
			(effects
				(font
					(size 1.27 1.27)
					(thickness 0.15)
				)
			)
		)
		(property "Description" "SMD Chip Resistor, 4.7 kohm, ± 1%, 62.5 mW, 0402 [1005 Metric], Thick Film, General Purpose"
			(at 0 0 180)
			(layer "F.Fab")
			(hide yes)
			(effects
				(font
					(size 1.27 1.27)
					(thickness 0.15)
				)
			)
		)
		(property "Author" "Antmicro"
			(at 426.122 249.508 0)
			(layer "B.Fab")
			(hide yes)
			(effects
				(font
					(size 1 1)
					(thickness 0.15)
				)
				(justify mirror)
			)
		)
		(property "License" "Apache-2.0"
			(at 426.122 249.508 0)
			(layer "B.Fab")
			(hide yes)
			(effects
				(font
					(size 1 1)
					(thickness 0.15)
				)
				(justify mirror)
			)
		)
		(property "MPN" "CR0402-FX-4701GLF"
			(at 426.122 249.508 0)
			(layer "B.Fab")
			(hide yes)
			(effects
				(font
					(size 1 1)
					(thickness 0.15)
				)
				(justify mirror)
			)
		)
		(property "Manufacturer" "Bourns"
			(at 426.122 249.508 0)
			(layer "B.Fab")
			(hide yes)
			(effects
				(font
					(size 1 1)
					(thickness 0.15)
				)
				(justify mirror)
			)
		)
		(property "Public" ""
			(at 426.122 249.508 0)
			(layer "B.Fab")
			(hide yes)
			(effects
				(font
					(size 1 1)
					(thickness 0.15)
				)
				(justify mirror)
			)
		)
		(property "Tolerance" "1%"
			(at 426.122 249.508 0)
			(layer "B.Fab")
			(hide yes)
			(effects
				(font
					(size 1 1)
					(thickness 0.15)
				)
				(justify mirror)
			)
		)
		(property "Val" "4k7"
			(at 426.122 249.508 0)
			(layer "B.Fab")
			(hide yes)
			(effects
				(font
					(size 1 1)
					(thickness 0.15)
				)
				(justify mirror)
			)
		)
		(sheetname "/Ethernet/")
		(sheetfile "ethernet.kicad_sch")
		(attr smd)
		(fp_rect
			(start -0.925 0.47)
			(end 0.925 -0.47)
			(stroke
				(width 0.05)
				(type default)
			)
			(fill no)
			(layer "B.CrtYd")
		)
		(fp_rect
			(start -0.5 0.25)
			(end 0.5 -0.25)
			(stroke
				(width 0.15)
				(type solid)
			)
			(fill no)
			(layer "B.Fab")
		)
		(fp_text user "Author: Antmicro"
			(at -0.95 -4.169 0)
			(layer "B.Fab")
			(effects
				(font
					(size 0.7 0.7)
					(thickness 0.15)
				)
				(justify left bottom mirror)
			)
		)
		(fp_text user "${REFERENCE}"
			(at -0.95 -3.168 0)
			(layer "B.Fab")
			(effects
				(font
					(size 0.7 0.7)
					(thickness 0.15)
				)
				(justify left bottom mirror)
			)
		)
		(fp_text user "License: Apache-2.0"
			(at -0.95 -5.169 0)
			(layer "B.Fab")
			(effects
				(font
					(size 0.7 0.7)
					(thickness 0.15)
				)
				(justify left bottom mirror)
			)
		)
		(pad "1" smd roundrect
			(at -0.48 0 180)
			(size 0.59 0.64)
			(layers "B.Cu" "B.Mask" "B.Paste")
			(roundrect_rratio 0.25)
			(net 282 "/Ethernet/ETH_RXCTRL")
			(pintype "passive")
		)
		(pad "2" smd roundrect
			(at 0.48 0 180)
			(size 0.59 0.64)
			(layers "B.Cu" "B.Mask" "B.Paste")
			(roundrect_rratio 0.25)
			(net 50 "+3V3")
			(pintype "passive")
		)
	)
	(footprint "antmicro-footprints:R_0402_1005Metric"
		(layer "B.Cu")
		(at 219.32 155.12 180)
		(descr "Resistor SMD 0402")
		(tags "resistor SMD 0402")
		(property "Reference" "R88"
			(at 0.96 -0.43 0)
			(layer "B.SilkS")
			(effects
				(font
					(size 0.7 0.7)
					(thickness 0.15)
				)
				(justify left bottom mirror)
			)
		)
		(property "Value" "R_50R_0402"
			(at -1.011843 -1.772047 0)
			(layer "B.Fab")
			(hide yes)
			(effects
				(font
					(size 0.7 0.7)
					(thickness 0.15)
				)
				(justify left bottom mirror)
			)
		)
		(property "Datasheet" "https://www.bourns.com/docs/product-datasheets/cr.pdf"
			(at 0 0 180)
			(layer "F.Fab")
			(hide yes)
			(effects
				(font
					(size 1.27 1.27)
					(thickness 0.15)
				)
			)
		)
		(property "Description" "SMD Chip Resistor"
			(at 0 0 180)
			(layer "F.Fab")
			(hide yes)
			(effects
				(font
					(size 1.27 1.27)
					(thickness 0.15)
				)
			)
		)
		(property "Author" "Antmicro"
			(at 438.64 310.24 0)
			(layer "B.Fab")
			(hide yes)
			(effects
				(font
					(size 1 1)
					(thickness 0.15)
				)
				(justify mirror)
			)
		)
		(property "License" "Apache-2.0"
			(at 438.64 310.24 0)
			(layer "B.Fab")
			(hide yes)
			(effects
				(font
					(size 1 1)
					(thickness 0.15)
				)
				(justify mirror)
			)
		)
		(property "MPN" "CR0402-FX-50R0GLF"
			(at 438.64 310.24 0)
			(layer "B.Fab")
			(hide yes)
			(effects
				(font
					(size 1 1)
					(thickness 0.15)
				)
				(justify mirror)
			)
		)
		(property "Manufacturer" "Bourns"
			(at 438.64 310.24 0)
			(layer "B.Fab")
			(hide yes)
			(effects
				(font
					(size 1 1)
					(thickness 0.15)
				)
				(justify mirror)
			)
		)
		(property "Public" ""
			(at 438.64 310.24 0)
			(layer "B.Fab")
			(hide yes)
			(effects
				(font
					(size 1 1)
					(thickness 0.15)
				)
				(justify mirror)
			)
		)
		(property "Tolerance" "1%"
			(at 438.64 310.24 0)
			(layer "B.Fab")
			(hide yes)
			(effects
				(font
					(size 1 1)
					(thickness 0.15)
				)
				(justify mirror)
			)
		)
		(property "Val" "50R"
			(at 438.64 310.24 0)
			(layer "B.Fab")
			(hide yes)
			(effects
				(font
					(size 1 1)
					(thickness 0.15)
				)
				(justify mirror)
			)
		)
		(sheetname "/PCIe/")
		(sheetfile "pcie.kicad_sch")
		(attr smd)
		(fp_rect
			(start -0.925 0.47)
			(end 0.925 -0.47)
			(stroke
				(width 0.05)
				(type default)
			)
			(fill no)
			(layer "B.CrtYd")
		)
		(fp_rect
			(start -0.5 0.25)
			(end 0.5 -0.25)
			(stroke
				(width 0.15)
				(type solid)
			)
			(fill no)
			(layer "B.Fab")
		)
		(fp_text user "Author: Antmicro"
			(at -0.95 -4.169 0)
			(layer "B.Fab")
			(effects
				(font
					(size 0.7 0.7)
					(thickness 0.15)
				)
				(justify left bottom mirror)
			)
		)
		(fp_text user "License: Apache-2.0"
			(at -0.95 -5.169 0)
			(layer "B.Fab")
			(effects
				(font
					(size 0.7 0.7)
					(thickness 0.15)
				)
				(justify left bottom mirror)
			)
		)
		(fp_text user "${REFERENCE}"
			(at -0.95 -3.168 0)
			(layer "B.Fab")
			(effects
				(font
					(size 0.7 0.7)
					(thickness 0.15)
				)
				(justify left bottom mirror)
			)
		)
		(pad "1" smd roundrect
			(at -0.48 0 180)
			(size 0.59 0.64)
			(layers "B.Cu" "B.Mask" "B.Paste")
			(roundrect_rratio 0.25)
			(net 417 "GND")
			(pintype "passive")
		)
		(pad "2" smd roundrect
			(at 0.48 0 180)
			(size 0.59 0.64)
			(layers "B.Cu" "B.Mask" "B.Paste")
			(roundrect_rratio 0.25)
			(net 314 "Net-(U17-CLK1-)")
			(pintype "passive")
		)
	)
	(footprint "antmicro-footprints:R_0402_1005Metric"
		(layer "B.Cu")
		(at 221.35 133.755 -90)
		(descr "Resistor SMD 0402")
		(tags "resistor SMD 0402")
		(property "Reference" "R2"
			(at 0.27 0.525 90)
			(layer "B.SilkS")
			(effects
				(font
					(size 0.7 0.7)
					(thickness 0.15)
				)
				(justify left bottom mirror)
			)
		)
		(property "Value" "R_30k9_0402"
			(at -1.011843 -1.772047 90)
			(layer "B.Fab")
			(hide yes)
			(effects
				(font
					(size 0.7 0.7)
					(thickness 0.15)
				)
				(justify left bottom mirror)
			)
		)
		(property "Datasheet" "https://www.bourns.com/docs/product-datasheets/cr.pdf"
			(at 0 0 270)
			(layer "F.Fab")
			(hide yes)
			(effects
				(font
					(size 1.27 1.27)
					(thickness 0.15)
				)
			)
		)
		(property "Description" "SMD Chip Resistor"
			(at 0 0 270)
			(layer "F.Fab")
			(hide yes)
			(effects
				(font
					(size 1.27 1.27)
					(thickness 0.15)
				)
			)
		)
		(property "Author" "Antmicro"
			(at 87.595 355.105 0)
			(layer "B.Fab")
			(hide yes)
			(effects
				(font
					(size 1 1)
					(thickness 0.15)
				)
				(justify mirror)
			)
		)
		(property "License" "Apache-2.0"
			(at 87.595 355.105 0)
			(layer "B.Fab")
			(hide yes)
			(effects
				(font
					(size 1 1)
					(thickness 0.15)
				)
				(justify mirror)
			)
		)
		(property "MPN" "CR0402-FX-3092GLF"
			(at 87.595 355.105 0)
			(layer "B.Fab")
			(hide yes)
			(effects
				(font
					(size 1 1)
					(thickness 0.15)
				)
				(justify mirror)
			)
		)
		(property "Manufacturer" "Bourns"
			(at 87.595 355.105 0)
			(layer "B.Fab")
			(hide yes)
			(effects
				(font
					(size 1 1)
					(thickness 0.15)
				)
				(justify mirror)
			)
		)
		(property "Public" ""
			(at 87.595 355.105 0)
			(layer "B.Fab")
			(hide yes)
			(effects
				(font
					(size 1 1)
					(thickness 0.15)
				)
				(justify mirror)
			)
		)
		(property "Tolerance" "1%"
			(at 87.595 355.105 0)
			(layer "B.Fab")
			(hide yes)
			(effects
				(font
					(size 1 1)
					(thickness 0.15)
				)
				(justify mirror)
			)
		)
		(property "Val" "30k9"
			(at 87.595 355.105 0)
			(layer "B.Fab")
			(hide yes)
			(effects
				(font
					(size 1 1)
					(thickness 0.15)
				)
				(justify mirror)
			)
		)
		(sheetname "/Supply/")
		(sheetfile "supply.kicad_sch")
		(attr smd)
		(fp_rect
			(start -0.925 0.47)
			(end 0.925 -0.47)
			(stroke
				(width 0.05)
				(type default)
			)
			(fill no)
			(layer "B.CrtYd")
		)
		(fp_rect
			(start -0.5 0.25)
			(end 0.5 -0.25)
			(stroke
				(width 0.15)
				(type solid)
			)
			(fill no)
			(layer "B.Fab")
		)
		(fp_text user "${REFERENCE}"
			(at -0.95 -3.168 90)
			(layer "B.Fab")
			(effects
				(font
					(size 0.7 0.7)
					(thickness 0.15)
				)
				(justify left bottom mirror)
			)
		)
		(fp_text user "License: Apache-2.0"
			(at -0.95 -5.169 90)
			(layer "B.Fab")
			(effects
				(font
					(size 0.7 0.7)
					(thickness 0.15)
				)
				(justify left bottom mirror)
			)
		)
		(fp_text user "Author: Antmicro"
			(at -0.95 -4.169 90)
			(layer "B.Fab")
			(effects
				(font
					(size 0.7 0.7)
					(thickness 0.15)
				)
				(justify left bottom mirror)
			)
		)
		(pad "1" smd roundrect
			(at -0.48 0 270)
			(size 0.59 0.64)
			(layers "B.Cu" "B.Mask" "B.Paste")
			(roundrect_rratio 0.25)
			(net 186 "/Supply/PR")
			(pintype "passive")
		)
		(pad "2" smd roundrect
			(at 0.48 0 270)
			(size 0.59 0.64)
			(layers "B.Cu" "B.Mask" "B.Paste")
			(roundrect_rratio 0.25)
			(net 333 "GPIO_VREF")
			(pintype "passive")
		)
	)
	(footprint "antmicro-footprints:R_0402_1005Metric"
		(layer "B.Cu")
		(at 208.25 135.35 180)
		(descr "Resistor SMD 0402")
		(tags "resistor SMD 0402")
		(property "Reference" "R41"
			(at 0.85 -0.4 0)
			(layer "B.SilkS")
			(effects
				(font
					(size 0.7 0.7)
					(thickness 0.15)
				)
				(justify left bottom mirror)
			)
		)
		(property "Value" "R_4k7_0402"
			(at -1.011843 -1.772047 0)
			(layer "B.Fab")
			(hide yes)
			(effects
				(font
					(size 0.7 0.7)
					(thickness 0.15)
				)
				(justify left bottom mirror)
			)
		)
		(property "Datasheet" "https://www.bourns.com/docs/product-datasheets/cr.pdf"
			(at 0 0 180)
			(layer "F.Fab")
			(hide yes)
			(effects
				(font
					(size 1.27 1.27)
					(thickness 0.15)
				)
			)
		)
		(property "Description" "SMD Chip Resistor, 4.7 kohm, ± 1%, 62.5 mW, 0402 [1005 Metric], Thick Film, General Purpose"
			(at 0 0 180)
			(layer "F.Fab")
			(hide yes)
			(effects
				(font
					(size 1.27 1.27)
					(thickness 0.15)
				)
			)
		)
		(property "Author" "Antmicro"
			(at 416.5 270.7 0)
			(layer "B.Fab")
			(hide yes)
			(effects
				(font
					(size 1 1)
					(thickness 0.15)
				)
				(justify mirror)
			)
		)
		(property "License" "Apache-2.0"
			(at 416.5 270.7 0)
			(layer "B.Fab")
			(hide yes)
			(effects
				(font
					(size 1 1)
					(thickness 0.15)
				)
				(justify mirror)
			)
		)
		(property "MPN" "CR0402-FX-4701GLF"
			(at 416.5 270.7 0)
			(layer "B.Fab")
			(hide yes)
			(effects
				(font
					(size 1 1)
					(thickness 0.15)
				)
				(justify mirror)
			)
		)
		(property "Manufacturer" "Bourns"
			(at 416.5 270.7 0)
			(layer "B.Fab")
			(hide yes)
			(effects
				(font
					(size 1 1)
					(thickness 0.15)
				)
				(justify mirror)
			)
		)
		(property "Public" ""
			(at 416.5 270.7 0)
			(layer "B.Fab")
			(hide yes)
			(effects
				(font
					(size 1 1)
					(thickness 0.15)
				)
				(justify mirror)
			)
		)
		(property "Tolerance" "1%"
			(at 416.5 270.7 0)
			(layer "B.Fab")
			(hide yes)
			(effects
				(font
					(size 1 1)
					(thickness 0.15)
				)
				(justify mirror)
			)
		)
		(property "Val" "4k7"
			(at 416.5 270.7 0)
			(layer "B.Fab")
			(hide yes)
			(effects
				(font
					(size 1 1)
					(thickness 0.15)
				)
				(justify mirror)
			)
		)
		(sheetname "/FPGA Config/")
		(sheetfile "fpga-config.kicad_sch")
		(attr smd)
		(fp_rect
			(start -0.925 0.47)
			(end 0.925 -0.47)
			(stroke
				(width 0.05)
				(type default)
			)
			(fill no)
			(layer "B.CrtYd")
		)
		(fp_rect
			(start -0.5 0.25)
			(end 0.5 -0.25)
			(stroke
				(width 0.15)
				(type solid)
			)
			(fill no)
			(layer "B.Fab")
		)
		(fp_text user "${REFERENCE}"
			(at -0.95 -3.168 0)
			(layer "B.Fab")
			(effects
				(font
					(size 0.7 0.7)
					(thickness 0.15)
				)
				(justify left bottom mirror)
			)
		)
		(fp_text user "License: Apache-2.0"
			(at -0.95 -5.169 0)
			(layer "B.Fab")
			(effects
				(font
					(size 0.7 0.7)
					(thickness 0.15)
				)
				(justify left bottom mirror)
			)
		)
		(fp_text user "Author: Antmicro"
			(at -0.95 -4.169 0)
			(layer "B.Fab")
			(effects
				(font
					(size 0.7 0.7)
					(thickness 0.15)
				)
				(justify left bottom mirror)
			)
		)
		(pad "1" smd roundrect
			(at -0.48 0 180)
			(size 0.59 0.64)
			(layers "B.Cu" "B.Mask" "B.Paste")
			(roundrect_rratio 0.25)
			(net 50 "+3V3")
			(pintype "passive")
		)
		(pad "2" smd roundrect
			(at 0.48 0 180)
			(size 0.59 0.64)
			(layers "B.Cu" "B.Mask" "B.Paste")
			(roundrect_rratio 0.25)
			(net 256 "Net-(U1D-SPI_EN)")
			(pintype "passive")
		)
	)
	(footprint "antmicro-footprints:C_0603_1608Metric"
		(layer "B.Cu")
		(at 190.1 141.101)
		(descr "Capacitor SMD 0603")
		(tags "capacitor 0603")
		(property "Reference" "C66"
			(at -1.503 -0.701 0)
			(layer "B.SilkS")
			(effects
				(font
					(size 0.7 0.7)
					(thickness 0.15)
				)
				(justify right bottom mirror)
			)
		)
		(property "Value" "C_47u_0603"
			(at -1.42757 -1.770288 0)
			(layer "B.Fab")
			(hide yes)
			(effects
				(font
					(size 0.7 0.7)
					(thickness 0.15)
				)
				(justify right bottom mirror)
			)
		)
		(property "Datasheet" "https://www.murata.com/products/productdetail?partno=GRM188R60J476ME15%23"
			(at 0 0 0)
			(layer "F.Fab")
			(hide yes)
			(effects
				(font
					(size 1.27 1.27)
					(thickness 0.15)
				)
			)
		)
		(property "Description" "SMD Multilayer Ceramic Capacitor, 47 µF, 6.3 V, 0603 [1608 Metric], ± 20%, X5R, GRM Series"
			(at 0 0 0)
			(layer "F.Fab")
			(hide yes)
			(effects
				(font
					(size 1.27 1.27)
					(thickness 0.15)
				)
			)
		)
		(property "Author" "Antmicro"
			(at 0 0 0)
			(layer "B.Fab")
			(hide yes)
			(effects
				(font
					(size 1 1)
					(thickness 0.15)
				)
				(justify mirror)
			)
		)
		(property "Capacitance" "47u"
			(at 0 0 0)
			(layer "B.Fab")
			(hide yes)
			(effects
				(font
					(size 1 1)
					(thickness 0.15)
				)
				(justify mirror)
			)
		)
		(property "Dielectric" "X7R"
			(at 0 0 0)
			(layer "B.Fab")
			(hide yes)
			(effects
				(font
					(size 1 1)
					(thickness 0.15)
				)
				(justify mirror)
			)
		)
		(property "License" "Apache-2.0"
			(at 0 0 0)
			(layer "B.Fab")
			(hide yes)
			(effects
				(font
					(size 1 1)
					(thickness 0.15)
				)
				(justify mirror)
			)
		)
		(property "MPN" "GRM188R60J476ME15D"
			(at 0 0 0)
			(layer "B.Fab")
			(hide yes)
			(effects
				(font
					(size 1 1)
					(thickness 0.15)
				)
				(justify mirror)
			)
		)
		(property "Manufacturer" "Murata"
			(at 0 0 0)
			(layer "B.Fab")
			(hide yes)
			(effects
				(font
					(size 1 1)
					(thickness 0.15)
				)
				(justify mirror)
			)
		)
		(property "Public" ""
			(at 0 0 0)
			(layer "B.Fab")
			(hide yes)
			(effects
				(font
					(size 1 1)
					(thickness 0.15)
				)
				(justify mirror)
			)
		)
		(property "Val" "47u"
			(at 0 0 0)
			(layer "B.Fab")
			(hide yes)
			(effects
				(font
					(size 1 1)
					(thickness 0.15)
				)
				(justify mirror)
			)
		)
		(property "Voltage" "50V"
			(at 0 0 0)
			(layer "B.Fab")
			(hide yes)
			(effects
				(font
					(size 1 1)
					(thickness 0.15)
				)
				(justify mirror)
			)
		)
		(sheetname "/FPGA Supply/")
		(sheetfile "fpga-supply.kicad_sch")
		(attr smd)
		(fp_line
			(start -0.15 -0.4)
			(end 0.15 -0.4)
			(stroke
				(width 0.15)
				(type solid)
			)
			(layer "B.SilkS")
		)
		(fp_line
			(start -0.15 0.4)
			(end 0.15 0.4)
			(stroke
				(width 0.15)
				(type solid)
			)
			(layer "B.SilkS")
		)
		(fp_rect
			(start -1.25 0.65)
			(end 1.25 -0.65)
			(stroke
				(width 0.05)
				(type solid)
			)
			(fill no)
			(layer "B.CrtYd")
		)
		(fp_rect
			(start -0.8 0.4)
			(end 0.8 -0.4)
			(stroke
				(width 0.15)
				(type solid)
			)
			(fill no)
			(layer "B.Fab")
		)
		(fp_text user "${REFERENCE}"
			(at -1.682 -3.895 180)
			(layer "B.Fab")
			(effects
				(font
					(size 0.7 0.7)
					(thickness 0.15)
				)
				(justify left bottom mirror)
			)
		)
		(fp_text user "Author: Antmicro"
			(at -1.682 -4.894 180)
			(layer "B.Fab")
			(effects
				(font
					(size 0.7 0.7)
					(thickness 0.15)
				)
				(justify left bottom mirror)
			)
		)
		(fp_text user "License: Apache-2.0"
			(at -1.682 -5.895 180)
			(layer "B.Fab")
			(effects
				(font
					(size 0.7 0.7)
					(thickness 0.15)
				)
				(justify left bottom mirror)
			)
		)
		(pad "1" smd roundrect
			(at -0.7 0)
			(size 0.8 1)
			(layers "B.Cu" "B.Mask" "B.Paste")
			(roundrect_rratio 0.2)
			(net 417 "GND")
			(pintype "passive")
		)
		(pad "2" smd roundrect
			(at 0.7 0)
			(size 0.8 1)
			(layers "B.Cu" "B.Mask" "B.Paste")
			(roundrect_rratio 0.2)
			(net 48 "+1V8")
			(pintype "passive")
		)
	)
	(footprint "antmicro-footprints:R_0402_1005Metric"
		(layer "B.Cu")
		(at 185.188498 148.183898 -90)
		(descr "Resistor SMD 0402")
		(tags "resistor SMD 0402")
		(property "Reference" "R78"
			(at -1.083898 0.488498 90)
			(layer "B.SilkS")
			(effects
				(font
					(size 0.7 0.7)
					(thickness 0.15)
				)
				(justify left bottom mirror)
			)
		)
		(property "Value" "R_0R_0402"
			(at -1.011843 -1.772047 90)
			(layer "B.Fab")
			(hide yes)
			(effects
				(font
					(size 0.7 0.7)
					(thickness 0.15)
				)
				(justify left bottom mirror)
			)
		)
		(property "Datasheet" "https://industrial.panasonic.com/cdbs/www-data/pdf/RDA0000/AOA0000C301.pdf"
			(at 0 0 270)
			(layer "F.Fab")
			(hide yes)
			(effects
				(font
					(size 1.27 1.27)
					(thickness 0.15)
				)
			)
		)
		(property "Description" "SMD Chip Resistor, Jumper, 0 ohm, 100 mW, 0402 [1005 Metric], Thick Film, General Purpose"
			(at 0 0 270)
			(layer "F.Fab")
			(hide yes)
			(effects
				(font
					(size 1.27 1.27)
					(thickness 0.15)
				)
			)
		)
		(property "Author" "Antmicro"
			(at 37.0046 333.372396 0)
			(layer "B.Fab")
			(hide yes)
			(effects
				(font
					(size 1 1)
					(thickness 0.15)
				)
				(justify mirror)
			)
		)
		(property "Current" "1A"
			(at 37.0046 333.372396 0)
			(layer "B.Fab")
			(hide yes)
			(effects
				(font
					(size 1 1)
					(thickness 0.15)
				)
				(justify mirror)
			)
		)
		(property "License" "Apache-2.0"
			(at 37.0046 333.372396 0)
			(layer "B.Fab")
			(hide yes)
			(effects
				(font
					(size 1 1)
					(thickness 0.15)
				)
				(justify mirror)
			)
		)
		(property "MPN" "ERJ2GE0R00X"
			(at 37.0046 333.372396 0)
			(layer "B.Fab")
			(hide yes)
			(effects
				(font
					(size 1 1)
					(thickness 0.15)
				)
				(justify mirror)
			)
		)
		(property "Manufacturer" "Panasonic"
			(at 37.0046 333.372396 0)
			(layer "B.Fab")
			(hide yes)
			(effects
				(font
					(size 1 1)
					(thickness 0.15)
				)
				(justify mirror)
			)
		)
		(property "Public" ""
			(at 37.0046 333.372396 0)
			(layer "B.Fab")
			(hide yes)
			(effects
				(font
					(size 1 1)
					(thickness 0.15)
				)
				(justify mirror)
			)
		)
		(property "Tolerance" "~"
			(at 37.0046 333.372396 0)
			(layer "B.Fab")
			(hide yes)
			(effects
				(font
					(size 1 1)
					(thickness 0.15)
				)
				(justify mirror)
			)
		)
		(property "Val" "0R"
			(at 37.0046 333.372396 0)
			(layer "B.Fab")
			(hide yes)
			(effects
				(font
					(size 1 1)
					(thickness 0.15)
				)
				(justify mirror)
			)
		)
		(sheetname "/Supply/")
		(sheetfile "supply.kicad_sch")
		(attr smd)
		(fp_rect
			(start -0.925 0.47)
			(end 0.925 -0.47)
			(stroke
				(width 0.05)
				(type default)
			)
			(fill no)
			(layer "B.CrtYd")
		)
		(fp_rect
			(start -0.5 0.25)
			(end 0.5 -0.25)
			(stroke
				(width 0.15)
				(type solid)
			)
			(fill no)
			(layer "B.Fab")
		)
		(fp_text user "Author: Antmicro"
			(at -0.95 -4.169 90)
			(layer "B.Fab")
			(effects
				(font
					(size 0.7 0.7)
					(thickness 0.15)
				)
				(justify left bottom mirror)
			)
		)
		(fp_text user "${REFERENCE}"
			(at -0.95 -3.168 90)
			(layer "B.Fab")
			(effects
				(font
					(size 0.7 0.7)
					(thickness 0.15)
				)
				(justify left bottom mirror)
			)
		)
		(fp_text user "License: Apache-2.0"
			(at -0.95 -5.169 90)
			(layer "B.Fab")
			(effects
				(font
					(size 0.7 0.7)
					(thickness 0.15)
				)
				(justify left bottom mirror)
			)
		)
		(pad "1" smd roundrect
			(at -0.48 0 270)
			(size 0.59 0.64)
			(layers "B.Cu" "B.Mask" "B.Paste")
			(roundrect_rratio 0.25)
			(net 633 "Net-(U7-OUT4)")
			(pintype "passive")
		)
		(pad "2" smd roundrect
			(at 0.48 0 270)
			(size 0.59 0.64)
			(layers "B.Cu" "B.Mask" "B.Paste")
			(roundrect_rratio 0.25)
			(net 103 "2V5_CL")
			(pintype "passive")
		)
	)
	(footprint "antmicro-footprints:C_0402_1005Metric"
		(layer "B.Cu")
		(at 210.5516 122.4066)
		(descr "Capacitor SMD 0402")
		(tags "capacitor SMD 0402")
		(property "Reference" "C256"
			(at -3.6016 2.6184 0)
			(layer "B.SilkS")
			(effects
				(font
					(size 0.7 0.7)
					(thickness 0.15)
				)
				(justify right bottom mirror)
			)
		)
		(property "Value" "C_100n_0402"
			(at -1.022927 -2.155213 0)
			(layer "B.Fab")
			(hide yes)
			(effects
				(font
					(size 0.7 0.7)
					(thickness 0.15)
				)
				(justify right bottom mirror)
			)
		)
		(property "Datasheet" "https://www.murata.com/products/productdetail?partno=GRM155R61H104KE14%23"
			(at 0 0 0)
			(layer "F.Fab")
			(hide yes)
			(effects
				(font
					(size 1.27 1.27)
					(thickness 0.15)
				)
			)
		)
		(property "Description" "SMD Multilayer Ceramic Capacitor, 0.1 µF, 50 V, 0402 [1005 Metric], ± 10%, X5R, GRM Series"
			(at 0 0 0)
			(layer "F.Fab")
			(hide yes)
			(effects
				(font
					(size 1.27 1.27)
					(thickness 0.15)
				)
			)
		)
		(property "Author" "Antmicro"
			(at 0 0 0)
			(layer "B.Fab")
			(hide yes)
			(effects
				(font
					(size 1 1)
					(thickness 0.15)
				)
				(justify mirror)
			)
		)
		(property "DNP" "DNP"
			(at 0 0 0)
			(layer "B.Fab")
			(hide yes)
			(effects
				(font
					(size 1 1)
					(thickness 0.15)
				)
				(justify mirror)
			)
		)
		(property "Dielectric" "X5R"
			(at 0 0 0)
			(layer "B.Fab")
			(hide yes)
			(effects
				(font
					(size 1 1)
					(thickness 0.15)
				)
				(justify mirror)
			)
		)
		(property "License" "Apache-2.0"
			(at 0 0 0)
			(layer "B.Fab")
			(hide yes)
			(effects
				(font
					(size 1 1)
					(thickness 0.15)
				)
				(justify mirror)
			)
		)
		(property "MPN" "GRM155R61H104KE14D"
			(at 0 0 0)
			(layer "B.Fab")
			(hide yes)
			(effects
				(font
					(size 1 1)
					(thickness 0.15)
				)
				(justify mirror)
			)
		)
		(property "Manufacturer" "Murata"
			(at 0 0 0)
			(layer "B.Fab")
			(hide yes)
			(effects
				(font
					(size 1 1)
					(thickness 0.15)
				)
				(justify mirror)
			)
		)
		(property "Public" ""
			(at 0 0 0)
			(layer "B.Fab")
			(hide yes)
			(effects
				(font
					(size 1 1)
					(thickness 0.15)
				)
				(justify mirror)
			)
		)
		(property "Val" "100n"
			(at 0 0 0)
			(layer "B.Fab")
			(hide yes)
			(effects
				(font
					(size 1 1)
					(thickness 0.15)
				)
				(justify mirror)
			)
		)
		(property "Voltage" "50V"
			(at 0 0 0)
			(layer "B.Fab")
			(hide yes)
			(effects
				(font
					(size 1 1)
					(thickness 0.15)
				)
				(justify mirror)
			)
		)
		(sheetname "/Ethernet/")
		(sheetfile "ethernet.kicad_sch")
		(attr smd dnp)
		(fp_rect
			(start -0.925 0.47)
			(end 0.925 -0.47)
			(stroke
				(width 0.05)
				(type default)
			)
			(fill no)
			(layer "B.CrtYd")
		)
		(fp_line
			(start -0.494 -0.248)
			(end -0.494 0.25)
			(stroke
				(width 0.15)
				(type solid)
			)
			(layer "B.Fab")
		)
		(fp_line
			(start -0.494 0.25)
			(end 0.504 0.25)
			(stroke
				(width 0.15)
				(type solid)
			)
			(layer "B.Fab")
		)
		(fp_line
			(start 0.504 -0.248)
			(end -0.494 -0.248)
			(stroke
				(width 0.15)
				(type solid)
			)
			(layer "B.Fab")
		)
		(fp_line
			(start 0.504 0.25)
			(end 0.504 -0.248)
			(stroke
				(width 0.15)
				(type solid)
			)
			(layer "B.Fab")
		)
		(fp_text user "Author: Antmicro"
			(at -0.939 -3.399 180)
			(layer "B.Fab")
			(effects
				(font
					(size 0.7 0.7)
					(thickness 0.15)
				)
				(justify left bottom mirror)
			)
		)
		(fp_text user "License: Apache-2.0"
			(at -0.939 -5.799 180)
			(layer "B.Fab")
			(effects
				(font
					(size 0.7 0.7)
					(thickness 0.15)
				)
				(justify left bottom mirror)
			)
		)
		(fp_text user "${REFERENCE}"
			(at -0.939 -4.599 180)
			(layer "B.Fab")
			(effects
				(font
					(size 0.7 0.7)
					(thickness 0.15)
				)
				(justify left bottom mirror)
			)
		)
		(pad "1" smd roundrect
			(at -0.48 0)
			(size 0.59 0.64)
			(layers "B.Cu" "B.Mask" "B.Paste")
			(roundrect_rratio 0.25)
			(net 9 "MSS_REFCLK_N")
			(pintype "passive")
		)
		(pad "2" smd roundrect
			(at 0.48 0)
			(size 0.59 0.64)
			(layers "B.Cu" "B.Mask" "B.Paste")
			(roundrect_rratio 0.25)
			(net 165 "/Ethernet/SGMII_CO_N")
			(pintype "passive")
		)
	)
	(footprint "antmicro-footprints:C_0402_1005Metric"
		(layer "B.Cu")
		(at 198.94 130.85 90)
		(descr "Capacitor SMD 0402")
		(tags "capacitor SMD 0402")
		(property "Reference" "C234"
			(at 5.18 -9.525 90)
			(layer "B.SilkS")
			(effects
				(font
					(size 0.7 0.7)
					(thickness 0.15)
				)
				(justify right bottom mirror)
			)
		)
		(property "Value" "C_100n_0402"
			(at -1.022927 -2.155213 90)
			(layer "B.Fab")
			(hide yes)
			(effects
				(font
					(size 0.7 0.7)
					(thickness 0.15)
				)
				(justify right bottom mirror)
			)
		)
		(property "Datasheet" "https://www.murata.com/products/productdetail?partno=GRM155R61H104KE14%23"
			(at 0 0 90)
			(layer "F.Fab")
			(hide yes)
			(effects
				(font
					(size 1.27 1.27)
					(thickness 0.15)
				)
			)
		)
		(property "Description" "SMD Multilayer Ceramic Capacitor, 0.1 µF, 50 V, 0402 [1005 Metric], ± 10%, X5R, GRM Series"
			(at 0 0 90)
			(layer "F.Fab")
			(hide yes)
			(effects
				(font
					(size 1.27 1.27)
					(thickness 0.15)
				)
			)
		)
		(property "Author" "Antmicro"
			(at 329.79 -68.09 0)
			(layer "B.Fab")
			(hide yes)
			(effects
				(font
					(size 1 1)
					(thickness 0.15)
				)
				(justify mirror)
			)
		)
		(property "Dielectric" "X5R"
			(at 329.79 -68.09 0)
			(layer "B.Fab")
			(hide yes)
			(effects
				(font
					(size 1 1)
					(thickness 0.15)
				)
				(justify mirror)
			)
		)
		(property "License" "Apache-2.0"
			(at 329.79 -68.09 0)
			(layer "B.Fab")
			(hide yes)
			(effects
				(font
					(size 1 1)
					(thickness 0.15)
				)
				(justify mirror)
			)
		)
		(property "MPN" "GRM155R61H104KE14D"
			(at 329.79 -68.09 0)
			(layer "B.Fab")
			(hide yes)
			(effects
				(font
					(size 1 1)
					(thickness 0.15)
				)
				(justify mirror)
			)
		)
		(property "Manufacturer" "Murata"
			(at 329.79 -68.09 0)
			(layer "B.Fab")
			(hide yes)
			(effects
				(font
					(size 1 1)
					(thickness 0.15)
				)
				(justify mirror)
			)
		)
		(property "Public" ""
			(at 329.79 -68.09 0)
			(layer "B.Fab")
			(hide yes)
			(effects
				(font
					(size 1 1)
					(thickness 0.15)
				)
				(justify mirror)
			)
		)
		(property "Val" "100n"
			(at 329.79 -68.09 0)
			(layer "B.Fab")
			(hide yes)
			(effects
				(font
					(size 1 1)
					(thickness 0.15)
				)
				(justify mirror)
			)
		)
		(property "Voltage" "50V"
			(at 329.79 -68.09 0)
			(layer "B.Fab")
			(hide yes)
			(effects
				(font
					(size 1 1)
					(thickness 0.15)
				)
				(justify mirror)
			)
		)
		(sheetname "/FPGA Supply/")
		(sheetfile "fpga-supply.kicad_sch")
		(attr smd)
		(fp_rect
			(start -0.925 0.47)
			(end 0.925 -0.47)
			(stroke
				(width 0.05)
				(type default)
			)
			(fill no)
			(layer "B.CrtYd")
		)
		(fp_line
			(start 0.504 -0.248)
			(end -0.494 -0.248)
			(stroke
				(width 0.15)
				(type solid)
			)
			(layer "B.Fab")
		)
		(fp_line
			(start -0.494 -0.248)
			(end -0.494 0.25)
			(stroke
				(width 0.15)
				(type solid)
			)
			(layer "B.Fab")
		)
		(fp_line
			(start 0.504 0.25)
			(end 0.504 -0.248)
			(stroke
				(width 0.15)
				(type solid)
			)
			(layer "B.Fab")
		)
		(fp_line
			(start -0.494 0.25)
			(end 0.504 0.25)
			(stroke
				(width 0.15)
				(type solid)
			)
			(layer "B.Fab")
		)
		(fp_text user "${REFERENCE}"
			(at -0.939 -4.599 270)
			(layer "B.Fab")
			(effects
				(font
					(size 0.7 0.7)
					(thickness 0.15)
				)
				(justify left bottom mirror)
			)
		)
		(fp_text user "License: Apache-2.0"
			(at -0.939 -5.799 270)
			(layer "B.Fab")
			(effects
				(font
					(size 0.7 0.7)
					(thickness 0.15)
				)
				(justify left bottom mirror)
			)
		)
		(fp_text user "Author: Antmicro"
			(at -0.939 -3.399 270)
			(layer "B.Fab")
			(effects
				(font
					(size 0.7 0.7)
					(thickness 0.15)
				)
				(justify left bottom mirror)
			)
		)
		(pad "1" smd roundrect
			(at -0.48 0 90)
			(size 0.59 0.64)
			(layers "B.Cu" "B.Mask" "B.Paste")
			(roundrect_rratio 0.25)
			(net 417 "GND")
			(pintype "passive")
		)
		(pad "2" smd roundrect
			(at 0.48 0 90)
			(size 0.59 0.64)
			(layers "B.Cu" "B.Mask" "B.Paste")
			(roundrect_rratio 0.25)
			(net 49 "VDDAUX")
			(pintype "passive")
		)
	)
	(footprint "antmicro-footprints:C_0402_1005Metric"
		(layer "B.Cu")
		(at 217.36 117.55 90)
		(descr "Capacitor SMD 0402")
		(tags "capacitor SMD 0402")
		(property "Reference" "C114"
			(at -3.75 0.44 90)
			(layer "B.SilkS")
			(effects
				(font
					(size 0.7 0.7)
					(thickness 0.15)
				)
				(justify right bottom mirror)
			)
		)
		(property "Value" "C_1u_0402"
			(at -1.022927 -2.155213 90)
			(layer "B.Fab")
			(hide yes)
			(effects
				(font
					(size 0.7 0.7)
					(thickness 0.15)
				)
				(justify right bottom mirror)
			)
		)
		(property "Datasheet" "https://product.tdk.com/en/search/capacitor/ceramic/mlcc/info?part_no=C1005X6S1A105K050BC"
			(at 0 0 90)
			(layer "F.Fab")
			(hide yes)
			(effects
				(font
					(size 1.27 1.27)
					(thickness 0.15)
				)
			)
		)
		(property "Description" "SMD Multilayer Ceramic Capacitor, 1 µF, 10 V, 0402 [1005 Metric], ± 10%, X6S, C"
			(at 0 0 90)
			(layer "F.Fab")
			(hide yes)
			(effects
				(font
					(size 1.27 1.27)
					(thickness 0.15)
				)
			)
		)
		(property "Author" "Antmicro"
			(at 334.91 -99.81 0)
			(layer "B.Fab")
			(hide yes)
			(effects
				(font
					(size 1 1)
					(thickness 0.15)
				)
				(justify mirror)
			)
		)
		(property "Dielectric" ""
			(at 334.91 -99.81 0)
			(layer "B.Fab")
			(hide yes)
			(effects
				(font
					(size 1 1)
					(thickness 0.15)
				)
				(justify mirror)
			)
		)
		(property "License" "Apache-2.0"
			(at 334.91 -99.81 0)
			(layer "B.Fab")
			(hide yes)
			(effects
				(font
					(size 1 1)
					(thickness 0.15)
				)
				(justify mirror)
			)
		)
		(property "MPN" "C1005X6S1A105K050BC"
			(at 334.91 -99.81 0)
			(layer "B.Fab")
			(hide yes)
			(effects
				(font
					(size 1 1)
					(thickness 0.15)
				)
				(justify mirror)
			)
		)
		(property "Manufacturer" "TDK"
			(at 334.91 -99.81 0)
			(layer "B.Fab")
			(hide yes)
			(effects
				(font
					(size 1 1)
					(thickness 0.15)
				)
				(justify mirror)
			)
		)
		(property "Public" ""
			(at 334.91 -99.81 0)
			(layer "B.Fab")
			(hide yes)
			(effects
				(font
					(size 1 1)
					(thickness 0.15)
				)
				(justify mirror)
			)
		)
		(property "Val" "1u"
			(at 334.91 -99.81 0)
			(layer "B.Fab")
			(hide yes)
			(effects
				(font
					(size 1 1)
					(thickness 0.15)
				)
				(justify mirror)
			)
		)
		(property "Voltage" ""
			(at 334.91 -99.81 0)
			(layer "B.Fab")
			(hide yes)
			(effects
				(font
					(size 1 1)
					(thickness 0.15)
				)
				(justify mirror)
			)
		)
		(sheetname "/Ethernet/")
		(sheetfile "ethernet.kicad_sch")
		(attr smd)
		(fp_rect
			(start -0.925 0.47)
			(end 0.925 -0.47)
			(stroke
				(width 0.05)
				(type default)
			)
			(fill no)
			(layer "B.CrtYd")
		)
		(fp_line
			(start 0.504 -0.248)
			(end -0.494 -0.248)
			(stroke
				(width 0.15)
				(type solid)
			)
			(layer "B.Fab")
		)
		(fp_line
			(start -0.494 -0.248)
			(end -0.494 0.25)
			(stroke
				(width 0.15)
				(type solid)
			)
			(layer "B.Fab")
		)
		(fp_line
			(start 0.504 0.25)
			(end 0.504 -0.248)
			(stroke
				(width 0.15)
				(type solid)
			)
			(layer "B.Fab")
		)
		(fp_line
			(start -0.494 0.25)
			(end 0.504 0.25)
			(stroke
				(width 0.15)
				(type solid)
			)
			(layer "B.Fab")
		)
		(fp_text user "Author: Antmicro"
			(at -0.939 -3.399 270)
			(layer "B.Fab")
			(effects
				(font
					(size 0.7 0.7)
					(thickness 0.15)
				)
				(justify left bottom mirror)
			)
		)
		(fp_text user "License: Apache-2.0"
			(at -0.939 -5.799 270)
			(layer "B.Fab")
			(effects
				(font
					(size 0.7 0.7)
					(thickness 0.15)
				)
				(justify left bottom mirror)
			)
		)
		(fp_text user "${REFERENCE}"
			(at -0.939 -4.599 270)
			(layer "B.Fab")
			(effects
				(font
					(size 0.7 0.7)
					(thickness 0.15)
				)
				(justify left bottom mirror)
			)
		)
		(pad "1" smd roundrect
			(at -0.48 0 90)
			(size 0.59 0.64)
			(layers "B.Cu" "B.Mask" "B.Paste")
			(roundrect_rratio 0.25)
			(net 417 "GND")
			(pintype "passive")
		)
		(pad "2" smd roundrect
			(at 0.48 0 90)
			(size 0.59 0.64)
			(layers "B.Cu" "B.Mask" "B.Paste")
			(roundrect_rratio 0.25)
			(net 50 "+3V3")
			(pintype "passive")
		)
	)
	(footprint "antmicro-footprints:C_0603_1608Metric"
		(layer "B.Cu")
		(at 201.8 133.9 180)
		(descr "Capacitor SMD 0603")
		(tags "capacitor 0603")
		(property "Reference" "C233"
			(at -1.4 0.7 0)
			(layer "B.SilkS")
			(effects
				(font
					(size 0.7 0.7)
					(thickness 0.15)
				)
				(justify left bottom mirror)
			)
		)
		(property "Value" "C_47u_0603"
			(at -1.42757 -1.770288 0)
			(layer "B.Fab")
			(hide yes)
			(effects
				(font
					(size 0.7 0.7)
					(thickness 0.15)
				)
				(justify left bottom mirror)
			)
		)
		(property "Datasheet" "https://www.murata.com/products/productdetail?partno=GRM188R60J476ME15%23"
			(at 0 0 180)
			(layer "F.Fab")
			(hide yes)
			(effects
				(font
					(size 1.27 1.27)
					(thickness 0.15)
				)
			)
		)
		(property "Description" "SMD Multilayer Ceramic Capacitor, 47 µF, 6.3 V, 0603 [1608 Metric], ± 20%, X5R, GRM Series"
			(at 0 0 180)
			(layer "F.Fab")
			(hide yes)
			(effects
				(font
					(size 1.27 1.27)
					(thickness 0.15)
				)
			)
		)
		(property "Author" "Antmicro"
			(at 403.6 267.8 0)
			(layer "B.Fab")
			(hide yes)
			(effects
				(font
					(size 1 1)
					(thickness 0.15)
				)
				(justify mirror)
			)
		)
		(property "Capacitance" "47u"
			(at 403.6 267.8 0)
			(layer "B.Fab")
			(hide yes)
			(effects
				(font
					(size 1 1)
					(thickness 0.15)
				)
				(justify mirror)
			)
		)
		(property "Dielectric" "X7R"
			(at 403.6 267.8 0)
			(layer "B.Fab")
			(hide yes)
			(effects
				(font
					(size 1 1)
					(thickness 0.15)
				)
				(justify mirror)
			)
		)
		(property "License" "Apache-2.0"
			(at 403.6 267.8 0)
			(layer "B.Fab")
			(hide yes)
			(effects
				(font
					(size 1 1)
					(thickness 0.15)
				)
				(justify mirror)
			)
		)
		(property "MPN" "GRM188R60J476ME15D"
			(at 403.6 267.8 0)
			(layer "B.Fab")
			(hide yes)
			(effects
				(font
					(size 1 1)
					(thickness 0.15)
				)
				(justify mirror)
			)
		)
		(property "Manufacturer" "Murata"
			(at 403.6 267.8 0)
			(layer "B.Fab")
			(hide yes)
			(effects
				(font
					(size 1 1)
					(thickness 0.15)
				)
				(justify mirror)
			)
		)
		(property "Public" ""
			(at 403.6 267.8 0)
			(layer "B.Fab")
			(hide yes)
			(effects
				(font
					(size 1 1)
					(thickness 0.15)
				)
				(justify mirror)
			)
		)
		(property "Val" "47u"
			(at 403.6 267.8 0)
			(layer "B.Fab")
			(hide yes)
			(effects
				(font
					(size 1 1)
					(thickness 0.15)
				)
				(justify mirror)
			)
		)
		(property "Voltage" "50V"
			(at 403.6 267.8 0)
			(layer "B.Fab")
			(hide yes)
			(effects
				(font
					(size 1 1)
					(thickness 0.15)
				)
				(justify mirror)
			)
		)
		(sheetname "/FPGA Supply/")
		(sheetfile "fpga-supply.kicad_sch")
		(attr smd)
		(fp_line
			(start -0.15 0.4)
			(end 0.15 0.4)
			(stroke
				(width 0.15)
				(type solid)
			)
			(layer "B.SilkS")
		)
		(fp_line
			(start -0.15 -0.4)
			(end 0.15 -0.4)
			(stroke
				(width 0.15)
				(type solid)
			)
			(layer "B.SilkS")
		)
		(fp_rect
			(start -1.25 0.65)
			(end 1.25 -0.65)
			(stroke
				(width 0.05)
				(type solid)
			)
			(fill no)
			(layer "B.CrtYd")
		)
		(fp_rect
			(start -0.8 0.4)
			(end 0.8 -0.4)
			(stroke
				(width 0.15)
				(type solid)
			)
			(fill no)
			(layer "B.Fab")
		)
		(fp_text user "License: Apache-2.0"
			(at -1.682 -5.895 0)
			(layer "B.Fab")
			(effects
				(font
					(size 0.7 0.7)
					(thickness 0.15)
				)
				(justify left bottom mirror)
			)
		)
		(fp_text user "${REFERENCE}"
			(at -1.682 -3.895 0)
			(layer "B.Fab")
			(effects
				(font
					(size 0.7 0.7)
					(thickness 0.15)
				)
				(justify left bottom mirror)
			)
		)
		(fp_text user "Author: Antmicro"
			(at -1.682 -4.894 0)
			(layer "B.Fab")
			(effects
				(font
					(size 0.7 0.7)
					(thickness 0.15)
				)
				(justify left bottom mirror)
			)
		)
		(pad "1" smd roundrect
			(at -0.7 0 180)
			(size 0.8 1)
			(layers "B.Cu" "B.Mask" "B.Paste")
			(roundrect_rratio 0.2)
			(net 417 "GND")
			(pintype "passive")
		)
		(pad "2" smd roundrect
			(at 0.7 0 180)
			(size 0.8 1)
			(layers "B.Cu" "B.Mask" "B.Paste")
			(roundrect_rratio 0.2)
			(net 49 "VDDAUX")
			(pintype "passive")
		)
	)
	(footprint "antmicro-footprints:C_0402_1005Metric"
		(layer "B.Cu")
		(at 208.116 145.5 180)
		(descr "Capacitor SMD 0402")
		(tags "capacitor SMD 0402")
		(property "Reference" "C206"
			(at 5.716 18.35 0)
			(layer "B.SilkS")
			(effects
				(font
					(size 0.7 0.7)
					(thickness 0.15)
				)
				(justify left bottom mirror)
			)
		)
		(property "Value" "C_100n_0402"
			(at -1.022927 -2.155213 0)
			(layer "B.Fab")
			(hide yes)
			(effects
				(font
					(size 0.7 0.7)
					(thickness 0.15)
				)
				(justify left bottom mirror)
			)
		)
		(property "Datasheet" "https://www.murata.com/products/productdetail?partno=GRM155R61H104KE14%23"
			(at 0 0 180)
			(layer "F.Fab")
			(hide yes)
			(effects
				(font
					(size 1.27 1.27)
					(thickness 0.15)
				)
			)
		)
		(property "Description" "SMD Multilayer Ceramic Capacitor, 0.1 µF, 50 V, 0402 [1005 Metric], ± 10%, X5R, GRM Series"
			(at 0 0 180)
			(layer "F.Fab")
			(hide yes)
			(effects
				(font
					(size 1.27 1.27)
					(thickness 0.15)
				)
			)
		)
		(property "Author" "Antmicro"
			(at 416.232 291 0)
			(layer "B.Fab")
			(hide yes)
			(effects
				(font
					(size 1 1)
					(thickness 0.15)
				)
				(justify mirror)
			)
		)
		(property "Dielectric" "X5R"
			(at 416.232 291 0)
			(layer "B.Fab")
			(hide yes)
			(effects
				(font
					(size 1 1)
					(thickness 0.15)
				)
				(justify mirror)
			)
		)
		(property "License" "Apache-2.0"
			(at 416.232 291 0)
			(layer "B.Fab")
			(hide yes)
			(effects
				(font
					(size 1 1)
					(thickness 0.15)
				)
				(justify mirror)
			)
		)
		(property "MPN" "GRM155R61H104KE14D"
			(at 416.232 291 0)
			(layer "B.Fab")
			(hide yes)
			(effects
				(font
					(size 1 1)
					(thickness 0.15)
				)
				(justify mirror)
			)
		)
		(property "Manufacturer" "Murata"
			(at 416.232 291 0)
			(layer "B.Fab")
			(hide yes)
			(effects
				(font
					(size 1 1)
					(thickness 0.15)
				)
				(justify mirror)
			)
		)
		(property "Public" ""
			(at 416.232 291 0)
			(layer "B.Fab")
			(hide yes)
			(effects
				(font
					(size 1 1)
					(thickness 0.15)
				)
				(justify mirror)
			)
		)
		(property "Val" "100n"
			(at 416.232 291 0)
			(layer "B.Fab")
			(hide yes)
			(effects
				(font
					(size 1 1)
					(thickness 0.15)
				)
				(justify mirror)
			)
		)
		(property "Voltage" "50V"
			(at 416.232 291 0)
			(layer "B.Fab")
			(hide yes)
			(effects
				(font
					(size 1 1)
					(thickness 0.15)
				)
				(justify mirror)
			)
		)
		(sheetname "/MIPI CrossLink/")
		(sheetfile "crosslink.kicad_sch")
		(attr smd)
		(fp_rect
			(start -0.925 0.47)
			(end 0.925 -0.47)
			(stroke
				(width 0.05)
				(type default)
			)
			(fill no)
			(layer "B.CrtYd")
		)
		(fp_line
			(start 0.504 0.25)
			(end 0.504 -0.248)
			(stroke
				(width 0.15)
				(type solid)
			)
			(layer "B.Fab")
		)
		(fp_line
			(start 0.504 -0.248)
			(end -0.494 -0.248)
			(stroke
				(width 0.15)
				(type solid)
			)
			(layer "B.Fab")
		)
		(fp_line
			(start -0.494 0.25)
			(end 0.504 0.25)
			(stroke
				(width 0.15)
				(type solid)
			)
			(layer "B.Fab")
		)
		(fp_line
			(start -0.494 -0.248)
			(end -0.494 0.25)
			(stroke
				(width 0.15)
				(type solid)
			)
			(layer "B.Fab")
		)
		(fp_text user "License: Apache-2.0"
			(at -0.939 -5.799 0)
			(layer "B.Fab")
			(effects
				(font
					(size 0.7 0.7)
					(thickness 0.15)
				)
				(justify left bottom mirror)
			)
		)
		(fp_text user "${REFERENCE}"
			(at -0.939 -4.599 0)
			(layer "B.Fab")
			(effects
				(font
					(size 0.7 0.7)
					(thickness 0.15)
				)
				(justify left bottom mirror)
			)
		)
		(fp_text user "Author: Antmicro"
			(at -0.939 -3.399 0)
			(layer "B.Fab")
			(effects
				(font
					(size 0.7 0.7)
					(thickness 0.15)
				)
				(justify left bottom mirror)
			)
		)
		(pad "1" smd roundrect
			(at -0.48 0 180)
			(size 0.59 0.64)
			(layers "B.Cu" "B.Mask" "B.Paste")
			(roundrect_rratio 0.25)
			(net 417 "GND")
			(pintype "passive")
		)
		(pad "2" smd roundrect
			(at 0.48 0 180)
			(size 0.59 0.64)
			(layers "B.Cu" "B.Mask" "B.Paste")
			(roundrect_rratio 0.25)
			(net 185 "/MIPI CrossLink/CL_VCCIO1")
			(pintype "passive")
		)
	)
	(footprint "antmicro-footprints:TP_SMD_0.75mm"
		(layer "B.Cu")
		(at 204.9 125.2 180)
		(property "Reference" "TP36"
			(at -1.96 -0.36 180)
			(layer "B.SilkS")
			(hide yes)
			(effects
				(font
					(size 0.65 0.65)
					(thickness 0.15)
				)
				(justify left bottom mirror)
			)
		)
		(property "Value" "TP_0.75mm_SMD"
			(at 0 -1.2 0)
			(layer "B.Fab")
			(hide yes)
			(effects
				(font
					(size 0.7 0.7)
					(thickness 0.15)
				)
				(justify left bottom mirror)
			)
		)
		(property "Description" "SMT test point"
			(at 0 0 0)
			(layer "B.Fab")
			(hide yes)
			(effects
				(font
					(size 1.27 1.27)
					(thickness 0.15)
				)
				(justify mirror)
			)
		)
		(property "MPN" ""
			(at 0 0 0)
			(unlocked yes)
			(layer "B.Fab")
			(hide yes)
			(effects
				(font
					(size 1 1)
					(thickness 0.15)
				)
				(justify mirror)
			)
		)
		(property "Manufacturer" ""
			(at 0 0 0)
			(unlocked yes)
			(layer "B.Fab")
			(hide yes)
			(effects
				(font
					(size 1 1)
					(thickness 0.15)
				)
				(justify mirror)
			)
		)
		(property "Author" "Antmicro"
			(at 0 0 0)
			(unlocked yes)
			(layer "B.Fab")
			(hide yes)
			(effects
				(font
					(size 1 1)
					(thickness 0.15)
				)
				(justify mirror)
			)
		)
		(property "License" "Apache-2.0"
			(at 0 0 0)
			(unlocked yes)
			(layer "B.Fab")
			(hide yes)
			(effects
				(font
					(size 1 1)
					(thickness 0.15)
				)
				(justify mirror)
			)
		)
		(property "Public" "False"
			(at 0 0 0)
			(unlocked yes)
			(layer "B.Fab")
			(hide yes)
			(effects
				(font
					(size 1 1)
					(thickness 0.15)
				)
				(justify mirror)
			)
		)
		(sheetname "/Supply/")
		(sheetfile "supply.kicad_sch")
		(attr exclude_from_pos_files exclude_from_bom)
		(fp_circle
			(center 0 0)
			(end 0.475 0)
			(stroke
				(width 0.05)
				(type default)
			)
			(fill no)
			(layer "B.CrtYd")
		)
		(fp_text user "Author: Antmicro"
			(at -0.4 -3.901 0)
			(layer "B.Fab")
			(effects
				(font
					(size 0.7 0.7)
					(thickness 0.15)
				)
				(justify left bottom mirror)
			)
		)
		(fp_text user "License: Apache-2.0"
			(at -0.4 -5.101 0)
			(layer "B.Fab")
			(effects
				(font
					(size 0.7 0.7)
					(thickness 0.15)
				)
				(justify left bottom mirror)
			)
		)
		(fp_text user "${REFERENCE}"
			(at -0.4 -2.7 0)
			(layer "B.Fab")
			(effects
				(font
					(size 0.7 0.7)
					(thickness 0.15)
				)
				(justify left bottom mirror)
			)
		)
		(pad "1" smd circle
			(at 0 0 180)
			(size 0.75 0.75)
			(layers "B.Cu" "B.Mask")
			(net 100 "/FPGA MSSIO/SUPPLY.SDA")
			(pinfunction "1")
			(pintype "passive")
		)
	)
	(footprint "antmicro-footprints:C_0402_1005Metric"
		(layer "B.Cu")
		(at 213.6925 131.197 90)
		(descr "Capacitor SMD 0402")
		(tags "capacitor SMD 0402")
		(property "Reference" "C72"
			(at 0.737 0.5075 90)
			(layer "B.SilkS")
			(effects
				(font
					(size 0.7 0.7)
					(thickness 0.15)
				)
				(justify right bottom mirror)
			)
		)
		(property "Value" "C_100n_0402"
			(at -1.022927 -2.155213 90)
			(layer "B.Fab")
			(hide yes)
			(effects
				(font
					(size 0.7 0.7)
					(thickness 0.15)
				)
				(justify right bottom mirror)
			)
		)
		(property "Datasheet" "https://www.murata.com/products/productdetail?partno=GRM155R61H104KE14%23"
			(at 0 0 90)
			(layer "F.Fab")
			(hide yes)
			(effects
				(font
					(size 1.27 1.27)
					(thickness 0.15)
				)
			)
		)
		(property "Description" "SMD Multilayer Ceramic Capacitor, 0.1 µF, 50 V, 0402 [1005 Metric], ± 10%, X5R, GRM Series"
			(at 0 0 90)
			(layer "F.Fab")
			(hide yes)
			(effects
				(font
					(size 1.27 1.27)
					(thickness 0.15)
				)
			)
		)
		(property "Author" "Antmicro"
			(at 344.8895 -82.4955 0)
			(layer "B.Fab")
			(hide yes)
			(effects
				(font
					(size 1 1)
					(thickness 0.15)
				)
				(justify mirror)
			)
		)
		(property "Dielectric" "X5R"
			(at 344.8895 -82.4955 0)
			(layer "B.Fab")
			(hide yes)
			(effects
				(font
					(size 1 1)
					(thickness 0.15)
				)
				(justify mirror)
			)
		)
		(property "License" "Apache-2.0"
			(at 344.8895 -82.4955 0)
			(layer "B.Fab")
			(hide yes)
			(effects
				(font
					(size 1 1)
					(thickness 0.15)
				)
				(justify mirror)
			)
		)
		(property "MPN" "GRM155R61H104KE14D"
			(at 344.8895 -82.4955 0)
			(layer "B.Fab")
			(hide yes)
			(effects
				(font
					(size 1 1)
					(thickness 0.15)
				)
				(justify mirror)
			)
		)
		(property "Manufacturer" "Murata"
			(at 344.8895 -82.4955 0)
			(layer "B.Fab")
			(hide yes)
			(effects
				(font
					(size 1 1)
					(thickness 0.15)
				)
				(justify mirror)
			)
		)
		(property "Public" ""
			(at 344.8895 -82.4955 0)
			(layer "B.Fab")
			(hide yes)
			(effects
				(font
					(size 1 1)
					(thickness 0.15)
				)
				(justify mirror)
			)
		)
		(property "Val" "100n"
			(at 344.8895 -82.4955 0)
			(layer "B.Fab")
			(hide yes)
			(effects
				(font
					(size 1 1)
					(thickness 0.15)
				)
				(justify mirror)
			)
		)
		(property "Voltage" "50V"
			(at 344.8895 -82.4955 0)
			(layer "B.Fab")
			(hide yes)
			(effects
				(font
					(size 1 1)
					(thickness 0.15)
				)
				(justify mirror)
			)
		)
		(sheetname "/Memory/")
		(sheetfile "memory.kicad_sch")
		(attr smd)
		(fp_rect
			(start -0.925 0.47)
			(end 0.925 -0.47)
			(stroke
				(width 0.05)
				(type default)
			)
			(fill no)
			(layer "B.CrtYd")
		)
		(fp_line
			(start 0.504 -0.248)
			(end -0.494 -0.248)
			(stroke
				(width 0.15)
				(type solid)
			)
			(layer "B.Fab")
		)
		(fp_line
			(start -0.494 -0.248)
			(end -0.494 0.25)
			(stroke
				(width 0.15)
				(type solid)
			)
			(layer "B.Fab")
		)
		(fp_line
			(start 0.504 0.25)
			(end 0.504 -0.248)
			(stroke
				(width 0.15)
				(type solid)
			)
			(layer "B.Fab")
		)
		(fp_line
			(start -0.494 0.25)
			(end 0.504 0.25)
			(stroke
				(width 0.15)
				(type solid)
			)
			(layer "B.Fab")
		)
		(fp_text user "Author: Antmicro"
			(at -0.939 -3.399 270)
			(layer "B.Fab")
			(effects
				(font
					(size 0.7 0.7)
					(thickness 0.15)
				)
				(justify left bottom mirror)
			)
		)
		(fp_text user "License: Apache-2.0"
			(at -0.939 -5.799 270)
			(layer "B.Fab")
			(effects
				(font
					(size 0.7 0.7)
					(thickness 0.15)
				)
				(justify left bottom mirror)
			)
		)
		(fp_text user "${REFERENCE}"
			(at -0.939 -4.599 270)
			(layer "B.Fab")
			(effects
				(font
					(size 0.7 0.7)
					(thickness 0.15)
				)
				(justify left bottom mirror)
			)
		)
		(pad "1" smd roundrect
			(at -0.48 0 90)
			(size 0.59 0.64)
			(layers "B.Cu" "B.Mask" "B.Paste")
			(roundrect_rratio 0.25)
			(net 417 "GND")
			(pintype "passive")
		)
		(pad "2" smd roundrect
			(at 0.48 0 90)
			(size 0.59 0.64)
			(layers "B.Cu" "B.Mask" "B.Paste")
			(roundrect_rratio 0.25)
			(net 50 "+3V3")
			(pintype "passive")
		)
	)
	(footprint "antmicro-footprints:C_0402_1005Metric"
		(layer "B.Cu")
		(at 181.25 127)
		(descr "Capacitor SMD 0402")
		(tags "capacitor SMD 0402")
		(property "Reference" "C75"
			(at -0.91 1.4 0)
			(layer "B.SilkS")
			(effects
				(font
					(size 0.7 0.7)
					(thickness 0.15)
				)
				(justify right bottom mirror)
			)
		)
		(property "Value" "C_10u_0402"
			(at -1.022927 -2.155213 0)
			(layer "B.Fab")
			(hide yes)
			(effects
				(font
					(size 0.7 0.7)
					(thickness 0.15)
				)
				(justify right bottom mirror)
			)
		)
		(property "Datasheet" "https://www.yageo.com/en/Chart/Download/pdf/CC0402MRX5R5BB106"
			(at 0 0 0)
			(layer "F.Fab")
			(hide yes)
			(effects
				(font
					(size 1.27 1.27)
					(thickness 0.15)
				)
			)
		)
		(property "Description" "SMD Multilayer Ceramic Capacitor, 10 µF, 6.3 V, 0402 [1005 Metric], ± 20%, X5R, CC Series"
			(at 0 0 0)
			(layer "F.Fab")
			(hide yes)
			(effects
				(font
					(size 1.27 1.27)
					(thickness 0.15)
				)
			)
		)
		(property "Author" "Antmicro"
			(at 0 0 0)
			(layer "B.Fab")
			(hide yes)
			(effects
				(font
					(size 1 1)
					(thickness 0.15)
				)
				(justify mirror)
			)
		)
		(property "Dielectric" ""
			(at 0 0 0)
			(layer "B.Fab")
			(hide yes)
			(effects
				(font
					(size 1 1)
					(thickness 0.15)
				)
				(justify mirror)
			)
		)
		(property "License" "Apache-2.0"
			(at 0 0 0)
			(layer "B.Fab")
			(hide yes)
			(effects
				(font
					(size 1 1)
					(thickness 0.15)
				)
				(justify mirror)
			)
		)
		(property "MPN" "CC0402MRX5R5BB106"
			(at 0 0 0)
			(layer "B.Fab")
			(hide yes)
			(effects
				(font
					(size 1 1)
					(thickness 0.15)
				)
				(justify mirror)
			)
		)
		(property "Manufacturer" "YAGEO"
			(at 0 0 0)
			(layer "B.Fab")
			(hide yes)
			(effects
				(font
					(size 1 1)
					(thickness 0.15)
				)
				(justify mirror)
			)
		)
		(property "Public" ""
			(at 0 0 0)
			(layer "B.Fab")
			(hide yes)
			(effects
				(font
					(size 1 1)
					(thickness 0.15)
				)
				(justify mirror)
			)
		)
		(property "Val" "10u"
			(at 0 0 0)
			(layer "B.Fab")
			(hide yes)
			(effects
				(font
					(size 1 1)
					(thickness 0.15)
				)
				(justify mirror)
			)
		)
		(property "Voltage" ""
			(at 0 0 0)
			(layer "B.Fab")
			(hide yes)
			(effects
				(font
					(size 1 1)
					(thickness 0.15)
				)
				(justify mirror)
			)
		)
		(sheetname "/LPDDR4/")
		(sheetfile "lpddr.kicad_sch")
		(attr smd)
		(fp_rect
			(start -0.925 0.47)
			(end 0.925 -0.47)
			(stroke
				(width 0.05)
				(type default)
			)
			(fill no)
			(layer "B.CrtYd")
		)
		(fp_line
			(start -0.494 -0.248)
			(end -0.494 0.25)
			(stroke
				(width 0.15)
				(type solid)
			)
			(layer "B.Fab")
		)
		(fp_line
			(start -0.494 0.25)
			(end 0.504 0.25)
			(stroke
				(width 0.15)
				(type solid)
			)
			(layer "B.Fab")
		)
		(fp_line
			(start 0.504 -0.248)
			(end -0.494 -0.248)
			(stroke
				(width 0.15)
				(type solid)
			)
			(layer "B.Fab")
		)
		(fp_line
			(start 0.504 0.25)
			(end 0.504 -0.248)
			(stroke
				(width 0.15)
				(type solid)
			)
			(layer "B.Fab")
		)
		(fp_text user "${REFERENCE}"
			(at -0.939 -4.599 180)
			(layer "B.Fab")
			(effects
				(font
					(size 0.7 0.7)
					(thickness 0.15)
				)
				(justify left bottom mirror)
			)
		)
		(fp_text user "License: Apache-2.0"
			(at -0.939 -5.799 180)
			(layer "B.Fab")
			(effects
				(font
					(size 0.7 0.7)
					(thickness 0.15)
				)
				(justify left bottom mirror)
			)
		)
		(fp_text user "Author: Antmicro"
			(at -0.939 -3.399 180)
			(layer "B.Fab")
			(effects
				(font
					(size 0.7 0.7)
					(thickness 0.15)
				)
				(justify left bottom mirror)
			)
		)
		(pad "1" smd roundrect
			(at -0.48 0)
			(size 0.59 0.64)
			(layers "B.Cu" "B.Mask" "B.Paste")
			(roundrect_rratio 0.25)
			(net 417 "GND")
			(pintype "passive")
		)
		(pad "2" smd roundrect
			(at 0.48 0)
			(size 0.59 0.64)
			(layers "B.Cu" "B.Mask" "B.Paste")
			(roundrect_rratio 0.25)
			(net 48 "+1V8")
			(pintype "passive")
		)
	)
	(footprint "antmicro-footprints:R_0402_1005Metric"
		(layer "B.Cu")
		(at 224.38 133.275 180)
		(descr "Resistor SMD 0402")
		(tags "resistor SMD 0402")
		(property "Reference" "R45"
			(at -1.52 -1.325 0)
			(layer "B.SilkS")
			(effects
				(font
					(size 0.7 0.7)
					(thickness 0.15)
				)
				(justify left bottom mirror)
			)
		)
		(property "Value" "R_10k_0402"
			(at -1.011843 -1.772047 0)
			(layer "B.Fab")
			(hide yes)
			(effects
				(font
					(size 0.7 0.7)
					(thickness 0.15)
				)
				(justify left bottom mirror)
			)
		)
		(property "Datasheet" "https://www.bourns.com/docs/product-datasheets/cr.pdf"
			(at 0 0 180)
			(layer "F.Fab")
			(hide yes)
			(effects
				(font
					(size 1.27 1.27)
					(thickness 0.15)
				)
			)
		)
		(property "Description" "SMD Chip Resistor, 10 kohm, ± 1%, 62.5 mW, 0402 [1005 Metric], Thick Film, General Purpose"
			(at 0 0 180)
			(layer "F.Fab")
			(hide yes)
			(effects
				(font
					(size 1.27 1.27)
					(thickness 0.15)
				)
			)
		)
		(property "Author" "Antmicro"
			(at 448.76 266.55 0)
			(layer "B.Fab")
			(hide yes)
			(effects
				(font
					(size 1 1)
					(thickness 0.15)
				)
				(justify mirror)
			)
		)
		(property "License" "Apache-2.0"
			(at 448.76 266.55 0)
			(layer "B.Fab")
			(hide yes)
			(effects
				(font
					(size 1 1)
					(thickness 0.15)
				)
				(justify mirror)
			)
		)
		(property "MPN" "CR0402-FX-1002GLF"
			(at 448.76 266.55 0)
			(layer "B.Fab")
			(hide yes)
			(effects
				(font
					(size 1 1)
					(thickness 0.15)
				)
				(justify mirror)
			)
		)
		(property "Manufacturer" "Bourns"
			(at 448.76 266.55 0)
			(layer "B.Fab")
			(hide yes)
			(effects
				(font
					(size 1 1)
					(thickness 0.15)
				)
				(justify mirror)
			)
		)
		(property "Public" ""
			(at 448.76 266.55 0)
			(layer "B.Fab")
			(hide yes)
			(effects
				(font
					(size 1 1)
					(thickness 0.15)
				)
				(justify mirror)
			)
		)
		(property "Tolerance" "1%"
			(at 448.76 266.55 0)
			(layer "B.Fab")
			(hide yes)
			(effects
				(font
					(size 1 1)
					(thickness 0.15)
				)
				(justify mirror)
			)
		)
		(property "Val" "10k"
			(at 448.76 266.55 0)
			(layer "B.Fab")
			(hide yes)
			(effects
				(font
					(size 1 1)
					(thickness 0.15)
				)
				(justify mirror)
			)
		)
		(sheetname "/FPGA Config/")
		(sheetfile "fpga-config.kicad_sch")
		(attr smd)
		(fp_rect
			(start -0.925 0.47)
			(end 0.925 -0.47)
			(stroke
				(width 0.05)
				(type default)
			)
			(fill no)
			(layer "B.CrtYd")
		)
		(fp_rect
			(start -0.5 0.25)
			(end 0.5 -0.25)
			(stroke
				(width 0.15)
				(type solid)
			)
			(fill no)
			(layer "B.Fab")
		)
		(fp_text user "License: Apache-2.0"
			(at -0.95 -5.169 0)
			(layer "B.Fab")
			(effects
				(font
					(size 0.7 0.7)
					(thickness 0.15)
				)
				(justify left bottom mirror)
			)
		)
		(fp_text user "${REFERENCE}"
			(at -0.95 -3.168 0)
			(layer "B.Fab")
			(effects
				(font
					(size 0.7 0.7)
					(thickness 0.15)
				)
				(justify left bottom mirror)
			)
		)
		(fp_text user "Author: Antmicro"
			(at -0.95 -4.169 0)
			(layer "B.Fab")
			(effects
				(font
					(size 0.7 0.7)
					(thickness 0.15)
				)
				(justify left bottom mirror)
			)
		)
		(pad "1" smd roundrect
			(at -0.48 0 180)
			(size 0.59 0.64)
			(layers "B.Cu" "B.Mask" "B.Paste")
			(roundrect_rratio 0.25)
			(net 258 "Net-(U3-W#{slash}DQ2)")
			(pintype "passive")
		)
		(pad "2" smd roundrect
			(at 0.48 0 180)
			(size 0.59 0.64)
			(layers "B.Cu" "B.Mask" "B.Paste")
			(roundrect_rratio 0.25)
			(net 50 "+3V3")
			(pintype "passive")
		)
	)
	(footprint "antmicro-footprints:C_0402_1005Metric"
		(layer "B.Cu")
		(at 217.98 141.56 90)
		(descr "Capacitor SMD 0402")
		(tags "capacitor SMD 0402")
		(property "Reference" "C123"
			(at 1.29 -0.33 180)
			(layer "B.SilkS")
			(effects
				(font
					(size 0.7 0.7)
					(thickness 0.15)
				)
				(justify right bottom mirror)
			)
		)
		(property "Value" "C_100n_0402"
			(at -1.022927 -2.155213 90)
			(layer "B.Fab")
			(hide yes)
			(effects
				(font
					(size 0.7 0.7)
					(thickness 0.15)
				)
				(justify right bottom mirror)
			)
		)
		(property "Datasheet" "https://www.murata.com/products/productdetail?partno=GRM155R61H104KE14%23"
			(at 0 0 90)
			(layer "F.Fab")
			(hide yes)
			(effects
				(font
					(size 1.27 1.27)
					(thickness 0.15)
				)
			)
		)
		(property "Description" "SMD Multilayer Ceramic Capacitor, 0.1 µF, 50 V, 0402 [1005 Metric], ± 10%, X5R, GRM Series"
			(at 0 0 90)
			(layer "F.Fab")
			(hide yes)
			(effects
				(font
					(size 1.27 1.27)
					(thickness 0.15)
				)
			)
		)
		(property "Author" "Antmicro"
			(at 359.54 -76.42 0)
			(layer "B.Fab")
			(hide yes)
			(effects
				(font
					(size 1 1)
					(thickness 0.15)
				)
				(justify mirror)
			)
		)
		(property "Dielectric" "X5R"
			(at 359.54 -76.42 0)
			(layer "B.Fab")
			(hide yes)
			(effects
				(font
					(size 1 1)
					(thickness 0.15)
				)
				(justify mirror)
			)
		)
		(property "License" "Apache-2.0"
			(at 359.54 -76.42 0)
			(layer "B.Fab")
			(hide yes)
			(effects
				(font
					(size 1 1)
					(thickness 0.15)
				)
				(justify mirror)
			)
		)
		(property "MPN" "GRM155R61H104KE14D"
			(at 359.54 -76.42 0)
			(layer "B.Fab")
			(hide yes)
			(effects
				(font
					(size 1 1)
					(thickness 0.15)
				)
				(justify mirror)
			)
		)
		(property "Manufacturer" "Murata"
			(at 359.54 -76.42 0)
			(layer "B.Fab")
			(hide yes)
			(effects
				(font
					(size 1 1)
					(thickness 0.15)
				)
				(justify mirror)
			)
		)
		(property "Public" ""
			(at 359.54 -76.42 0)
			(layer "B.Fab")
			(hide yes)
			(effects
				(font
					(size 1 1)
					(thickness 0.15)
				)
				(justify mirror)
			)
		)
		(property "Val" "100n"
			(at 359.54 -76.42 0)
			(layer "B.Fab")
			(hide yes)
			(effects
				(font
					(size 1 1)
					(thickness 0.15)
				)
				(justify mirror)
			)
		)
		(property "Voltage" "50V"
			(at 359.54 -76.42 0)
			(layer "B.Fab")
			(hide yes)
			(effects
				(font
					(size 1 1)
					(thickness 0.15)
				)
				(justify mirror)
			)
		)
		(sheetname "/FPGA GPIO/")
		(sheetfile "fpga-gpio.kicad_sch")
		(attr smd)
		(fp_rect
			(start -0.925 0.47)
			(end 0.925 -0.47)
			(stroke
				(width 0.05)
				(type default)
			)
			(fill no)
			(layer "B.CrtYd")
		)
		(fp_line
			(start 0.504 -0.248)
			(end -0.494 -0.248)
			(stroke
				(width 0.15)
				(type solid)
			)
			(layer "B.Fab")
		)
		(fp_line
			(start -0.494 -0.248)
			(end -0.494 0.25)
			(stroke
				(width 0.15)
				(type solid)
			)
			(layer "B.Fab")
		)
		(fp_line
			(start 0.504 0.25)
			(end 0.504 -0.248)
			(stroke
				(width 0.15)
				(type solid)
			)
			(layer "B.Fab")
		)
		(fp_line
			(start -0.494 0.25)
			(end 0.504 0.25)
			(stroke
				(width 0.15)
				(type solid)
			)
			(layer "B.Fab")
		)
		(fp_text user "${REFERENCE}"
			(at -0.939 -4.599 270)
			(layer "B.Fab")
			(effects
				(font
					(size 0.7 0.7)
					(thickness 0.15)
				)
				(justify left bottom mirror)
			)
		)
		(fp_text user "License: Apache-2.0"
			(at -0.939 -5.799 270)
			(layer "B.Fab")
			(effects
				(font
					(size 0.7 0.7)
					(thickness 0.15)
				)
				(justify left bottom mirror)
			)
		)
		(fp_text user "Author: Antmicro"
			(at -0.939 -3.399 270)
			(layer "B.Fab")
			(effects
				(font
					(size 0.7 0.7)
					(thickness 0.15)
				)
				(justify left bottom mirror)
			)
		)
		(pad "1" smd roundrect
			(at -0.48 0 90)
			(size 0.59 0.64)
			(layers "B.Cu" "B.Mask" "B.Paste")
			(roundrect_rratio 0.25)
			(net 649 "VDD")
			(pintype "passive")
		)
		(pad "2" smd roundrect
			(at 0.48 0 90)
			(size 0.59 0.64)
			(layers "B.Cu" "B.Mask" "B.Paste")
			(roundrect_rratio 0.25)
			(net 417 "GND")
			(pintype "passive")
		)
	)
	(footprint "antmicro-footprints:C_0402_1005Metric"
		(layer "B.Cu")
		(at 212.66 153 180)
		(descr "Capacitor SMD 0402")
		(tags "capacitor SMD 0402")
		(property "Reference" "C220"
			(at -2 -1.43 0)
			(layer "B.SilkS")
			(effects
				(font
					(size 0.7 0.7)
					(thickness 0.15)
				)
				(justify left bottom mirror)
			)
		)
		(property "Value" "C_100n_0402"
			(at -1.022927 -2.155213 0)
			(layer "B.Fab")
			(hide yes)
			(effects
				(font
					(size 0.7 0.7)
					(thickness 0.15)
				)
				(justify left bottom mirror)
			)
		)
		(property "Datasheet" "https://www.murata.com/products/productdetail?partno=GRM155R61H104KE14%23"
			(at 0 0 180)
			(layer "F.Fab")
			(hide yes)
			(effects
				(font
					(size 1.27 1.27)
					(thickness 0.15)
				)
			)
		)
		(property "Description" "SMD Multilayer Ceramic Capacitor, 0.1 µF, 50 V, 0402 [1005 Metric], ± 10%, X5R, GRM Series"
			(at 0 0 180)
			(layer "F.Fab")
			(hide yes)
			(effects
				(font
					(size 1.27 1.27)
					(thickness 0.15)
				)
			)
		)
		(property "Author" "Antmicro"
			(at 425.32 306 0)
			(layer "B.Fab")
			(hide yes)
			(effects
				(font
					(size 1 1)
					(thickness 0.15)
				)
				(justify mirror)
			)
		)
		(property "Dielectric" "X5R"
			(at 425.32 306 0)
			(layer "B.Fab")
			(hide yes)
			(effects
				(font
					(size 1 1)
					(thickness 0.15)
				)
				(justify mirror)
			)
		)
		(property "License" "Apache-2.0"
			(at 425.32 306 0)
			(layer "B.Fab")
			(hide yes)
			(effects
				(font
					(size 1 1)
					(thickness 0.15)
				)
				(justify mirror)
			)
		)
		(property "MPN" "GRM155R61H104KE14D"
			(at 425.32 306 0)
			(layer "B.Fab")
			(hide yes)
			(effects
				(font
					(size 1 1)
					(thickness 0.15)
				)
				(justify mirror)
			)
		)
		(property "Manufacturer" "Murata"
			(at 425.32 306 0)
			(layer "B.Fab")
			(hide yes)
			(effects
				(font
					(size 1 1)
					(thickness 0.15)
				)
				(justify mirror)
			)
		)
		(property "Public" ""
			(at 425.32 306 0)
			(layer "B.Fab")
			(hide yes)
			(effects
				(font
					(size 1 1)
					(thickness 0.15)
				)
				(justify mirror)
			)
		)
		(property "Val" "100n"
			(at 425.32 306 0)
			(layer "B.Fab")
			(hide yes)
			(effects
				(font
					(size 1 1)
					(thickness 0.15)
				)
				(justify mirror)
			)
		)
		(property "Voltage" "50V"
			(at 425.32 306 0)
			(layer "B.Fab")
			(hide yes)
			(effects
				(font
					(size 1 1)
					(thickness 0.15)
				)
				(justify mirror)
			)
		)
		(sheetname "/USB/")
		(sheetfile "usb.kicad_sch")
		(attr smd)
		(fp_rect
			(start -0.925 0.47)
			(end 0.925 -0.47)
			(stroke
				(width 0.05)
				(type default)
			)
			(fill no)
			(layer "B.CrtYd")
		)
		(fp_line
			(start 0.504 0.25)
			(end 0.504 -0.248)
			(stroke
				(width 0.15)
				(type solid)
			)
			(layer "B.Fab")
		)
		(fp_line
			(start 0.504 -0.248)
			(end -0.494 -0.248)
			(stroke
				(width 0.15)
				(type solid)
			)
			(layer "B.Fab")
		)
		(fp_line
			(start -0.494 0.25)
			(end 0.504 0.25)
			(stroke
				(width 0.15)
				(type solid)
			)
			(layer "B.Fab")
		)
		(fp_line
			(start -0.494 -0.248)
			(end -0.494 0.25)
			(stroke
				(width 0.15)
				(type solid)
			)
			(layer "B.Fab")
		)
		(fp_text user "Author: Antmicro"
			(at -0.939 -3.399 0)
			(layer "B.Fab")
			(effects
				(font
					(size 0.7 0.7)
					(thickness 0.15)
				)
				(justify left bottom mirror)
			)
		)
		(fp_text user "${REFERENCE}"
			(at -0.939 -4.599 0)
			(layer "B.Fab")
			(effects
				(font
					(size 0.7 0.7)
					(thickness 0.15)
				)
				(justify left bottom mirror)
			)
		)
		(fp_text user "License: Apache-2.0"
			(at -0.939 -5.799 0)
			(layer "B.Fab")
			(effects
				(font
					(size 0.7 0.7)
					(thickness 0.15)
				)
				(justify left bottom mirror)
			)
		)
		(pad "1" smd roundrect
			(at -0.48 0 180)
			(size 0.59 0.64)
			(layers "B.Cu" "B.Mask" "B.Paste")
			(roundrect_rratio 0.25)
			(net 417 "GND")
			(pintype "passive")
		)
		(pad "2" smd roundrect
			(at 0.48 0 180)
			(size 0.59 0.64)
			(layers "B.Cu" "B.Mask" "B.Paste")
			(roundrect_rratio 0.25)
			(net 50 "+3V3")
			(pintype "passive")
		)
	)
	(footprint "antmicro-footprints:R_0402_1005Metric"
		(layer "B.Cu")
		(at 199.95 121.7 -90)
		(descr "Resistor SMD 0402")
		(tags "resistor SMD 0402")
		(property "Reference" "R54"
			(at 2.2 0.375 90)
			(layer "B.SilkS")
			(effects
				(font
					(size 0.7 0.7)
					(thickness 0.15)
				)
				(justify left bottom mirror)
			)
		)
		(property "Value" "R_10k_0402"
			(at -1.011843 -1.772047 90)
			(layer "B.Fab")
			(hide yes)
			(effects
				(font
					(size 0.7 0.7)
					(thickness 0.15)
				)
				(justify left bottom mirror)
			)
		)
		(property "Datasheet" "https://www.bourns.com/docs/product-datasheets/cr.pdf"
			(at 0 0 270)
			(layer "F.Fab")
			(hide yes)
			(effects
				(font
					(size 1.27 1.27)
					(thickness 0.15)
				)
			)
		)
		(property "Description" "SMD Chip Resistor, 10 kohm, ± 1%, 62.5 mW, 0402 [1005 Metric], Thick Film, General Purpose"
			(at 0 0 270)
			(layer "F.Fab")
			(hide yes)
			(effects
				(font
					(size 1.27 1.27)
					(thickness 0.15)
				)
			)
		)
		(property "Author" "Antmicro"
			(at 78.25 321.65 0)
			(layer "B.Fab")
			(hide yes)
			(effects
				(font
					(size 1 1)
					(thickness 0.15)
				)
				(justify mirror)
			)
		)
		(property "License" "Apache-2.0"
			(at 78.25 321.65 0)
			(layer "B.Fab")
			(hide yes)
			(effects
				(font
					(size 1 1)
					(thickness 0.15)
				)
				(justify mirror)
			)
		)
		(property "MPN" "CR0402-FX-1002GLF"
			(at 78.25 321.65 0)
			(layer "B.Fab")
			(hide yes)
			(effects
				(font
					(size 1 1)
					(thickness 0.15)
				)
				(justify mirror)
			)
		)
		(property "Manufacturer" "Bourns"
			(at 78.25 321.65 0)
			(layer "B.Fab")
			(hide yes)
			(effects
				(font
					(size 1 1)
					(thickness 0.15)
				)
				(justify mirror)
			)
		)
		(property "Public" ""
			(at 78.25 321.65 0)
			(layer "B.Fab")
			(hide yes)
			(effects
				(font
					(size 1 1)
					(thickness 0.15)
				)
				(justify mirror)
			)
		)
		(property "Tolerance" "1%"
			(at 78.25 321.65 0)
			(layer "B.Fab")
			(hide yes)
			(effects
				(font
					(size 1 1)
					(thickness 0.15)
				)
				(justify mirror)
			)
		)
		(property "Val" "10k"
			(at 78.25 321.65 0)
			(layer "B.Fab")
			(hide yes)
			(effects
				(font
					(size 1 1)
					(thickness 0.15)
				)
				(justify mirror)
			)
		)
		(sheetname "/Memory/")
		(sheetfile "memory.kicad_sch")
		(attr smd)
		(fp_rect
			(start -0.925 0.47)
			(end 0.925 -0.47)
			(stroke
				(width 0.05)
				(type default)
			)
			(fill no)
			(layer "B.CrtYd")
		)
		(fp_rect
			(start -0.5 0.25)
			(end 0.5 -0.25)
			(stroke
				(width 0.15)
				(type solid)
			)
			(fill no)
			(layer "B.Fab")
		)
		(fp_text user "${REFERENCE}"
			(at -0.95 -3.168 90)
			(layer "B.Fab")
			(effects
				(font
					(size 0.7 0.7)
					(thickness 0.15)
				)
				(justify left bottom mirror)
			)
		)
		(fp_text user "Author: Antmicro"
			(at -0.95 -4.169 90)
			(layer "B.Fab")
			(effects
				(font
					(size 0.7 0.7)
					(thickness 0.15)
				)
				(justify left bottom mirror)
			)
		)
		(fp_text user "License: Apache-2.0"
			(at -0.95 -5.169 90)
			(layer "B.Fab")
			(effects
				(font
					(size 0.7 0.7)
					(thickness 0.15)
				)
				(justify left bottom mirror)
			)
		)
		(pad "1" smd roundrect
			(at -0.48 0 270)
			(size 0.59 0.64)
			(layers "B.Cu" "B.Mask" "B.Paste")
			(roundrect_rratio 0.25)
			(net 44 "SD_PWR_ON")
			(pintype "passive")
		)
		(pad "2" smd roundrect
			(at 0.48 0 270)
			(size 0.59 0.64)
			(layers "B.Cu" "B.Mask" "B.Paste")
			(roundrect_rratio 0.25)
			(net 137 "SD_VDD")
			(pintype "passive")
		)
	)
	(footprint "antmicro-footprints:C_0402_1005Metric"
		(layer "B.Cu")
		(at 198.94 134.73 90)
		(descr "Capacitor SMD 0402")
		(tags "capacitor SMD 0402")
		(property "Reference" "C32"
			(at 6.98 -9.565 270)
			(layer "B.SilkS")
			(effects
				(font
					(size 0.7 0.7)
					(thickness 0.15)
				)
				(justify left bottom mirror)
			)
		)
		(property "Value" "C_10n_0402"
			(at -1.022927 -2.155213 270)
			(layer "B.Fab")
			(hide yes)
			(effects
				(font
					(size 0.7 0.7)
					(thickness 0.15)
				)
				(justify left bottom mirror)
			)
		)
		(property "Datasheet" "https://www.murata.com/products/productdetail?partno=GRM155R71H103KA88%23"
			(at 0 0 90)
			(layer "F.Fab")
			(hide yes)
			(effects
				(font
					(size 1.27 1.27)
					(thickness 0.15)
				)
			)
		)
		(property "Description" "SMD Multilayer Ceramic Capacitor, 10000 pF, 50 V, 0402 [1005 Metric], ± 10%, X7R, GRM Series"
			(at 0 0 90)
			(layer "F.Fab")
			(hide yes)
			(effects
				(font
					(size 1.27 1.27)
					(thickness 0.15)
				)
			)
		)
		(property "Author" "Antmicro"
			(at 333.67 -64.21 0)
			(layer "B.Fab")
			(hide yes)
			(effects
				(font
					(size 1 1)
					(thickness 0.15)
				)
				(justify mirror)
			)
		)
		(property "Dielectric" "X7R"
			(at 333.67 -64.21 0)
			(layer "B.Fab")
			(hide yes)
			(effects
				(font
					(size 1 1)
					(thickness 0.15)
				)
				(justify mirror)
			)
		)
		(property "License" "Apache-2.0"
			(at 333.67 -64.21 0)
			(layer "B.Fab")
			(hide yes)
			(effects
				(font
					(size 1 1)
					(thickness 0.15)
				)
				(justify mirror)
			)
		)
		(property "MPN" "GRM155R71H103KA88D"
			(at 333.67 -64.21 0)
			(layer "B.Fab")
			(hide yes)
			(effects
				(font
					(size 1 1)
					(thickness 0.15)
				)
				(justify mirror)
			)
		)
		(property "Manufacturer" "Murata"
			(at 333.67 -64.21 0)
			(layer "B.Fab")
			(hide yes)
			(effects
				(font
					(size 1 1)
					(thickness 0.15)
				)
				(justify mirror)
			)
		)
		(property "Public" ""
			(at 333.67 -64.21 0)
			(layer "B.Fab")
			(hide yes)
			(effects
				(font
					(size 1 1)
					(thickness 0.15)
				)
				(justify mirror)
			)
		)
		(property "Val" "10n"
			(at 333.67 -64.21 0)
			(layer "B.Fab")
			(hide yes)
			(effects
				(font
					(size 1 1)
					(thickness 0.15)
				)
				(justify mirror)
			)
		)
		(property "Voltage" "50V"
			(at 333.67 -64.21 0)
			(layer "B.Fab")
			(hide yes)
			(effects
				(font
					(size 1 1)
					(thickness 0.15)
				)
				(justify mirror)
			)
		)
		(sheetname "/FPGA Supply/")
		(sheetfile "fpga-supply.kicad_sch")
		(attr smd)
		(fp_rect
			(start -0.925 0.47)
			(end 0.925 -0.47)
			(stroke
				(width 0.05)
				(type default)
			)
			(fill no)
			(layer "B.CrtYd")
		)
		(fp_line
			(start 0.504 -0.248)
			(end -0.494 -0.248)
			(stroke
				(width 0.15)
				(type solid)
			)
			(layer "B.Fab")
		)
		(fp_line
			(start -0.494 -0.248)
			(end -0.494 0.25)
			(stroke
				(width 0.15)
				(type solid)
			)
			(layer "B.Fab")
		)
		(fp_line
			(start 0.504 0.25)
			(end 0.504 -0.248)
			(stroke
				(width 0.15)
				(type solid)
			)
			(layer "B.Fab")
		)
		(fp_line
			(start -0.494 0.25)
			(end 0.504 0.25)
			(stroke
				(width 0.15)
				(type solid)
			)
			(layer "B.Fab")
		)
		(fp_text user "${REFERENCE}"
			(at -0.939 -4.599 270)
			(layer "B.Fab")
			(effects
				(font
					(size 0.7 0.7)
					(thickness 0.15)
				)
				(justify left bottom mirror)
			)
		)
		(fp_text user "License: Apache-2.0"
			(at -0.939 -5.799 270)
			(layer "B.Fab")
			(effects
				(font
					(size 0.7 0.7)
					(thickness 0.15)
				)
				(justify left bottom mirror)
			)
		)
		(fp_text user "Author: Antmicro"
			(at -0.939 -3.399 270)
			(layer "B.Fab")
			(effects
				(font
					(size 0.7 0.7)
					(thickness 0.15)
				)
				(justify left bottom mirror)
			)
		)
		(pad "1" smd roundrect
			(at -0.48 0 90)
			(size 0.59 0.64)
			(layers "B.Cu" "B.Mask" "B.Paste")
			(roundrect_rratio 0.25)
			(net 417 "GND")
			(pintype "passive")
		)
		(pad "2" smd roundrect
			(at 0.48 0 90)
			(size 0.59 0.64)
			(layers "B.Cu" "B.Mask" "B.Paste")
			(roundrect_rratio 0.25)
			(net 47 "+1V05")
			(pintype "passive")
		)
	)
	(footprint "antmicro-footprints:C_0402_1005Metric"
		(layer "B.Cu")
		(at 213.381 147.1 180)
		(descr "Capacitor SMD 0402")
		(tags "capacitor SMD 0402")
		(property "Reference" "C223"
			(at -1.219 -2.525 0)
			(layer "B.SilkS")
			(effects
				(font
					(size 0.7 0.7)
					(thickness 0.15)
				)
				(justify left bottom mirror)
			)
		)
		(property "Value" "C_100n_0402"
			(at -1.022927 -2.155213 0)
			(layer "B.Fab")
			(hide yes)
			(effects
				(font
					(size 0.7 0.7)
					(thickness 0.15)
				)
				(justify left bottom mirror)
			)
		)
		(property "Datasheet" "https://www.murata.com/products/productdetail?partno=GRM155R61H104KE14%23"
			(at 0 0 180)
			(layer "F.Fab")
			(hide yes)
			(effects
				(font
					(size 1.27 1.27)
					(thickness 0.15)
				)
			)
		)
		(property "Description" "SMD Multilayer Ceramic Capacitor, 0.1 µF, 50 V, 0402 [1005 Metric], ± 10%, X5R, GRM Series"
			(at 0 0 180)
			(layer "F.Fab")
			(hide yes)
			(effects
				(font
					(size 1.27 1.27)
					(thickness 0.15)
				)
			)
		)
		(property "Author" "Antmicro"
			(at 426.762 294.2 0)
			(layer "B.Fab")
			(hide yes)
			(effects
				(font
					(size 1 1)
					(thickness 0.15)
				)
				(justify mirror)
			)
		)
		(property "Dielectric" "X5R"
			(at 426.762 294.2 0)
			(layer "B.Fab")
			(hide yes)
			(effects
				(font
					(size 1 1)
					(thickness 0.15)
				)
				(justify mirror)
			)
		)
		(property "License" "Apache-2.0"
			(at 426.762 294.2 0)
			(layer "B.Fab")
			(hide yes)
			(effects
				(font
					(size 1 1)
					(thickness 0.15)
				)
				(justify mirror)
			)
		)
		(property "MPN" "GRM155R61H104KE14D"
			(at 426.762 294.2 0)
			(layer "B.Fab")
			(hide yes)
			(effects
				(font
					(size 1 1)
					(thickness 0.15)
				)
				(justify mirror)
			)
		)
		(property "Manufacturer" "Murata"
			(at 426.762 294.2 0)
			(layer "B.Fab")
			(hide yes)
			(effects
				(font
					(size 1 1)
					(thickness 0.15)
				)
				(justify mirror)
			)
		)
		(property "Public" ""
			(at 426.762 294.2 0)
			(layer "B.Fab")
			(hide yes)
			(effects
				(font
					(size 1 1)
					(thickness 0.15)
				)
				(justify mirror)
			)
		)
		(property "Val" "100n"
			(at 426.762 294.2 0)
			(layer "B.Fab")
			(hide yes)
			(effects
				(font
					(size 1 1)
					(thickness 0.15)
				)
				(justify mirror)
			)
		)
		(property "Voltage" "50V"
			(at 426.762 294.2 0)
			(layer "B.Fab")
			(hide yes)
			(effects
				(font
					(size 1 1)
					(thickness 0.15)
				)
				(justify mirror)
			)
		)
		(sheetname "/USB/")
		(sheetfile "usb.kicad_sch")
		(attr smd)
		(fp_rect
			(start -0.925 0.47)
			(end 0.925 -0.47)
			(stroke
				(width 0.05)
				(type default)
			)
			(fill no)
			(layer "B.CrtYd")
		)
		(fp_line
			(start 0.504 0.25)
			(end 0.504 -0.248)
			(stroke
				(width 0.15)
				(type solid)
			)
			(layer "B.Fab")
		)
		(fp_line
			(start 0.504 -0.248)
			(end -0.494 -0.248)
			(stroke
				(width 0.15)
				(type solid)
			)
			(layer "B.Fab")
		)
		(fp_line
			(start -0.494 0.25)
			(end 0.504 0.25)
			(stroke
				(width 0.15)
				(type solid)
			)
			(layer "B.Fab")
		)
		(fp_line
			(start -0.494 -0.248)
			(end -0.494 0.25)
			(stroke
				(width 0.15)
				(type solid)
			)
			(layer "B.Fab")
		)
		(fp_text user "Author: Antmicro"
			(at -0.939 -3.399 0)
			(layer "B.Fab")
			(effects
				(font
					(size 0.7 0.7)
					(thickness 0.15)
				)
				(justify left bottom mirror)
			)
		)
		(fp_text user "${REFERENCE}"
			(at -0.939 -4.599 0)
			(layer "B.Fab")
			(effects
				(font
					(size 0.7 0.7)
					(thickness 0.15)
				)
				(justify left bottom mirror)
			)
		)
		(fp_text user "License: Apache-2.0"
			(at -0.939 -5.799 0)
			(layer "B.Fab")
			(effects
				(font
					(size 0.7 0.7)
					(thickness 0.15)
				)
				(justify left bottom mirror)
			)
		)
		(pad "1" smd roundrect
			(at -0.48 0 180)
			(size 0.59 0.64)
			(layers "B.Cu" "B.Mask" "B.Paste")
			(roundrect_rratio 0.25)
			(net 417 "GND")
			(pintype "passive")
		)
		(pad "2" smd roundrect
			(at 0.48 0 180)
			(size 0.59 0.64)
			(layers "B.Cu" "B.Mask" "B.Paste")
			(roundrect_rratio 0.25)
			(net 50 "+3V3")
			(pintype "passive")
		)
	)
	(footprint "antmicro-footprints:TP_SMD_0.75mm"
		(layer "B.Cu")
		(at 182.9 143.4 180)
		(property "Reference" "TP20"
			(at -1.725 0.375 0)
			(layer "B.SilkS")
			(hide yes)
			(effects
				(font
					(size 0.7 0.7)
					(thickness 0.15)
				)
				(justify left bottom mirror)
			)
		)
		(property "Value" "TP_0.75mm_SMD"
			(at 0 -1.2 0)
			(layer "B.Fab")
			(hide yes)
			(effects
				(font
					(size 0.7 0.7)
					(thickness 0.15)
				)
				(justify left bottom mirror)
			)
		)
		(property "Description" "SMT test point"
			(at 0 0 0)
			(layer "B.Fab")
			(hide yes)
			(effects
				(font
					(size 1.27 1.27)
					(thickness 0.15)
				)
				(justify mirror)
			)
		)
		(property "MPN" ""
			(at 0 0 0)
			(unlocked yes)
			(layer "B.Fab")
			(hide yes)
			(effects
				(font
					(size 1 1)
					(thickness 0.15)
				)
				(justify mirror)
			)
		)
		(property "Manufacturer" ""
			(at 0 0 0)
			(unlocked yes)
			(layer "B.Fab")
			(hide yes)
			(effects
				(font
					(size 1 1)
					(thickness 0.15)
				)
				(justify mirror)
			)
		)
		(property "Author" "Antmicro"
			(at 0 0 0)
			(unlocked yes)
			(layer "B.Fab")
			(hide yes)
			(effects
				(font
					(size 1 1)
					(thickness 0.15)
				)
				(justify mirror)
			)
		)
		(property "License" "Apache-2.0"
			(at 0 0 0)
			(unlocked yes)
			(layer "B.Fab")
			(hide yes)
			(effects
				(font
					(size 1 1)
					(thickness 0.15)
				)
				(justify mirror)
			)
		)
		(property "Public" "False"
			(at 0 0 0)
			(unlocked yes)
			(layer "B.Fab")
			(hide yes)
			(effects
				(font
					(size 1 1)
					(thickness 0.15)
				)
				(justify mirror)
			)
		)
		(sheetname "/Supply/")
		(sheetfile "supply.kicad_sch")
		(attr exclude_from_pos_files exclude_from_bom)
		(fp_circle
			(center 0 0)
			(end 0.475 0)
			(stroke
				(width 0.05)
				(type default)
			)
			(fill no)
			(layer "B.CrtYd")
		)
		(fp_text user "Author: Antmicro"
			(at -0.4 -3.901 0)
			(layer "B.Fab")
			(effects
				(font
					(size 0.7 0.7)
					(thickness 0.15)
				)
				(justify left bottom mirror)
			)
		)
		(fp_text user "License: Apache-2.0"
			(at -0.4 -5.101 0)
			(layer "B.Fab")
			(effects
				(font
					(size 0.7 0.7)
					(thickness 0.15)
				)
				(justify left bottom mirror)
			)
		)
		(fp_text user "${REFERENCE}"
			(at -0.4 -2.7 0)
			(layer "B.Fab")
			(effects
				(font
					(size 0.7 0.7)
					(thickness 0.15)
				)
				(justify left bottom mirror)
			)
		)
		(pad "1" smd circle
			(at 0 0 180)
			(size 0.75 0.75)
			(layers "B.Cu" "B.Mask")
			(net 409 "/Supply/SENSE4_P")
			(pinfunction "1")
			(pintype "passive")
		)
	)
	(footprint "antmicro-footprints:C_0402_1005Metric"
		(layer "B.Cu")
		(at 222.43 153.74)
		(descr "Capacitor SMD 0402")
		(tags "capacitor SMD 0402")
		(property "Reference" "C12"
			(at 0.94 1.7 0)
			(layer "B.SilkS")
			(effects
				(font
					(size 0.7 0.7)
					(thickness 0.15)
				)
				(justify right bottom mirror)
			)
		)
		(property "Value" "C_100n_0402"
			(at -1.022927 -2.155213 0)
			(layer "B.Fab")
			(hide yes)
			(effects
				(font
					(size 0.7 0.7)
					(thickness 0.15)
				)
				(justify right bottom mirror)
			)
		)
		(property "Datasheet" "https://www.murata.com/products/productdetail?partno=GRM155R61H104KE14%23"
			(at 0 0 0)
			(layer "F.Fab")
			(hide yes)
			(effects
				(font
					(size 1.27 1.27)
					(thickness 0.15)
				)
			)
		)
		(property "Description" "SMD Multilayer Ceramic Capacitor, 0.1 µF, 50 V, 0402 [1005 Metric], ± 10%, X5R, GRM Series"
			(at 0 0 0)
			(layer "F.Fab")
			(hide yes)
			(effects
				(font
					(size 1.27 1.27)
					(thickness 0.15)
				)
			)
		)
		(property "Author" "Antmicro"
			(at 0 0 0)
			(layer "B.Fab")
			(hide yes)
			(effects
				(font
					(size 1 1)
					(thickness 0.15)
				)
				(justify mirror)
			)
		)
		(property "Dielectric" "X5R"
			(at 0 0 0)
			(layer "B.Fab")
			(hide yes)
			(effects
				(font
					(size 1 1)
					(thickness 0.15)
				)
				(justify mirror)
			)
		)
		(property "License" "Apache-2.0"
			(at 0 0 0)
			(layer "B.Fab")
			(hide yes)
			(effects
				(font
					(size 1 1)
					(thickness 0.15)
				)
				(justify mirror)
			)
		)
		(property "MPN" "GRM155R61H104KE14D"
			(at 0 0 0)
			(layer "B.Fab")
			(hide yes)
			(effects
				(font
					(size 1 1)
					(thickness 0.15)
				)
				(justify mirror)
			)
		)
		(property "Manufacturer" "Murata"
			(at 0 0 0)
			(layer "B.Fab")
			(hide yes)
			(effects
				(font
					(size 1 1)
					(thickness 0.15)
				)
				(justify mirror)
			)
		)
		(property "Public" ""
			(at 0 0 0)
			(layer "B.Fab")
			(hide yes)
			(effects
				(font
					(size 1 1)
					(thickness 0.15)
				)
				(justify mirror)
			)
		)
		(property "Val" "100n"
			(at 0 0 0)
			(layer "B.Fab")
			(hide yes)
			(effects
				(font
					(size 1 1)
					(thickness 0.15)
				)
				(justify mirror)
			)
		)
		(property "Voltage" "50V"
			(at 0 0 0)
			(layer "B.Fab")
			(hide yes)
			(effects
				(font
					(size 1 1)
					(thickness 0.15)
				)
				(justify mirror)
			)
		)
		(sheetname "/PCIe/")
		(sheetfile "pcie.kicad_sch")
		(attr smd)
		(fp_rect
			(start -0.925 0.47)
			(end 0.925 -0.47)
			(stroke
				(width 0.05)
				(type default)
			)
			(fill no)
			(layer "B.CrtYd")
		)
		(fp_line
			(start -0.494 -0.248)
			(end -0.494 0.25)
			(stroke
				(width 0.15)
				(type solid)
			)
			(layer "B.Fab")
		)
		(fp_line
			(start -0.494 0.25)
			(end 0.504 0.25)
			(stroke
				(width 0.15)
				(type solid)
			)
			(layer "B.Fab")
		)
		(fp_line
			(start 0.504 -0.248)
			(end -0.494 -0.248)
			(stroke
				(width 0.15)
				(type solid)
			)
			(layer "B.Fab")
		)
		(fp_line
			(start 0.504 0.25)
			(end 0.504 -0.248)
			(stroke
				(width 0.15)
				(type solid)
			)
			(layer "B.Fab")
		)
		(fp_text user "License: Apache-2.0"
			(at -0.939 -5.799 180)
			(layer "B.Fab")
			(effects
				(font
					(size 0.7 0.7)
					(thickness 0.15)
				)
				(justify left bottom mirror)
			)
		)
		(fp_text user "${REFERENCE}"
			(at -0.939 -4.599 180)
			(layer "B.Fab")
			(effects
				(font
					(size 0.7 0.7)
					(thickness 0.15)
				)
				(justify left bottom mirror)
			)
		)
		(fp_text user "Author: Antmicro"
			(at -0.939 -3.399 180)
			(layer "B.Fab")
			(effects
				(font
					(size 0.7 0.7)
					(thickness 0.15)
				)
				(justify left bottom mirror)
			)
		)
		(pad "1" smd roundrect
			(at -0.48 0)
			(size 0.59 0.64)
			(layers "B.Cu" "B.Mask" "B.Paste")
			(roundrect_rratio 0.25)
			(net 417 "GND")
			(pintype "passive")
		)
		(pad "2" smd roundrect
			(at 0.48 0)
			(size 0.59 0.64)
			(layers "B.Cu" "B.Mask" "B.Paste")
			(roundrect_rratio 0.25)
			(net 418 "+2V5")
			(pintype "passive")
		)
	)
	(footprint "antmicro-footprints:R_0402_1005Metric"
		(layer "B.Cu")
		(at 178.51 139.27 90)
		(descr "Resistor SMD 0402")
		(tags "resistor SMD 0402")
		(property "Reference" "R93"
			(at -10.755 10.64 90)
			(layer "B.SilkS")
			(effects
				(font
					(size 0.7 0.7)
					(thickness 0.15)
				)
				(justify right bottom mirror)
			)
		)
		(property "Value" "R_0R_0402"
			(at -1.011843 -1.772046 90)
			(layer "B.Fab")
			(hide yes)
			(effects
				(font
					(size 0.7 0.7)
					(thickness 0.15)
				)
				(justify right bottom mirror)
			)
		)
		(property "Datasheet" "https://industrial.panasonic.com/cdbs/www-data/pdf/RDA0000/AOA0000C301.pdf"
			(at 0 0 90)
			(layer "F.Fab")
			(hide yes)
			(effects
				(font
					(size 1.27 1.27)
					(thickness 0.15)
				)
			)
		)
		(property "Description" "SMD Chip Resistor, Jumper, 0 ohm, 100 mW, 0402 [1005 Metric], Thick Film, General Purpose"
			(at 0 0 90)
			(layer "F.Fab")
			(hide yes)
			(effects
				(font
					(size 1.27 1.27)
					(thickness 0.15)
				)
			)
		)
		(property "Author" "Antmicro"
			(at 317.78 -39.24 0)
			(layer "B.Fab")
			(hide yes)
			(effects
				(font
					(size 1 1)
					(thickness 0.15)
				)
				(justify mirror)
			)
		)
		(property "Current" "1A"
			(at 317.78 -39.24 0)
			(layer "B.Fab")
			(hide yes)
			(effects
				(font
					(size 1 1)
					(thickness 0.15)
				)
				(justify mirror)
			)
		)
		(property "DNP" "DNP"
			(at 317.78 -39.24 0)
			(layer "B.Fab")
			(hide yes)
			(effects
				(font
					(size 1 1)
					(thickness 0.15)
				)
				(justify mirror)
			)
		)
		(property "License" "Apache-2.0"
			(at 317.78 -39.24 0)
			(layer "B.Fab")
			(hide yes)
			(effects
				(font
					(size 1 1)
					(thickness 0.15)
				)
				(justify mirror)
			)
		)
		(property "MPN" "ERJ2GE0R00X"
			(at 317.78 -39.24 0)
			(layer "B.Fab")
			(hide yes)
			(effects
				(font
					(size 1 1)
					(thickness 0.15)
				)
				(justify mirror)
			)
		)
		(property "Manufacturer" "Panasonic"
			(at 317.78 -39.24 0)
			(layer "B.Fab")
			(hide yes)
			(effects
				(font
					(size 1 1)
					(thickness 0.15)
				)
				(justify mirror)
			)
		)
		(property "Public" ""
			(at 317.78 -39.24 0)
			(layer "B.Fab")
			(hide yes)
			(effects
				(font
					(size 1 1)
					(thickness 0.15)
				)
				(justify mirror)
			)
		)
		(property "Tolerance" "~"
			(at 317.78 -39.24 0)
			(layer "B.Fab")
			(hide yes)
			(effects
				(font
					(size 1 1)
					(thickness 0.15)
				)
				(justify mirror)
			)
		)
		(property "Val" "0R"
			(at 317.78 -39.24 0)
			(layer "B.Fab")
			(hide yes)
			(effects
				(font
					(size 1 1)
					(thickness 0.15)
				)
				(justify mirror)
			)
		)
		(sheetname "/Supply/")
		(sheetfile "supply.kicad_sch")
		(attr smd)
		(fp_rect
			(start -0.925 0.47)
			(end 0.925 -0.47)
			(stroke
				(width 0.05)
				(type default)
			)
			(fill no)
			(layer "B.CrtYd")
		)
		(fp_rect
			(start -0.5 0.25)
			(end 0.5 -0.25)
			(stroke
				(width 0.15)
				(type solid)
			)
			(fill no)
			(layer "B.Fab")
		)
		(fp_text user "License: Apache-2.0"
			(at -0.95 -5.169 270)
			(layer "B.Fab")
			(effects
				(font
					(size 0.7 0.7)
					(thickness 0.15)
				)
				(justify left bottom mirror)
			)
		)
		(fp_text user "Author: Antmicro"
			(at -0.95 -4.169 270)
			(layer "B.Fab")
			(effects
				(font
					(size 0.7 0.7)
					(thickness 0.15)
				)
				(justify left bottom mirror)
			)
		)
		(fp_text user "${REFERENCE}"
			(at -0.95 -3.168 270)
			(layer "B.Fab")
			(effects
				(font
					(size 0.7 0.7)
					(thickness 0.15)
				)
				(justify left bottom mirror)
			)
		)
		(pad "1" smd roundrect
			(at -0.48 0 90)
			(size 0.59 0.64)
			(layers "B.Cu" "B.Mask" "B.Paste")
			(roundrect_rratio 0.25)
			(net 209 "/Supply/SENSE1_P")
			(pintype "passive")
		)
		(pad "2" smd roundrect
			(at 0.48 0 90)
			(size 0.59 0.64)
			(layers "B.Cu" "B.Mask" "B.Paste")
			(roundrect_rratio 0.25)
			(net 576 "Net-(U6-SENSE1+)")
			(pintype "passive")
		)
	)
	(footprint "antmicro-footprints:C_0402_1005Metric"
		(layer "B.Cu")
		(at 201.704 138.09 180)
		(descr "Capacitor SMD 0402")
		(tags "capacitor SMD 0402")
		(property "Reference" "C8"
			(at -0.956 -1.44 0)
			(layer "B.SilkS")
			(effects
				(font
					(size 0.7 0.7)
					(thickness 0.15)
				)
				(justify left bottom mirror)
			)
		)
		(property "Value" "C_100n_0402"
			(at -1.022927 -2.155213 0)
			(layer "B.Fab")
			(hide yes)
			(effects
				(font
					(size 0.7 0.7)
					(thickness 0.15)
				)
				(justify left bottom mirror)
			)
		)
		(property "Datasheet" "https://www.murata.com/products/productdetail?partno=GRM155R61H104KE14%23"
			(at 0 0 180)
			(layer "F.Fab")
			(hide yes)
			(effects
				(font
					(size 1.27 1.27)
					(thickness 0.15)
				)
			)
		)
		(property "Description" "SMD Multilayer Ceramic Capacitor, 0.1 µF, 50 V, 0402 [1005 Metric], ± 10%, X5R, GRM Series"
			(at 0 0 180)
			(layer "F.Fab")
			(hide yes)
			(effects
				(font
					(size 1.27 1.27)
					(thickness 0.15)
				)
			)
		)
		(property "Author" "Antmicro"
			(at 403.408 276.18 0)
			(layer "B.Fab")
			(hide yes)
			(effects
				(font
					(size 1 1)
					(thickness 0.15)
				)
				(justify mirror)
			)
		)
		(property "Dielectric" "X5R"
			(at 403.408 276.18 0)
			(layer "B.Fab")
			(hide yes)
			(effects
				(font
					(size 1 1)
					(thickness 0.15)
				)
				(justify mirror)
			)
		)
		(property "License" "Apache-2.0"
			(at 403.408 276.18 0)
			(layer "B.Fab")
			(hide yes)
			(effects
				(font
					(size 1 1)
					(thickness 0.15)
				)
				(justify mirror)
			)
		)
		(property "MPN" "GRM155R61H104KE14D"
			(at 403.408 276.18 0)
			(layer "B.Fab")
			(hide yes)
			(effects
				(font
					(size 1 1)
					(thickness 0.15)
				)
				(justify mirror)
			)
		)
		(property "Manufacturer" "Murata"
			(at 403.408 276.18 0)
			(layer "B.Fab")
			(hide yes)
			(effects
				(font
					(size 1 1)
					(thickness 0.15)
				)
				(justify mirror)
			)
		)
		(property "Public" ""
			(at 403.408 276.18 0)
			(layer "B.Fab")
			(hide yes)
			(effects
				(font
					(size 1 1)
					(thickness 0.15)
				)
				(justify mirror)
			)
		)
		(property "Val" "100n"
			(at 403.408 276.18 0)
			(layer "B.Fab")
			(hide yes)
			(effects
				(font
					(size 1 1)
					(thickness 0.15)
				)
				(justify mirror)
			)
		)
		(property "Voltage" "50V"
			(at 403.408 276.18 0)
			(layer "B.Fab")
			(hide yes)
			(effects
				(font
					(size 1 1)
					(thickness 0.15)
				)
				(justify mirror)
			)
		)
		(sheetname "/FPGA Supply/")
		(sheetfile "fpga-supply.kicad_sch")
		(attr smd)
		(fp_rect
			(start -0.925 0.47)
			(end 0.925 -0.47)
			(stroke
				(width 0.05)
				(type default)
			)
			(fill no)
			(layer "B.CrtYd")
		)
		(fp_line
			(start 0.504 0.25)
			(end 0.504 -0.248)
			(stroke
				(width 0.15)
				(type solid)
			)
			(layer "B.Fab")
		)
		(fp_line
			(start 0.504 -0.248)
			(end -0.494 -0.248)
			(stroke
				(width 0.15)
				(type solid)
			)
			(layer "B.Fab")
		)
		(fp_line
			(start -0.494 0.25)
			(end 0.504 0.25)
			(stroke
				(width 0.15)
				(type solid)
			)
			(layer "B.Fab")
		)
		(fp_line
			(start -0.494 -0.248)
			(end -0.494 0.25)
			(stroke
				(width 0.15)
				(type solid)
			)
			(layer "B.Fab")
		)
		(fp_text user "License: Apache-2.0"
			(at -0.939 -5.799 0)
			(layer "B.Fab")
			(effects
				(font
					(size 0.7 0.7)
					(thickness 0.15)
				)
				(justify left bottom mirror)
			)
		)
		(fp_text user "${REFERENCE}"
			(at -0.939 -4.599 0)
			(layer "B.Fab")
			(effects
				(font
					(size 0.7 0.7)
					(thickness 0.15)
				)
				(justify left bottom mirror)
			)
		)
		(fp_text user "Author: Antmicro"
			(at -0.939 -3.399 0)
			(layer "B.Fab")
			(effects
				(font
					(size 0.7 0.7)
					(thickness 0.15)
				)
				(justify left bottom mirror)
			)
		)
		(pad "1" smd roundrect
			(at -0.48 0 180)
			(size 0.59 0.64)
			(layers "B.Cu" "B.Mask" "B.Paste")
			(roundrect_rratio 0.25)
			(net 417 "GND")
			(pintype "passive")
		)
		(pad "2" smd roundrect
			(at 0.48 0 180)
			(size 0.59 0.64)
			(layers "B.Cu" "B.Mask" "B.Paste")
			(roundrect_rratio 0.25)
			(net 1 "/FPGA Supply/XCVR_VREF")
			(pintype "passive")
		)
	)
	(footprint "antmicro-footprints:C_0402_1005Metric"
		(layer "B.Cu")
		(at 193.96 124.26 180)
		(descr "Capacitor SMD 0402")
		(tags "capacitor SMD 0402")
		(property "Reference" "C5"
			(at -0.815 1.56 0)
			(layer "B.SilkS")
			(effects
				(font
					(size 0.7 0.7)
					(thickness 0.15)
				)
				(justify left bottom mirror)
			)
		)
		(property "Value" "C_3n3_0402"
			(at -1.022927 -2.155213 0)
			(layer "B.Fab")
			(hide yes)
			(effects
				(font
					(size 0.7 0.7)
					(thickness 0.15)
				)
				(justify left bottom mirror)
			)
		)
		(property "Datasheet" "https://www.kemet.com/en/us/capacitors/product/C0402C332K5RAC.html"
			(at 0 0 180)
			(layer "F.Fab")
			(hide yes)
			(effects
				(font
					(size 1.27 1.27)
					(thickness 0.15)
				)
			)
		)
		(property "Description" "SMD Multilayer Ceramic Capacitor, 3300 pF, 50 V, 0402 [1005 Metric], ± 10%, X7R, MC"
			(at 0 0 180)
			(layer "F.Fab")
			(hide yes)
			(effects
				(font
					(size 1.27 1.27)
					(thickness 0.15)
				)
			)
		)
		(property "Author" "Antmicro"
			(at 387.92 248.52 0)
			(layer "B.Fab")
			(hide yes)
			(effects
				(font
					(size 1 1)
					(thickness 0.15)
				)
				(justify mirror)
			)
		)
		(property "Dielectric" "X7R"
			(at 387.92 248.52 0)
			(layer "B.Fab")
			(hide yes)
			(effects
				(font
					(size 1 1)
					(thickness 0.15)
				)
				(justify mirror)
			)
		)
		(property "License" "Apache-2.0"
			(at 387.92 248.52 0)
			(layer "B.Fab")
			(hide yes)
			(effects
				(font
					(size 1 1)
					(thickness 0.15)
				)
				(justify mirror)
			)
		)
		(property "MPN" "C0402C332K5RAC"
			(at 387.92 248.52 0)
			(layer "B.Fab")
			(hide yes)
			(effects
				(font
					(size 1 1)
					(thickness 0.15)
				)
				(justify mirror)
			)
		)
		(property "Manufacturer" "KEMET"
			(at 387.92 248.52 0)
			(layer "B.Fab")
			(hide yes)
			(effects
				(font
					(size 1 1)
					(thickness 0.15)
				)
				(justify mirror)
			)
		)
		(property "Public" ""
			(at 387.92 248.52 0)
			(layer "B.Fab")
			(hide yes)
			(effects
				(font
					(size 1 1)
					(thickness 0.15)
				)
				(justify mirror)
			)
		)
		(property "Val" "3n3"
			(at 387.92 248.52 0)
			(layer "B.Fab")
			(hide yes)
			(effects
				(font
					(size 1 1)
					(thickness 0.15)
				)
				(justify mirror)
			)
		)
		(property "Voltage" "50V"
			(at 387.92 248.52 0)
			(layer "B.Fab")
			(hide yes)
			(effects
				(font
					(size 1 1)
					(thickness 0.15)
				)
				(justify mirror)
			)
		)
		(sheetname "/FPGA Supply/")
		(sheetfile "fpga-supply.kicad_sch")
		(attr smd)
		(fp_rect
			(start -0.925 0.47)
			(end 0.925 -0.47)
			(stroke
				(width 0.05)
				(type default)
			)
			(fill no)
			(layer "B.CrtYd")
		)
		(fp_line
			(start 0.504 0.25)
			(end 0.504 -0.248)
			(stroke
				(width 0.15)
				(type solid)
			)
			(layer "B.Fab")
		)
		(fp_line
			(start 0.504 -0.248)
			(end -0.494 -0.248)
			(stroke
				(width 0.15)
				(type solid)
			)
			(layer "B.Fab")
		)
		(fp_line
			(start -0.494 0.25)
			(end 0.504 0.25)
			(stroke
				(width 0.15)
				(type solid)
			)
			(layer "B.Fab")
		)
		(fp_line
			(start -0.494 -0.248)
			(end -0.494 0.25)
			(stroke
				(width 0.15)
				(type solid)
			)
			(layer "B.Fab")
		)
		(fp_text user "License: Apache-2.0"
			(at -0.939 -5.799 0)
			(layer "B.Fab")
			(effects
				(font
					(size 0.7 0.7)
					(thickness 0.15)
				)
				(justify left bottom mirror)
			)
		)
		(fp_text user "Author: Antmicro"
			(at -0.939 -3.399 0)
			(layer "B.Fab")
			(effects
				(font
					(size 0.7 0.7)
					(thickness 0.15)
				)
				(justify left bottom mirror)
			)
		)
		(fp_text user "${REFERENCE}"
			(at -0.939 -4.599 0)
			(layer "B.Fab")
			(effects
				(font
					(size 0.7 0.7)
					(thickness 0.15)
				)
				(justify left bottom mirror)
			)
		)
		(pad "1" smd roundrect
			(at -0.48 0 180)
			(size 0.59 0.64)
			(layers "B.Cu" "B.Mask" "B.Paste")
			(roundrect_rratio 0.25)
			(net 417 "GND")
			(pintype "passive")
		)
		(pad "2" smd roundrect
			(at 0.48 0 180)
			(size 0.59 0.64)
			(layers "B.Cu" "B.Mask" "B.Paste")
			(roundrect_rratio 0.25)
			(net 2 "+1V1")
			(pintype "passive")
		)
	)
	(footprint "antmicro-footprints:R_0402_1005Metric"
		(layer "B.Cu")
		(at 198.975 121.7 90)
		(descr "Resistor SMD 0402")
		(tags "resistor SMD 0402")
		(property "Reference" "R55"
			(at -2.21 -0.305 270)
			(layer "B.SilkS")
			(effects
				(font
					(size 0.7 0.7)
					(thickness 0.15)
				)
				(justify left bottom mirror)
			)
		)
		(property "Value" "R_10k_0402"
			(at -1.011843 -1.772047 270)
			(layer "B.Fab")
			(hide yes)
			(effects
				(font
					(size 0.7 0.7)
					(thickness 0.15)
				)
				(justify left bottom mirror)
			)
		)
		(property "Datasheet" "https://www.bourns.com/docs/product-datasheets/cr.pdf"
			(at 0 0 90)
			(layer "F.Fab")
			(hide yes)
			(effects
				(font
					(size 1.27 1.27)
					(thickness 0.15)
				)
			)
		)
		(property "Description" "SMD Chip Resistor, 10 kohm, ± 1%, 62.5 mW, 0402 [1005 Metric], Thick Film, General Purpose"
			(at 0 0 90)
			(layer "F.Fab")
			(hide yes)
			(effects
				(font
					(size 1.27 1.27)
					(thickness 0.15)
				)
			)
		)
		(property "Author" "Antmicro"
			(at 320.675 -77.275 0)
			(layer "B.Fab")
			(hide yes)
			(effects
				(font
					(size 1 1)
					(thickness 0.15)
				)
				(justify mirror)
			)
		)
		(property "DNP" "DNP"
			(at 320.675 -77.275 0)
			(layer "B.Fab")
			(hide yes)
			(effects
				(font
					(size 1 1)
					(thickness 0.15)
				)
				(justify mirror)
			)
		)
		(property "License" "Apache-2.0"
			(at 320.675 -77.275 0)
			(layer "B.Fab")
			(hide yes)
			(effects
				(font
					(size 1 1)
					(thickness 0.15)
				)
				(justify mirror)
			)
		)
		(property "MPN" "CR0402-FX-1002GLF"
			(at 320.675 -77.275 0)
			(layer "B.Fab")
			(hide yes)
			(effects
				(font
					(size 1 1)
					(thickness 0.15)
				)
				(justify mirror)
			)
		)
		(property "Manufacturer" "Bourns"
			(at 320.675 -77.275 0)
			(layer "B.Fab")
			(hide yes)
			(effects
				(font
					(size 1 1)
					(thickness 0.15)
				)
				(justify mirror)
			)
		)
		(property "Public" ""
			(at 320.675 -77.275 0)
			(layer "B.Fab")
			(hide yes)
			(effects
				(font
					(size 1 1)
					(thickness 0.15)
				)
				(justify mirror)
			)
		)
		(property "Tolerance" "1%"
			(at 320.675 -77.275 0)
			(layer "B.Fab")
			(hide yes)
			(effects
				(font
					(size 1 1)
					(thickness 0.15)
				)
				(justify mirror)
			)
		)
		(property "Val" "10k"
			(at 320.675 -77.275 0)
			(layer "B.Fab")
			(hide yes)
			(effects
				(font
					(size 1 1)
					(thickness 0.15)
				)
				(justify mirror)
			)
		)
		(sheetname "/Memory/")
		(sheetfile "memory.kicad_sch")
		(attr smd dnp)
		(fp_rect
			(start -0.925 0.47)
			(end 0.925 -0.47)
			(stroke
				(width 0.05)
				(type default)
			)
			(fill no)
			(layer "B.CrtYd")
		)
		(fp_rect
			(start -0.5 0.25)
			(end 0.5 -0.25)
			(stroke
				(width 0.15)
				(type solid)
			)
			(fill no)
			(layer "B.Fab")
		)
		(fp_text user "Author: Antmicro"
			(at -0.95 -4.169 270)
			(layer "B.Fab")
			(effects
				(font
					(size 0.7 0.7)
					(thickness 0.15)
				)
				(justify left bottom mirror)
			)
		)
		(fp_text user "${REFERENCE}"
			(at -0.95 -3.168 270)
			(layer "B.Fab")
			(effects
				(font
					(size 0.7 0.7)
					(thickness 0.15)
				)
				(justify left bottom mirror)
			)
		)
		(fp_text user "License: Apache-2.0"
			(at -0.95 -5.169 270)
			(layer "B.Fab")
			(effects
				(font
					(size 0.7 0.7)
					(thickness 0.15)
				)
				(justify left bottom mirror)
			)
		)
		(pad "1" smd roundrect
			(at -0.48 0 90)
			(size 0.59 0.64)
			(layers "B.Cu" "B.Mask" "B.Paste")
			(roundrect_rratio 0.25)
			(net 417 "GND")
			(pintype "passive")
		)
		(pad "2" smd roundrect
			(at 0.48 0 90)
			(size 0.59 0.64)
			(layers "B.Cu" "B.Mask" "B.Paste")
			(roundrect_rratio 0.25)
			(net 44 "SD_PWR_ON")
			(pintype "passive")
		)
	)
	(footprint "antmicro-footprints:C_0402_1005Metric"
		(layer "B.Cu")
		(at 189.28 144.65 180)
		(descr "Capacitor SMD 0402")
		(tags "capacitor SMD 0402")
		(property "Reference" "C43"
			(at -2.45 -4.08 0)
			(layer "B.SilkS")
			(effects
				(font
					(size 0.7 0.7)
					(thickness 0.15)
				)
				(justify left bottom mirror)
			)
		)
		(property "Value" "C_100n_0402"
			(at -1.022927 -2.155213 0)
			(layer "B.Fab")
			(hide yes)
			(effects
				(font
					(size 0.7 0.7)
					(thickness 0.15)
				)
				(justify left bottom mirror)
			)
		)
		(property "Datasheet" "https://www.murata.com/products/productdetail?partno=GRM155R61H104KE14%23"
			(at 0 0 180)
			(layer "F.Fab")
			(hide yes)
			(effects
				(font
					(size 1.27 1.27)
					(thickness 0.15)
				)
			)
		)
		(property "Description" "SMD Multilayer Ceramic Capacitor, 0.1 µF, 50 V, 0402 [1005 Metric], ± 10%, X5R, GRM Series"
			(at 0 0 180)
			(layer "F.Fab")
			(hide yes)
			(effects
				(font
					(size 1.27 1.27)
					(thickness 0.15)
				)
			)
		)
		(property "Author" "Antmicro"
			(at 378.56 289.3 0)
			(layer "B.Fab")
			(hide yes)
			(effects
				(font
					(size 1 1)
					(thickness 0.15)
				)
				(justify mirror)
			)
		)
		(property "Dielectric" "X5R"
			(at 378.56 289.3 0)
			(layer "B.Fab")
			(hide yes)
			(effects
				(font
					(size 1 1)
					(thickness 0.15)
				)
				(justify mirror)
			)
		)
		(property "License" "Apache-2.0"
			(at 378.56 289.3 0)
			(layer "B.Fab")
			(hide yes)
			(effects
				(font
					(size 1 1)
					(thickness 0.15)
				)
				(justify mirror)
			)
		)
		(property "MPN" "GRM155R61H104KE14D"
			(at 378.56 289.3 0)
			(layer "B.Fab")
			(hide yes)
			(effects
				(font
					(size 1 1)
					(thickness 0.15)
				)
				(justify mirror)
			)
		)
		(property "Manufacturer" "Murata"
			(at 378.56 289.3 0)
			(layer "B.Fab")
			(hide yes)
			(effects
				(font
					(size 1 1)
					(thickness 0.15)
				)
				(justify mirror)
			)
		)
		(property "Public" ""
			(at 378.56 289.3 0)
			(layer "B.Fab")
			(hide yes)
			(effects
				(font
					(size 1 1)
					(thickness 0.15)
				)
				(justify mirror)
			)
		)
		(property "Val" "100n"
			(at 378.56 289.3 0)
			(layer "B.Fab")
			(hide yes)
			(effects
				(font
					(size 1 1)
					(thickness 0.15)
				)
				(justify mirror)
			)
		)
		(property "Voltage" "50V"
			(at 378.56 289.3 0)
			(layer "B.Fab")
			(hide yes)
			(effects
				(font
					(size 1 1)
					(thickness 0.15)
				)
				(justify mirror)
			)
		)
		(sheetname "/FPGA Supply/")
		(sheetfile "fpga-supply.kicad_sch")
		(attr smd)
		(fp_rect
			(start -0.925 0.47)
			(end 0.925 -0.47)
			(stroke
				(width 0.05)
				(type default)
			)
			(fill no)
			(layer "B.CrtYd")
		)
		(fp_line
			(start 0.504 0.25)
			(end 0.504 -0.248)
			(stroke
				(width 0.15)
				(type solid)
			)
			(layer "B.Fab")
		)
		(fp_line
			(start 0.504 -0.248)
			(end -0.494 -0.248)
			(stroke
				(width 0.15)
				(type solid)
			)
			(layer "B.Fab")
		)
		(fp_line
			(start -0.494 0.25)
			(end 0.504 0.25)
			(stroke
				(width 0.15)
				(type solid)
			)
			(layer "B.Fab")
		)
		(fp_line
			(start -0.494 -0.248)
			(end -0.494 0.25)
			(stroke
				(width 0.15)
				(type solid)
			)
			(layer "B.Fab")
		)
		(fp_text user "${REFERENCE}"
			(at -0.939 -4.599 0)
			(layer "B.Fab")
			(effects
				(font
					(size 0.7 0.7)
					(thickness 0.15)
				)
				(justify left bottom mirror)
			)
		)
		(fp_text user "License: Apache-2.0"
			(at -0.939 -5.799 0)
			(layer "B.Fab")
			(effects
				(font
					(size 0.7 0.7)
					(thickness 0.15)
				)
				(justify left bottom mirror)
			)
		)
		(fp_text user "Author: Antmicro"
			(at -0.939 -3.399 0)
			(layer "B.Fab")
			(effects
				(font
					(size 0.7 0.7)
					(thickness 0.15)
				)
				(justify left bottom mirror)
			)
		)
		(pad "1" smd roundrect
			(at -0.48 0 180)
			(size 0.59 0.64)
			(layers "B.Cu" "B.Mask" "B.Paste")
			(roundrect_rratio 0.25)
			(net 417 "GND")
			(pintype "passive")
		)
		(pad "2" smd roundrect
			(at 0.48 0 180)
			(size 0.59 0.64)
			(layers "B.Cu" "B.Mask" "B.Paste")
			(roundrect_rratio 0.25)
			(net 47 "+1V05")
			(pintype "passive")
		)
	)
	(footprint "antmicro-footprints:TP_SMD_0.75mm"
		(layer "B.Cu")
		(at 187.15 139.125 180)
		(property "Reference" "TP39"
			(at 0 0.6 0)
			(layer "B.SilkS")
			(hide yes)
			(effects
				(font
					(size 0.7 0.7)
					(thickness 0.15)
				)
				(justify left bottom mirror)
			)
		)
		(property "Value" "TP_0.75mm_SMD"
			(at 0 -1.2 0)
			(layer "B.Fab")
			(hide yes)
			(effects
				(font
					(size 0.7 0.7)
					(thickness 0.15)
				)
				(justify left bottom mirror)
			)
		)
		(property "Description" "SMT test point"
			(at 0 0 0)
			(layer "B.Fab")
			(hide yes)
			(effects
				(font
					(size 1.27 1.27)
					(thickness 0.15)
				)
				(justify mirror)
			)
		)
		(property "MPN" ""
			(at 0 0 0)
			(unlocked yes)
			(layer "B.Fab")
			(hide yes)
			(effects
				(font
					(size 1 1)
					(thickness 0.15)
				)
				(justify mirror)
			)
		)
		(property "Manufacturer" ""
			(at 0 0 0)
			(unlocked yes)
			(layer "B.Fab")
			(hide yes)
			(effects
				(font
					(size 1 1)
					(thickness 0.15)
				)
				(justify mirror)
			)
		)
		(property "Author" "Antmicro"
			(at 0 0 0)
			(unlocked yes)
			(layer "B.Fab")
			(hide yes)
			(effects
				(font
					(size 1 1)
					(thickness 0.15)
				)
				(justify mirror)
			)
		)
		(property "License" "Apache-2.0"
			(at 0 0 0)
			(unlocked yes)
			(layer "B.Fab")
			(hide yes)
			(effects
				(font
					(size 1 1)
					(thickness 0.15)
				)
				(justify mirror)
			)
		)
		(property "Public" "False"
			(at 0 0 0)
			(unlocked yes)
			(layer "B.Fab")
			(hide yes)
			(effects
				(font
					(size 1 1)
					(thickness 0.15)
				)
				(justify mirror)
			)
		)
		(sheetname "/Supply/")
		(sheetfile "supply.kicad_sch")
		(attr exclude_from_pos_files exclude_from_bom)
		(fp_circle
			(center 0 0)
			(end 0.475 0)
			(stroke
				(width 0.05)
				(type default)
			)
			(fill no)
			(layer "B.CrtYd")
		)
		(fp_text user "License: Apache-2.0"
			(at -0.4 -5.101 0)
			(layer "B.Fab")
			(effects
				(font
					(size 0.7 0.7)
					(thickness 0.15)
				)
				(justify left bottom mirror)
			)
		)
		(fp_text user "${REFERENCE}"
			(at -0.4 -2.7 0)
			(layer "B.Fab")
			(effects
				(font
					(size 0.7 0.7)
					(thickness 0.15)
				)
				(justify left bottom mirror)
			)
		)
		(fp_text user "Author: Antmicro"
			(at -0.4 -3.901 0)
			(layer "B.Fab")
			(effects
				(font
					(size 0.7 0.7)
					(thickness 0.15)
				)
				(justify left bottom mirror)
			)
		)
		(pad "1" smd circle
			(at 0 0 180)
			(size 0.75 0.75)
			(layers "B.Cu" "B.Mask")
			(net 90 "+5V")
			(pinfunction "1")
			(pintype "passive")
		)
	)
	(footprint "antmicro-footprints:C_0402_1005Metric"
		(layer "B.Cu")
		(at 199.91 138.63 90)
		(descr "Capacitor SMD 0402")
		(tags "capacitor SMD 0402")
		(property "Reference" "C25"
			(at 4.88 -9.685 90)
			(layer "B.SilkS")
			(effects
				(font
					(size 0.7 0.7)
					(thickness 0.15)
				)
				(justify right bottom mirror)
			)
		)
		(property "Value" "C_4n7_0402"
			(at -1.022927 -2.155213 90)
			(layer "B.Fab")
			(hide yes)
			(effects
				(font
					(size 0.7 0.7)
					(thickness 0.15)
				)
				(justify right bottom mirror)
			)
		)
		(property "Datasheet" "https://product.tdk.com/en/search/capacitor/ceramic/mlcc/info?part_no=CGA2B3X7S2A472K050BB"
			(at 0 0 90)
			(layer "F.Fab")
			(hide yes)
			(effects
				(font
					(size 1.27 1.27)
					(thickness 0.15)
				)
			)
		)
		(property "Description" "SMD Multilayer Ceramic Capacitor, 4700 pF, 100 V, 0402 [1005 Metric], ± 10%, X7S, CGA"
			(at 0 0 90)
			(layer "F.Fab")
			(hide yes)
			(effects
				(font
					(size 1.27 1.27)
					(thickness 0.15)
				)
			)
		)
		(property "Author" "Antmicro"
			(at 338.54 -61.28 0)
			(layer "B.Fab")
			(hide yes)
			(effects
				(font
					(size 1 1)
					(thickness 0.15)
				)
				(justify mirror)
			)
		)
		(property "Dielectric" "X7R"
			(at 338.54 -61.28 0)
			(layer "B.Fab")
			(hide yes)
			(effects
				(font
					(size 1 1)
					(thickness 0.15)
				)
				(justify mirror)
			)
		)
		(property "License" "Apache-2.0"
			(at 338.54 -61.28 0)
			(layer "B.Fab")
			(hide yes)
			(effects
				(font
					(size 1 1)
					(thickness 0.15)
				)
				(justify mirror)
			)
		)
		(property "MPN" "CGA2B3X7S2A472K050BB"
			(at 338.54 -61.28 0)
			(layer "B.Fab")
			(hide yes)
			(effects
				(font
					(size 1 1)
					(thickness 0.15)
				)
				(justify mirror)
			)
		)
		(property "Manufacturer" "TDK"
			(at 338.54 -61.28 0)
			(layer "B.Fab")
			(hide yes)
			(effects
				(font
					(size 1 1)
					(thickness 0.15)
				)
				(justify mirror)
			)
		)
		(property "Public" ""
			(at 338.54 -61.28 0)
			(layer "B.Fab")
			(hide yes)
			(effects
				(font
					(size 1 1)
					(thickness 0.15)
				)
				(justify mirror)
			)
		)
		(property "Val" "4n7"
			(at 338.54 -61.28 0)
			(layer "B.Fab")
			(hide yes)
			(effects
				(font
					(size 1 1)
					(thickness 0.15)
				)
				(justify mirror)
			)
		)
		(property "Voltage" "25V"
			(at 338.54 -61.28 0)
			(layer "B.Fab")
			(hide yes)
			(effects
				(font
					(size 1 1)
					(thickness 0.15)
				)
				(justify mirror)
			)
		)
		(sheetname "/FPGA Supply/")
		(sheetfile "fpga-supply.kicad_sch")
		(attr smd)
		(fp_rect
			(start -0.925 0.47)
			(end 0.925 -0.47)
			(stroke
				(width 0.05)
				(type default)
			)
			(fill no)
			(layer "B.CrtYd")
		)
		(fp_line
			(start 0.504 -0.248)
			(end -0.494 -0.248)
			(stroke
				(width 0.15)
				(type solid)
			)
			(layer "B.Fab")
		)
		(fp_line
			(start -0.494 -0.248)
			(end -0.494 0.25)
			(stroke
				(width 0.15)
				(type solid)
			)
			(layer "B.Fab")
		)
		(fp_line
			(start 0.504 0.25)
			(end 0.504 -0.248)
			(stroke
				(width 0.15)
				(type solid)
			)
			(layer "B.Fab")
		)
		(fp_line
			(start -0.494 0.25)
			(end 0.504 0.25)
			(stroke
				(width 0.15)
				(type solid)
			)
			(layer "B.Fab")
		)
		(fp_text user "${REFERENCE}"
			(at -0.939 -4.599 270)
			(layer "B.Fab")
			(effects
				(font
					(size 0.7 0.7)
					(thickness 0.15)
				)
				(justify left bottom mirror)
			)
		)
		(fp_text user "License: Apache-2.0"
			(at -0.939 -5.799 270)
			(layer "B.Fab")
			(effects
				(font
					(size 0.7 0.7)
					(thickness 0.15)
				)
				(justify left bottom mirror)
			)
		)
		(fp_text user "Author: Antmicro"
			(at -0.939 -3.399 270)
			(layer "B.Fab")
			(effects
				(font
					(size 0.7 0.7)
					(thickness 0.15)
				)
				(justify left bottom mirror)
			)
		)
		(pad "1" smd roundrect
			(at -0.48 0 90)
			(size 0.59 0.64)
			(layers "B.Cu" "B.Mask" "B.Paste")
			(roundrect_rratio 0.25)
			(net 417 "GND")
			(pintype "passive")
		)
		(pad "2" smd roundrect
			(at 0.48 0 90)
			(size 0.59 0.64)
			(layers "B.Cu" "B.Mask" "B.Paste")
			(roundrect_rratio 0.25)
			(net 418 "+2V5")
			(pintype "passive")
		)
	)
	(footprint "antmicro-footprints:C_0402_1005Metric"
		(layer "B.Cu")
		(at 177.7 125.1 -90)
		(descr "Capacitor SMD 0402")
		(tags "capacitor SMD 0402")
		(property "Reference" "C142"
			(at -1.3 -1.36 90)
			(layer "B.SilkS")
			(effects
				(font
					(size 0.7 0.7)
					(thickness 0.15)
				)
				(justify left bottom mirror)
			)
		)
		(property "Value" "C_1u_0402"
			(at -1.022927 -2.155213 90)
			(layer "B.Fab")
			(hide yes)
			(effects
				(font
					(size 0.7 0.7)
					(thickness 0.15)
				)
				(justify left bottom mirror)
			)
		)
		(property "Datasheet" "https://product.tdk.com/en/search/capacitor/ceramic/mlcc/info?part_no=C1005X6S1A105K050BC"
			(at 0 0 270)
			(layer "F.Fab")
			(hide yes)
			(effects
				(font
					(size 1.27 1.27)
					(thickness 0.15)
				)
			)
		)
		(property "Description" "SMD Multilayer Ceramic Capacitor, 1 µF, 10 V, 0402 [1005 Metric], ± 10%, X6S, C"
			(at 0 0 270)
			(layer "F.Fab")
			(hide yes)
			(effects
				(font
					(size 1.27 1.27)
					(thickness 0.15)
				)
			)
		)
		(property "Author" "Antmicro"
			(at 52.6 302.8 0)
			(layer "B.Fab")
			(hide yes)
			(effects
				(font
					(size 1 1)
					(thickness 0.15)
				)
				(justify mirror)
			)
		)
		(property "Dielectric" "X5R"
			(at 52.6 302.8 0)
			(layer "B.Fab")
			(hide yes)
			(effects
				(font
					(size 1 1)
					(thickness 0.15)
				)
				(justify mirror)
			)
		)
		(property "License" "Apache-2.0"
			(at 52.6 302.8 0)
			(layer "B.Fab")
			(hide yes)
			(effects
				(font
					(size 1 1)
					(thickness 0.15)
				)
				(justify mirror)
			)
		)
		(property "MPN" "C1005X6S1A105K050BC"
			(at 52.6 302.8 0)
			(layer "B.Fab")
			(hide yes)
			(effects
				(font
					(size 1 1)
					(thickness 0.15)
				)
				(justify mirror)
			)
		)
		(property "Manufacturer" "TDK"
			(at 52.6 302.8 0)
			(layer "B.Fab")
			(hide yes)
			(effects
				(font
					(size 1 1)
					(thickness 0.15)
				)
				(justify mirror)
			)
		)
		(property "Public" ""
			(at 52.6 302.8 0)
			(layer "B.Fab")
			(hide yes)
			(effects
				(font
					(size 1 1)
					(thickness 0.15)
				)
				(justify mirror)
			)
		)
		(property "Val" "1u"
			(at 52.6 302.8 0)
			(layer "B.Fab")
			(hide yes)
			(effects
				(font
					(size 1 1)
					(thickness 0.15)
				)
				(justify mirror)
			)
		)
		(property "Voltage" "16V"
			(at 52.6 302.8 0)
			(layer "B.Fab")
			(hide yes)
			(effects
				(font
					(size 1 1)
					(thickness 0.15)
				)
				(justify mirror)
			)
		)
		(sheetname "/LPDDR4/")
		(sheetfile "lpddr.kicad_sch")
		(attr smd)
		(fp_rect
			(start -0.925 0.47)
			(end 0.925 -0.47)
			(stroke
				(width 0.05)
				(type default)
			)
			(fill no)
			(layer "B.CrtYd")
		)
		(fp_line
			(start -0.494 0.25)
			(end 0.504 0.25)
			(stroke
				(width 0.15)
				(type solid)
			)
			(layer "B.Fab")
		)
		(fp_line
			(start 0.504 0.25)
			(end 0.504 -0.248)
			(stroke
				(width 0.15)
				(type solid)
			)
			(layer "B.Fab")
		)
		(fp_line
			(start -0.494 -0.248)
			(end -0.494 0.25)
			(stroke
				(width 0.15)
				(type solid)
			)
			(layer "B.Fab")
		)
		(fp_line
			(start 0.504 -0.248)
			(end -0.494 -0.248)
			(stroke
				(width 0.15)
				(type solid)
			)
			(layer "B.Fab")
		)
		(fp_text user "License: Apache-2.0"
			(at -0.939 -5.799 90)
			(layer "B.Fab")
			(effects
				(font
					(size 0.7 0.7)
					(thickness 0.15)
				)
				(justify left bottom mirror)
			)
		)
		(fp_text user "${REFERENCE}"
			(at -0.939 -4.599 90)
			(layer "B.Fab")
			(effects
				(font
					(size 0.7 0.7)
					(thickness 0.15)
				)
				(justify left bottom mirror)
			)
		)
		(fp_text user "Author: Antmicro"
			(at -0.939 -3.399 90)
			(layer "B.Fab")
			(effects
				(font
					(size 0.7 0.7)
					(thickness 0.15)
				)
				(justify left bottom mirror)
			)
		)
		(pad "1" smd roundrect
			(at -0.48 0 270)
			(size 0.59 0.64)
			(layers "B.Cu" "B.Mask" "B.Paste")
			(roundrect_rratio 0.25)
			(net 417 "GND")
			(pintype "passive")
		)
		(pad "2" smd roundrect
			(at 0.48 0 270)
			(size 0.59 0.64)
			(layers "B.Cu" "B.Mask" "B.Paste")
			(roundrect_rratio 0.25)
			(net 2 "+1V1")
			(pintype "passive")
		)
	)
	(footprint "antmicro-footprints:R_0402_1005Metric"
		(layer "B.Cu")
		(at 187.85 120.85 -90)
		(descr "Resistor SMD 0402")
		(tags "resistor SMD 0402")
		(property "Reference" "R42"
			(at -4.875 -0.2 90)
			(layer "B.SilkS")
			(effects
				(font
					(size 0.7 0.7)
					(thickness 0.15)
				)
				(justify left bottom mirror)
			)
		)
		(property "Value" "R_1k_0402"
			(at -1.011843 -1.772047 90)
			(layer "B.Fab")
			(hide yes)
			(effects
				(font
					(size 0.7 0.7)
					(thickness 0.15)
				)
				(justify left bottom mirror)
			)
		)
		(property "Datasheet" "https://www.bourns.com/docs/product-datasheets/cr.pdf"
			(at 0 0 270)
			(layer "F.Fab")
			(hide yes)
			(effects
				(font
					(size 1.27 1.27)
					(thickness 0.15)
				)
			)
		)
		(property "Description" "SMD Chip Resistor, 1 kohm, ± 1%, 63 mW, 0402 [1005 Metric], Thick Film, General Purpose"
			(at 0 0 270)
			(layer "F.Fab")
			(hide yes)
			(effects
				(font
					(size 1.27 1.27)
					(thickness 0.15)
				)
			)
		)
		(property "Author" "Antmicro"
			(at 67 308.7 0)
			(layer "B.Fab")
			(hide yes)
			(effects
				(font
					(size 1 1)
					(thickness 0.15)
				)
				(justify mirror)
			)
		)
		(property "License" "Apache-2.0"
			(at 67 308.7 0)
			(layer "B.Fab")
			(hide yes)
			(effects
				(font
					(size 1 1)
					(thickness 0.15)
				)
				(justify mirror)
			)
		)
		(property "MPN" "CR0402-FX-1001GLF"
			(at 67 308.7 0)
			(layer "B.Fab")
			(hide yes)
			(effects
				(font
					(size 1 1)
					(thickness 0.15)
				)
				(justify mirror)
			)
		)
		(property "Manufacturer" "Bourns"
			(at 67 308.7 0)
			(layer "B.Fab")
			(hide yes)
			(effects
				(font
					(size 1 1)
					(thickness 0.15)
				)
				(justify mirror)
			)
		)
		(property "Public" ""
			(at 67 308.7 0)
			(layer "B.Fab")
			(hide yes)
			(effects
				(font
					(size 1 1)
					(thickness 0.15)
				)
				(justify mirror)
			)
		)
		(property "Tolerance" "1%"
			(at 67 308.7 0)
			(layer "B.Fab")
			(hide yes)
			(effects
				(font
					(size 1 1)
					(thickness 0.15)
				)
				(justify mirror)
			)
		)
		(property "Val" "1k"
			(at 67 308.7 0)
			(layer "B.Fab")
			(hide yes)
			(effects
				(font
					(size 1 1)
					(thickness 0.15)
				)
				(justify mirror)
			)
		)
		(sheetname "/FPGA Config/")
		(sheetfile "fpga-config.kicad_sch")
		(attr smd)
		(fp_rect
			(start -0.925 0.47)
			(end 0.925 -0.47)
			(stroke
				(width 0.05)
				(type default)
			)
			(fill no)
			(layer "B.CrtYd")
		)
		(fp_rect
			(start -0.5 0.25)
			(end 0.5 -0.25)
			(stroke
				(width 0.15)
				(type solid)
			)
			(fill no)
			(layer "B.Fab")
		)
		(fp_text user "Author: Antmicro"
			(at -0.95 -4.169 90)
			(layer "B.Fab")
			(effects
				(font
					(size 0.7 0.7)
					(thickness 0.15)
				)
				(justify left bottom mirror)
			)
		)
		(fp_text user "License: Apache-2.0"
			(at -0.95 -5.169 90)
			(layer "B.Fab")
			(effects
				(font
					(size 0.7 0.7)
					(thickness 0.15)
				)
				(justify left bottom mirror)
			)
		)
		(fp_text user "${REFERENCE}"
			(at -0.95 -3.168 90)
			(layer "B.Fab")
			(effects
				(font
					(size 0.7 0.7)
					(thickness 0.15)
				)
				(justify left bottom mirror)
			)
		)
		(pad "1" smd roundrect
			(at -0.48 0 270)
			(size 0.59 0.64)
			(layers "B.Cu" "B.Mask" "B.Paste")
			(roundrect_rratio 0.25)
			(net 655 "/FPGA Config/DEVRST_N")
			(pintype "passive")
		)
		(pad "2" smd roundrect
			(at 0.48 0 270)
			(size 0.59 0.64)
			(layers "B.Cu" "B.Mask" "B.Paste")
			(roundrect_rratio 0.25)
			(net 50 "+3V3")
			(pintype "passive")
		)
	)
	(footprint "antmicro-footprints:R_0402_1005Metric"
		(layer "B.Cu")
		(at 210.1925 131.347)
		(descr "Resistor SMD 0402")
		(tags "resistor SMD 0402")
		(property "Reference" "R32"
			(at -0.8425 0.628 180)
			(layer "B.SilkS")
			(effects
				(font
					(size 0.7 0.7)
					(thickness 0.15)
				)
				(justify left bottom mirror)
			)
		)
		(property "Value" "R_49k9_0402"
			(at -1.011843 -1.772047 180)
			(layer "B.Fab")
			(hide yes)
			(effects
				(font
					(size 0.7 0.7)
					(thickness 0.15)
				)
				(justify left bottom mirror)
			)
		)
		(property "Datasheet" "https://www.bourns.com/docs/product-datasheets/cr.pdf"
			(at 0 0 0)
			(layer "F.Fab")
			(hide yes)
			(effects
				(font
					(size 1.27 1.27)
					(thickness 0.15)
				)
			)
		)
		(property "Description" "SMD Chip Resistor, 49.9 kohm, ± 1%, 63 mW, 0402 [1005 Metric], Thick Film, General Purpose"
			(at 0 0 0)
			(layer "F.Fab")
			(hide yes)
			(effects
				(font
					(size 1.27 1.27)
					(thickness 0.15)
				)
			)
		)
		(property "Author" "Antmicro"
			(at 0 0 0)
			(layer "B.Fab")
			(hide yes)
			(effects
				(font
					(size 1 1)
					(thickness 0.15)
				)
				(justify mirror)
			)
		)
		(property "License" "Apache-2.0"
			(at 0 0 0)
			(layer "B.Fab")
			(hide yes)
			(effects
				(font
					(size 1 1)
					(thickness 0.15)
				)
				(justify mirror)
			)
		)
		(property "MPN" "CR0402-FX-4992GLF"
			(at 0 0 0)
			(layer "B.Fab")
			(hide yes)
			(effects
				(font
					(size 1 1)
					(thickness 0.15)
				)
				(justify mirror)
			)
		)
		(property "Manufacturer" "Bourns"
			(at 0 0 0)
			(layer "B.Fab")
			(hide yes)
			(effects
				(font
					(size 1 1)
					(thickness 0.15)
				)
				(justify mirror)
			)
		)
		(property "Public" ""
			(at 0 0 0)
			(layer "B.Fab")
			(hide yes)
			(effects
				(font
					(size 1 1)
					(thickness 0.15)
				)
				(justify mirror)
			)
		)
		(property "Tolerance" "1%"
			(at 0 0 0)
			(layer "B.Fab")
			(hide yes)
			(effects
				(font
					(size 1 1)
					(thickness 0.15)
				)
				(justify mirror)
			)
		)
		(property "Val" "49k9"
			(at 0 0 0)
			(layer "B.Fab")
			(hide yes)
			(effects
				(font
					(size 1 1)
					(thickness 0.15)
				)
				(justify mirror)
			)
		)
		(sheetname "/Memory/")
		(sheetfile "memory.kicad_sch")
		(attr smd)
		(fp_rect
			(start -0.925 0.47)
			(end 0.925 -0.47)
			(stroke
				(width 0.05)
				(type default)
			)
			(fill no)
			(layer "B.CrtYd")
		)
		(fp_rect
			(start -0.5 0.25)
			(end 0.5 -0.25)
			(stroke
				(width 0.15)
				(type solid)
			)
			(fill no)
			(layer "B.Fab")
		)
		(fp_text user "License: Apache-2.0"
			(at -0.95 -5.169 180)
			(layer "B.Fab")
			(effects
				(font
					(size 0.7 0.7)
					(thickness 0.15)
				)
				(justify left bottom mirror)
			)
		)
		(fp_text user "${REFERENCE}"
			(at -0.95 -3.168 180)
			(layer "B.Fab")
			(effects
				(font
					(size 0.7 0.7)
					(thickness 0.15)
				)
				(justify left bottom mirror)
			)
		)
		(fp_text user "Author: Antmicro"
			(at -0.95 -4.169 180)
			(layer "B.Fab")
			(effects
				(font
					(size 0.7 0.7)
					(thickness 0.15)
				)
				(justify left bottom mirror)
			)
		)
		(pad "1" smd roundrect
			(at -0.48 0)
			(size 0.59 0.64)
			(layers "B.Cu" "B.Mask" "B.Paste")
			(roundrect_rratio 0.25)
			(net 249 "/FPGA MSSIO/EMMC.DAT6")
			(pintype "passive")
		)
		(pad "2" smd roundrect
			(at 0.48 0)
			(size 0.59 0.64)
			(layers "B.Cu" "B.Mask" "B.Paste")
			(roundrect_rratio 0.25)
			(net 137 "SD_VDD")
			(pintype "passive")
		)
	)
	(footprint "antmicro-footprints:R_0402_1005Metric"
		(layer "B.Cu")
		(at 184.262625 146.299364 -45)
		(descr "Resistor SMD 0402")
		(tags "resistor SMD 0402")
		(property "Reference" "R84"
			(at 3.046224 -1.645253 315)
			(layer "B.SilkS")
			(effects
				(font
					(size 0.7 0.7)
					(thickness 0.15)
				)
				(justify left bottom mirror)
			)
		)
		(property "Value" "R_0R_0402"
			(at -1.011843 -1.772046 135)
			(layer "B.Fab")
			(hide yes)
			(effects
				(font
					(size 0.7 0.7)
					(thickness 0.15)
				)
				(justify left bottom mirror)
			)
		)
		(property "Datasheet" "https://industrial.panasonic.com/cdbs/www-data/pdf/RDA0000/AOA0000C301.pdf"
			(at 0 0 315)
			(layer "F.Fab")
			(hide yes)
			(effects
				(font
					(size 1.27 1.27)
					(thickness 0.15)
				)
			)
		)
		(property "Description" "SMD Chip Resistor, Jumper, 0 ohm, 100 mW, 0402 [1005 Metric], Thick Film, General Purpose"
			(at 0 0 315)
			(layer "F.Fab")
			(hide yes)
			(effects
				(font
					(size 1.27 1.27)
					(thickness 0.15)
				)
			)
		)
		(property "Author" "Antmicro"
			(at -49.479999 173.143443 0)
			(layer "B.Fab")
			(hide yes)
			(effects
				(font
					(size 1 1)
					(thickness 0.15)
				)
				(justify mirror)
			)
		)
		(property "Current" "1A"
			(at -49.479999 173.143443 0)
			(layer "B.Fab")
			(hide yes)
			(effects
				(font
					(size 1 1)
					(thickness 0.15)
				)
				(justify mirror)
			)
		)
		(property "License" "Apache-2.0"
			(at -49.479999 173.143443 0)
			(layer "B.Fab")
			(hide yes)
			(effects
				(font
					(size 1 1)
					(thickness 0.15)
				)
				(justify mirror)
			)
		)
		(property "MPN" "ERJ2GE0R00X"
			(at -49.479999 173.143443 0)
			(layer "B.Fab")
			(hide yes)
			(effects
				(font
					(size 1 1)
					(thickness 0.15)
				)
				(justify mirror)
			)
		)
		(property "Manufacturer" "Panasonic"
			(at -49.479999 173.143443 0)
			(layer "B.Fab")
			(hide yes)
			(effects
				(font
					(size 1 1)
					(thickness 0.15)
				)
				(justify mirror)
			)
		)
		(property "Public" ""
			(at -49.479999 173.143443 0)
			(layer "B.Fab")
			(hide yes)
			(effects
				(font
					(size 1 1)
					(thickness 0.15)
				)
				(justify mirror)
			)
		)
		(property "Tolerance" "~"
			(at -49.479999 173.143443 0)
			(layer "B.Fab")
			(hide yes)
			(effects
				(font
					(size 1 1)
					(thickness 0.15)
				)
				(justify mirror)
			)
		)
		(property "Val" "0R"
			(at -49.479999 173.143443 0)
			(layer "B.Fab")
			(hide yes)
			(effects
				(font
					(size 1 1)
					(thickness 0.15)
				)
				(justify mirror)
			)
		)
		(sheetname "/Supply/")
		(sheetfile "supply.kicad_sch")
		(attr smd)
		(fp_poly
			(pts
				(xy -0.925 0.47) (xy 0.925 0.47) (xy 0.925 -0.47) (xy -0.925 -0.47)
			)
			(stroke
				(width 0.05)
				(type default)
			)
			(fill no)
			(layer "B.CrtYd")
		)
		(fp_poly
			(pts
				(xy -0.5 0.25) (xy 0.5 0.25) (xy 0.5 -0.25) (xy -0.5 -0.25)
			)
			(stroke
				(width 0.15)
				(type solid)
			)
			(fill no)
			(layer "B.Fab")
		)
		(fp_text user "License: Apache-2.0"
			(at -0.949999 -5.169 135)
			(layer "B.Fab")
			(effects
				(font
					(size 0.7 0.7)
					(thickness 0.15)
				)
				(justify left bottom mirror)
			)
		)
		(fp_text user "Author: Antmicro"
			(at -0.95 -4.169 135)
			(layer "B.Fab")
			(effects
				(font
					(size 0.7 0.7)
					(thickness 0.15)
				)
				(justify left bottom mirror)
			)
		)
		(fp_text user "${REFERENCE}"
			(at -0.95 -3.168 135)
			(layer "B.Fab")
			(effects
				(font
					(size 0.7 0.7)
					(thickness 0.15)
				)
				(justify left bottom mirror)
			)
		)
		(pad "1" smd roundrect
			(at -0.48 0 315)
			(size 0.59 0.64)
			(layers "B.Cu" "B.Mask" "B.Paste")
			(roundrect_rratio 0.25)
			(net 634 "Net-(U7-OUT5)")
			(pintype "passive")
		)
		(pad "2" smd roundrect
			(at 0.48 0 315)
			(size 0.59 0.64)
			(layers "B.Cu" "B.Mask" "B.Paste")
			(roundrect_rratio 0.25)
			(net 237 "1V8_CL")
			(pintype "passive")
		)
	)
	(footprint "antmicro-footprints:C_0402_1005Metric"
		(layer "B.Cu")
		(at 175.25 136.6 90)
		(descr "Capacitor SMD 0402")
		(tags "capacitor SMD 0402")
		(property "Reference" "C168"
			(at 1.425 1.375 270)
			(layer "B.SilkS")
			(effects
				(font
					(size 0.7 0.7)
					(thickness 0.15)
				)
				(justify left bottom mirror)
			)
		)
		(property "Value" "C_1u_0402"
			(at -1.022927 -2.155213 270)
			(layer "B.Fab")
			(hide yes)
			(effects
				(font
					(size 0.7 0.7)
					(thickness 0.15)
				)
				(justify left bottom mirror)
			)
		)
		(property "Datasheet" "https://product.tdk.com/en/search/capacitor/ceramic/mlcc/info?part_no=C1005X6S1A105K050BC"
			(at 0 0 90)
			(layer "F.Fab")
			(hide yes)
			(effects
				(font
					(size 1.27 1.27)
					(thickness 0.15)
				)
			)
		)
		(property "Description" "SMD Multilayer Ceramic Capacitor, 1 µF, 10 V, 0402 [1005 Metric], ± 10%, X6S, C"
			(at 0 0 90)
			(layer "F.Fab")
			(hide yes)
			(effects
				(font
					(size 1.27 1.27)
					(thickness 0.15)
				)
			)
		)
		(property "Author" "Antmicro"
			(at 311.85 -38.65 0)
			(layer "B.Fab")
			(hide yes)
			(effects
				(font
					(size 1 1)
					(thickness 0.15)
				)
				(justify mirror)
			)
		)
		(property "Dielectric" "X5R"
			(at 311.85 -38.65 0)
			(layer "B.Fab")
			(hide yes)
			(effects
				(font
					(size 1 1)
					(thickness 0.15)
				)
				(justify mirror)
			)
		)
		(property "License" "Apache-2.0"
			(at 311.85 -38.65 0)
			(layer "B.Fab")
			(hide yes)
			(effects
				(font
					(size 1 1)
					(thickness 0.15)
				)
				(justify mirror)
			)
		)
		(property "MPN" "C1005X6S1A105K050BC"
			(at 311.85 -38.65 0)
			(layer "B.Fab")
			(hide yes)
			(effects
				(font
					(size 1 1)
					(thickness 0.15)
				)
				(justify mirror)
			)
		)
		(property "Manufacturer" "TDK"
			(at 311.85 -38.65 0)
			(layer "B.Fab")
			(hide yes)
			(effects
				(font
					(size 1 1)
					(thickness 0.15)
				)
				(justify mirror)
			)
		)
		(property "Public" ""
			(at 311.85 -38.65 0)
			(layer "B.Fab")
			(hide yes)
			(effects
				(font
					(size 1 1)
					(thickness 0.15)
				)
				(justify mirror)
			)
		)
		(property "Val" "1u"
			(at 311.85 -38.65 0)
			(layer "B.Fab")
			(hide yes)
			(effects
				(font
					(size 1 1)
					(thickness 0.15)
				)
				(justify mirror)
			)
		)
		(property "Voltage" "16V"
			(at 311.85 -38.65 0)
			(layer "B.Fab")
			(hide yes)
			(effects
				(font
					(size 1 1)
					(thickness 0.15)
				)
				(justify mirror)
			)
		)
		(sheetname "/LPDDR4/")
		(sheetfile "lpddr.kicad_sch")
		(attr smd)
		(fp_rect
			(start -0.925 0.47)
			(end 0.925 -0.47)
			(stroke
				(width 0.05)
				(type default)
			)
			(fill no)
			(layer "B.CrtYd")
		)
		(fp_line
			(start 0.504 -0.248)
			(end -0.494 -0.248)
			(stroke
				(width 0.15)
				(type solid)
			)
			(layer "B.Fab")
		)
		(fp_line
			(start -0.494 -0.248)
			(end -0.494 0.25)
			(stroke
				(width 0.15)
				(type solid)
			)
			(layer "B.Fab")
		)
		(fp_line
			(start 0.504 0.25)
			(end 0.504 -0.248)
			(stroke
				(width 0.15)
				(type solid)
			)
			(layer "B.Fab")
		)
		(fp_line
			(start -0.494 0.25)
			(end 0.504 0.25)
			(stroke
				(width 0.15)
				(type solid)
			)
			(layer "B.Fab")
		)
		(fp_text user "Author: Antmicro"
			(at -0.939 -3.399 270)
			(layer "B.Fab")
			(effects
				(font
					(size 0.7 0.7)
					(thickness 0.15)
				)
				(justify left bottom mirror)
			)
		)
		(fp_text user "License: Apache-2.0"
			(at -0.939 -5.799 270)
			(layer "B.Fab")
			(effects
				(font
					(size 0.7 0.7)
					(thickness 0.15)
				)
				(justify left bottom mirror)
			)
		)
		(fp_text user "${REFERENCE}"
			(at -0.939 -4.599 270)
			(layer "B.Fab")
			(effects
				(font
					(size 0.7 0.7)
					(thickness 0.15)
				)
				(justify left bottom mirror)
			)
		)
		(pad "1" smd roundrect
			(at -0.48 0 90)
			(size 0.59 0.64)
			(layers "B.Cu" "B.Mask" "B.Paste")
			(roundrect_rratio 0.25)
			(net 417 "GND")
			(pintype "passive")
		)
		(pad "2" smd roundrect
			(at 0.48 0 90)
			(size 0.59 0.64)
			(layers "B.Cu" "B.Mask" "B.Paste")
			(roundrect_rratio 0.25)
			(net 2 "+1V1")
			(pintype "passive")
		)
	)
	(footprint "antmicro-footprints:C_0402_1005Metric"
		(layer "B.Cu")
		(at 193.776 129.1)
		(descr "Capacitor SMD 0402")
		(tags "capacitor SMD 0402")
		(property "Reference" "C13"
			(at -2.976 0.45 0)
			(layer "B.SilkS")
			(effects
				(font
					(size 0.7 0.7)
					(thickness 0.15)
				)
				(justify right bottom mirror)
			)
		)
		(property "Value" "C_10n_0402"
			(at -1.022927 -2.155213 0)
			(layer "B.Fab")
			(hide yes)
			(effects
				(font
					(size 0.7 0.7)
					(thickness 0.15)
				)
				(justify right bottom mirror)
			)
		)
		(property "Datasheet" "https://www.murata.com/products/productdetail?partno=GRM155R71H103KA88%23"
			(at 0 0 0)
			(layer "F.Fab")
			(hide yes)
			(effects
				(font
					(size 1.27 1.27)
					(thickness 0.15)
				)
			)
		)
		(property "Description" "SMD Multilayer Ceramic Capacitor, 10000 pF, 50 V, 0402 [1005 Metric], ± 10%, X7R, GRM Series"
			(at 0 0 0)
			(layer "F.Fab")
			(hide yes)
			(effects
				(font
					(size 1.27 1.27)
					(thickness 0.15)
				)
			)
		)
		(property "Author" "Antmicro"
			(at 0 0 0)
			(layer "B.Fab")
			(hide yes)
			(effects
				(font
					(size 1 1)
					(thickness 0.15)
				)
				(justify mirror)
			)
		)
		(property "Dielectric" "X7R"
			(at 0 0 0)
			(layer "B.Fab")
			(hide yes)
			(effects
				(font
					(size 1 1)
					(thickness 0.15)
				)
				(justify mirror)
			)
		)
		(property "License" "Apache-2.0"
			(at 0 0 0)
			(layer "B.Fab")
			(hide yes)
			(effects
				(font
					(size 1 1)
					(thickness 0.15)
				)
				(justify mirror)
			)
		)
		(property "MPN" "GRM155R71H103KA88D"
			(at 0 0 0)
			(layer "B.Fab")
			(hide yes)
			(effects
				(font
					(size 1 1)
					(thickness 0.15)
				)
				(justify mirror)
			)
		)
		(property "Manufacturer" "Murata"
			(at 0 0 0)
			(layer "B.Fab")
			(hide yes)
			(effects
				(font
					(size 1 1)
					(thickness 0.15)
				)
				(justify mirror)
			)
		)
		(property "Public" ""
			(at 0 0 0)
			(layer "B.Fab")
			(hide yes)
			(effects
				(font
					(size 1 1)
					(thickness 0.15)
				)
				(justify mirror)
			)
		)
		(property "Val" "10n"
			(at 0 0 0)
			(layer "B.Fab")
			(hide yes)
			(effects
				(font
					(size 1 1)
					(thickness 0.15)
				)
				(justify mirror)
			)
		)
		(property "Voltage" "50V"
			(at 0 0 0)
			(layer "B.Fab")
			(hide yes)
			(effects
				(font
					(size 1 1)
					(thickness 0.15)
				)
				(justify mirror)
			)
		)
		(sheetname "/FPGA Supply/")
		(sheetfile "fpga-supply.kicad_sch")
		(attr smd)
		(fp_rect
			(start -0.925 0.47)
			(end 0.925 -0.47)
			(stroke
				(width 0.05)
				(type default)
			)
			(fill no)
			(layer "B.CrtYd")
		)
		(fp_line
			(start -0.494 -0.248)
			(end -0.494 0.25)
			(stroke
				(width 0.15)
				(type solid)
			)
			(layer "B.Fab")
		)
		(fp_line
			(start -0.494 0.25)
			(end 0.504 0.25)
			(stroke
				(width 0.15)
				(type solid)
			)
			(layer "B.Fab")
		)
		(fp_line
			(start 0.504 -0.248)
			(end -0.494 -0.248)
			(stroke
				(width 0.15)
				(type solid)
			)
			(layer "B.Fab")
		)
		(fp_line
			(start 0.504 0.25)
			(end 0.504 -0.248)
			(stroke
				(width 0.15)
				(type solid)
			)
			(layer "B.Fab")
		)
		(fp_text user "${REFERENCE}"
			(at -0.939 -4.599 180)
			(layer "B.Fab")
			(effects
				(font
					(size 0.7 0.7)
					(thickness 0.15)
				)
				(justify left bottom mirror)
			)
		)
		(fp_text user "Author: Antmicro"
			(at -0.939 -3.399 180)
			(layer "B.Fab")
			(effects
				(font
					(size 0.7 0.7)
					(thickness 0.15)
				)
				(justify left bottom mirror)
			)
		)
		(fp_text user "License: Apache-2.0"
			(at -0.939 -5.799 180)
			(layer "B.Fab")
			(effects
				(font
					(size 0.7 0.7)
					(thickness 0.15)
				)
				(justify left bottom mirror)
			)
		)
		(pad "1" smd roundrect
			(at -0.48 0)
			(size 0.59 0.64)
			(layers "B.Cu" "B.Mask" "B.Paste")
			(roundrect_rratio 0.25)
			(net 417 "GND")
			(pintype "passive")
		)
		(pad "2" smd roundrect
			(at 0.48 0)
			(size 0.59 0.64)
			(layers "B.Cu" "B.Mask" "B.Paste")
			(roundrect_rratio 0.25)
			(net 2 "+1V1")
			(pintype "passive")
		)
	)
	(footprint "antmicro-footprints:C_0402_1005Metric"
		(layer "B.Cu")
		(at 208.25 136.35 180)
		(descr "Capacitor SMD 0402")
		(tags "capacitor SMD 0402")
		(property "Reference" "C125"
			(at 0.8 -0.4 0)
			(layer "B.SilkS")
			(effects
				(font
					(size 0.7 0.7)
					(thickness 0.15)
				)
				(justify left bottom mirror)
			)
		)
		(property "Value" "C_100n_0402"
			(at -1.022927 -2.155213 0)
			(layer "B.Fab")
			(hide yes)
			(effects
				(font
					(size 0.7 0.7)
					(thickness 0.15)
				)
				(justify left bottom mirror)
			)
		)
		(property "Datasheet" "https://www.murata.com/products/productdetail?partno=GRM155R61H104KE14%23"
			(at 0 0 180)
			(layer "F.Fab")
			(hide yes)
			(effects
				(font
					(size 1.27 1.27)
					(thickness 0.15)
				)
			)
		)
		(property "Description" "SMD Multilayer Ceramic Capacitor, 0.1 µF, 50 V, 0402 [1005 Metric], ± 10%, X5R, GRM Series"
			(at 0 0 180)
			(layer "F.Fab")
			(hide yes)
			(effects
				(font
					(size 1.27 1.27)
					(thickness 0.15)
				)
			)
		)
		(property "Author" "Antmicro"
			(at 416.5 272.7 0)
			(layer "B.Fab")
			(hide yes)
			(effects
				(font
					(size 1 1)
					(thickness 0.15)
				)
				(justify mirror)
			)
		)
		(property "Dielectric" "X5R"
			(at 416.5 272.7 0)
			(layer "B.Fab")
			(hide yes)
			(effects
				(font
					(size 1 1)
					(thickness 0.15)
				)
				(justify mirror)
			)
		)
		(property "License" "Apache-2.0"
			(at 416.5 272.7 0)
			(layer "B.Fab")
			(hide yes)
			(effects
				(font
					(size 1 1)
					(thickness 0.15)
				)
				(justify mirror)
			)
		)
		(property "MPN" "GRM155R61H104KE14D"
			(at 416.5 272.7 0)
			(layer "B.Fab")
			(hide yes)
			(effects
				(font
					(size 1 1)
					(thickness 0.15)
				)
				(justify mirror)
			)
		)
		(property "Manufacturer" "Murata"
			(at 416.5 272.7 0)
			(layer "B.Fab")
			(hide yes)
			(effects
				(font
					(size 1 1)
					(thickness 0.15)
				)
				(justify mirror)
			)
		)
		(property "Public" ""
			(at 416.5 272.7 0)
			(layer "B.Fab")
			(hide yes)
			(effects
				(font
					(size 1 1)
					(thickness 0.15)
				)
				(justify mirror)
			)
		)
		(property "Val" "100n"
			(at 416.5 272.7 0)
			(layer "B.Fab")
			(hide yes)
			(effects
				(font
					(size 1 1)
					(thickness 0.15)
				)
				(justify mirror)
			)
		)
		(property "Voltage" "50V"
			(at 416.5 272.7 0)
			(layer "B.Fab")
			(hide yes)
			(effects
				(font
					(size 1 1)
					(thickness 0.15)
				)
				(justify mirror)
			)
		)
		(sheetname "/FPGA GPIO/")
		(sheetfile "fpga-gpio.kicad_sch")
		(attr smd)
		(fp_rect
			(start -0.925 0.47)
			(end 0.925 -0.47)
			(stroke
				(width 0.05)
				(type default)
			)
			(fill no)
			(layer "B.CrtYd")
		)
		(fp_line
			(start 0.504 0.25)
			(end 0.504 -0.248)
			(stroke
				(width 0.15)
				(type solid)
			)
			(layer "B.Fab")
		)
		(fp_line
			(start 0.504 -0.248)
			(end -0.494 -0.248)
			(stroke
				(width 0.15)
				(type solid)
			)
			(layer "B.Fab")
		)
		(fp_line
			(start -0.494 0.25)
			(end 0.504 0.25)
			(stroke
				(width 0.15)
				(type solid)
			)
			(layer "B.Fab")
		)
		(fp_line
			(start -0.494 -0.248)
			(end -0.494 0.25)
			(stroke
				(width 0.15)
				(type solid)
			)
			(layer "B.Fab")
		)
		(fp_text user "Author: Antmicro"
			(at -0.939 -3.399 0)
			(layer "B.Fab")
			(effects
				(font
					(size 0.7 0.7)
					(thickness 0.15)
				)
				(justify left bottom mirror)
			)
		)
		(fp_text user "${REFERENCE}"
			(at -0.939 -4.599 0)
			(layer "B.Fab")
			(effects
				(font
					(size 0.7 0.7)
					(thickness 0.15)
				)
				(justify left bottom mirror)
			)
		)
		(fp_text user "License: Apache-2.0"
			(at -0.939 -5.799 0)
			(layer "B.Fab")
			(effects
				(font
					(size 0.7 0.7)
					(thickness 0.15)
				)
				(justify left bottom mirror)
			)
		)
		(pad "1" smd roundrect
			(at -0.48 0 180)
			(size 0.59 0.64)
			(layers "B.Cu" "B.Mask" "B.Paste")
			(roundrect_rratio 0.25)
			(net 50 "+3V3")
			(pintype "passive")
		)
		(pad "2" smd roundrect
			(at 0.48 0 180)
			(size 0.59 0.64)
			(layers "B.Cu" "B.Mask" "B.Paste")
			(roundrect_rratio 0.25)
			(net 417 "GND")
			(pintype "passive")
		)
	)
	(footprint "antmicro-footprints:TP_SMD_0.75mm"
		(layer "B.Cu")
		(at 176.45 142.95 180)
		(property "Reference" "TP7"
			(at -2.25 1.275 45)
			(layer "B.SilkS")
			(hide yes)
			(effects
				(font
					(size 0.7 0.7)
					(thickness 0.15)
				)
				(justify left bottom mirror)
			)
		)
		(property "Value" "TP_0.75mm_SMD"
			(at 0 -1.2 0)
			(layer "B.Fab")
			(hide yes)
			(effects
				(font
					(size 0.7 0.7)
					(thickness 0.15)
				)
				(justify left bottom mirror)
			)
		)
		(property "Description" "SMT test point"
			(at 0 0 0)
			(layer "B.Fab")
			(hide yes)
			(effects
				(font
					(size 1.27 1.27)
					(thickness 0.15)
				)
				(justify mirror)
			)
		)
		(property "MPN" ""
			(at 0 0 0)
			(unlocked yes)
			(layer "B.Fab")
			(hide yes)
			(effects
				(font
					(size 1 1)
					(thickness 0.15)
				)
				(justify mirror)
			)
		)
		(property "Manufacturer" ""
			(at 0 0 0)
			(unlocked yes)
			(layer "B.Fab")
			(hide yes)
			(effects
				(font
					(size 1 1)
					(thickness 0.15)
				)
				(justify mirror)
			)
		)
		(property "Author" "Antmicro"
			(at 0 0 0)
			(unlocked yes)
			(layer "B.Fab")
			(hide yes)
			(effects
				(font
					(size 1 1)
					(thickness 0.15)
				)
				(justify mirror)
			)
		)
		(property "License" "Apache-2.0"
			(at 0 0 0)
			(unlocked yes)
			(layer "B.Fab")
			(hide yes)
			(effects
				(font
					(size 1 1)
					(thickness 0.15)
				)
				(justify mirror)
			)
		)
		(property "Public" "False"
			(at 0 0 0)
			(unlocked yes)
			(layer "B.Fab")
			(hide yes)
			(effects
				(font
					(size 1 1)
					(thickness 0.15)
				)
				(justify mirror)
			)
		)
		(sheetname "/Supply/")
		(sheetfile "supply.kicad_sch")
		(attr exclude_from_pos_files exclude_from_bom)
		(fp_circle
			(center 0 0)
			(end 0.475 0)
			(stroke
				(width 0.05)
				(type default)
			)
			(fill no)
			(layer "B.CrtYd")
		)
		(fp_text user "License: Apache-2.0"
			(at -0.4 -5.101 0)
			(layer "B.Fab")
			(effects
				(font
					(size 0.7 0.7)
					(thickness 0.15)
				)
				(justify left bottom mirror)
			)
		)
		(fp_text user "Author: Antmicro"
			(at -0.4 -3.901 0)
			(layer "B.Fab")
			(effects
				(font
					(size 0.7 0.7)
					(thickness 0.15)
				)
				(justify left bottom mirror)
			)
		)
		(fp_text user "${REFERENCE}"
			(at -0.4 -2.7 0)
			(layer "B.Fab")
			(effects
				(font
					(size 0.7 0.7)
					(thickness 0.15)
				)
				(justify left bottom mirror)
			)
		)
		(pad "1" smd circle
			(at 0 0 180)
			(size 0.75 0.75)
			(layers "B.Cu" "B.Mask")
			(net 406 "/Supply/SENSE2_P")
			(pinfunction "1")
			(pintype "passive")
		)
	)
	(footprint "antmicro-footprints:SOT-886"
		(layer "B.Cu")
		(at 187.8 140.893 -90)
		(property "Reference" "U18"
			(at -3.218 -0.925 90)
			(layer "B.SilkS")
			(effects
				(font
					(size 0.7 0.7)
					(thickness 0.15)
				)
				(justify left bottom mirror)
			)
		)
		(property "Value" "74LVC1T45GM"
			(at -2.492 -1.647 90)
			(layer "B.Fab")
			(hide yes)
			(effects
				(font
					(size 0.7 0.7)
					(thickness 0.15)
				)
				(justify left bottom mirror)
			)
		)
		(property "Datasheet" "http://www.ti.com/general/docs/suppproductinfo.tsp?distId=10&gotoUrl=http%3A%2F%2Fwww.ti.com%2Flit%2Fgpn%2Fsn74lvc1t45"
			(at 0 0 270)
			(layer "F.Fab")
			(hide yes)
			(effects
				(font
					(size 1.27 1.27)
					(thickness 0.15)
				)
			)
		)
		(property "Description" "Transceiver, Translating, 74LVC1T45, 74LVC Family, 1.2V to 5.5V Supply, XSON-6"
			(at 0 0 270)
			(layer "F.Fab")
			(hide yes)
			(effects
				(font
					(size 1.27 1.27)
					(thickness 0.15)
				)
			)
		)
		(property "Author" "Antmicro"
			(at 46.907 328.693 0)
			(layer "B.Fab")
			(hide yes)
			(effects
				(font
					(size 1 1)
					(thickness 0.15)
				)
				(justify mirror)
			)
		)
		(property "License" "Apache-2.0"
			(at 46.907 328.693 0)
			(layer "B.Fab")
			(hide yes)
			(effects
				(font
					(size 1 1)
					(thickness 0.15)
				)
				(justify mirror)
			)
		)
		(property "MPN" "74LVC1T45GM-Q100X"
			(at 46.907 328.693 0)
			(layer "B.Fab")
			(hide yes)
			(effects
				(font
					(size 1 1)
					(thickness 0.15)
				)
				(justify mirror)
			)
		)
		(property "Manufacturer" "Nexperia"
			(at 46.907 328.693 0)
			(layer "B.Fab")
			(hide yes)
			(effects
				(font
					(size 1 1)
					(thickness 0.15)
				)
				(justify mirror)
			)
		)
		(sheetname "/FPGA GPIO/")
		(sheetfile "fpga-gpio.kicad_sch")
		(attr smd)
		(fp_line
			(start -0.843 0.491)
			(end -0.843 -0.183)
			(stroke
				(width 0.15)
				(type solid)
			)
			(layer "B.SilkS")
		)
		(fp_line
			(start 0.858 0.491)
			(end 0.858 -0.509)
			(stroke
				(width 0.15)
				(type solid)
			)
			(layer "B.SilkS")
		)
		(fp_circle
			(center -0.493 -0.847)
			(end -0.443 -0.847)
			(stroke
				(width 0.15)
				(type solid)
			)
			(fill yes)
			(layer "B.SilkS")
		)
		(fp_rect
			(start -1.23 1)
			(end 1.22 -0.99)
			(stroke
				(width 0.05)
				(type solid)
			)
			(fill no)
			(layer "B.CrtYd")
		)
		(fp_line
			(start -0.843 0.616)
			(end 0.858 0.616)
			(stroke
				(width 0.15)
				(type solid)
			)
			(layer "B.Fab")
		)
		(fp_line
			(start -0.843 0.616)
			(end -0.843 -0.634)
			(stroke
				(width 0.15)
				(type solid)
			)
			(layer "B.Fab")
		)
		(fp_line
			(start 0.858 0.616)
			(end 0.858 -0.634)
			(stroke
				(width 0.15)
				(type solid)
			)
			(layer "B.Fab")
		)
		(fp_line
			(start -0.843 -0.434)
			(end -0.644 -0.634)
			(stroke
				(width 0.15)
				(type solid)
			)
			(layer "B.Fab")
		)
		(fp_line
			(start 0.858 -0.634)
			(end -0.843 -0.634)
			(stroke
				(width 0.15)
				(type solid)
			)
			(layer "B.Fab")
		)
		(fp_text user "Author: Antmicro"
			(at -2.492 -4.847 90)
			(layer "B.Fab")
			(effects
				(font
					(size 0.7 0.7)
					(thickness 0.15)
				)
				(justify left bottom mirror)
			)
		)
		(fp_text user "${REFERENCE}"
			(at -2.492 -3.647 90)
			(layer "B.Fab")
			(effects
				(font
					(size 0.7 0.7)
					(thickness 0.15)
				)
				(justify left bottom mirror)
			)
		)
		(fp_text user "License: Apache-2.0"
			(at -2.492 -6.047 90)
			(layer "B.Fab")
			(effects
				(font
					(size 0.7 0.7)
					(thickness 0.15)
				)
				(justify left bottom mirror)
			)
		)
		(pad "1" smd rect
			(at -0.493 -0.347 270)
			(size 0.27 0.325)
			(layers "B.Cu" "B.Mask" "B.Paste")
			(net 649 "VDD")
			(pinfunction "VCCA")
			(pintype "power_in")
			(solder_mask_margin 0.05)
		)
		(pad "2" smd rect
			(at 0.005 -0.347 270)
			(size 0.27 0.325)
			(layers "B.Cu" "B.Mask" "B.Paste")
			(net 417 "GND")
			(pinfunction "GND")
			(pintype "power_in")
			(solder_mask_margin 0.05)
		)
		(pad "3" smd rect
			(at 0.505 -0.347 270)
			(size 0.27 0.325)
			(layers "B.Cu" "B.Mask" "B.Paste")
			(net 356 "/FPGA GPIO/HDMI0_HPD_SRC")
			(pinfunction "A")
			(pintype "bidirectional")
			(solder_mask_margin 0.05)
		)
		(pad "4" smd rect
			(at 0.505 0.33 90)
			(size 0.27 0.325)
			(layers "B.Cu" "B.Mask" "B.Paste")
			(net 505 "PI3HDX511F_HOTPLUG")
			(pinfunction "B")
			(pintype "bidirectional")
			(solder_mask_margin 0.05)
		)
		(pad "5" smd rect
			(at 0.005 0.33 90)
			(size 0.27 0.325)
			(layers "B.Cu" "B.Mask" "B.Paste")
			(net 417 "GND")
			(pinfunction "DIR")
			(pintype "input")
			(solder_mask_margin 0.05)
		)
		(pad "6" smd rect
			(at -0.493 0.33 90)
			(size 0.27 0.325)
			(layers "B.Cu" "B.Mask" "B.Paste")
			(net 50 "+3V3")
			(pinfunction "VCCB")
			(pintype "power_in")
			(solder_mask_margin 0.05)
		)
	)
	(footprint "antmicro-footprints:R_0402_1005Metric"
		(layer "B.Cu")
		(at 184.35 122.45)
		(descr "Resistor SMD 0402")
		(tags "resistor SMD 0402")
		(property "Reference" "R76"
			(at 2.975 0.25 180)
			(layer "B.SilkS")
			(effects
				(font
					(size 0.7 0.7)
					(thickness 0.15)
				)
				(justify left bottom mirror)
			)
		)
		(property "Value" "R_240R_0402"
			(at -1.011843 -1.772047 180)
			(layer "B.Fab")
			(hide yes)
			(effects
				(font
					(size 0.7 0.7)
					(thickness 0.15)
				)
				(justify left bottom mirror)
			)
		)
		(property "Datasheet" "https://www.bourns.com/docs/product-datasheets/cr.pdf"
			(at 0 0 0)
			(layer "F.Fab")
			(hide yes)
			(effects
				(font
					(size 1.27 1.27)
					(thickness 0.15)
				)
			)
		)
		(property "Description" "SMD Chip Resistor, 240 ohm, ± 1%, 63 mW, 0402 [1005 Metric], Thick Film, General Purpose"
			(at 0 0 0)
			(layer "F.Fab")
			(hide yes)
			(effects
				(font
					(size 1.27 1.27)
					(thickness 0.15)
				)
			)
		)
		(property "Author" "Antmicro"
			(at 0 0 0)
			(layer "B.Fab")
			(hide yes)
			(effects
				(font
					(size 1 1)
					(thickness 0.15)
				)
				(justify mirror)
			)
		)
		(property "License" "Apache-2.0"
			(at 0 0 0)
			(layer "B.Fab")
			(hide yes)
			(effects
				(font
					(size 1 1)
					(thickness 0.15)
				)
				(justify mirror)
			)
		)
		(property "MPN" "CR0402-FX-2400GLF"
			(at 0 0 0)
			(layer "B.Fab")
			(hide yes)
			(effects
				(font
					(size 1 1)
					(thickness 0.15)
				)
				(justify mirror)
			)
		)
		(property "Manufacturer" "Bourns"
			(at 0 0 0)
			(layer "B.Fab")
			(hide yes)
			(effects
				(font
					(size 1 1)
					(thickness 0.15)
				)
				(justify mirror)
			)
		)
		(property "Public" ""
			(at 0 0 0)
			(layer "B.Fab")
			(hide yes)
			(effects
				(font
					(size 1 1)
					(thickness 0.15)
				)
				(justify mirror)
			)
		)
		(property "Tolerance" "1%"
			(at 0 0 0)
			(layer "B.Fab")
			(hide yes)
			(effects
				(font
					(size 1 1)
					(thickness 0.15)
				)
				(justify mirror)
			)
		)
		(property "Val" "240R"
			(at 0 0 0)
			(layer "B.Fab")
			(hide yes)
			(effects
				(font
					(size 1 1)
					(thickness 0.15)
				)
				(justify mirror)
			)
		)
		(sheetname "/LPDDR4/")
		(sheetfile "lpddr.kicad_sch")
		(attr smd)
		(fp_rect
			(start -0.925 0.47)
			(end 0.925 -0.47)
			(stroke
				(width 0.05)
				(type default)
			)
			(fill no)
			(layer "B.CrtYd")
		)
		(fp_rect
			(start -0.5 0.25)
			(end 0.5 -0.25)
			(stroke
				(width 0.15)
				(type solid)
			)
			(fill no)
			(layer "B.Fab")
		)
		(fp_text user "Author: Antmicro"
			(at -0.95 -4.169 180)
			(layer "B.Fab")
			(effects
				(font
					(size 0.7 0.7)
					(thickness 0.15)
				)
				(justify left bottom mirror)
			)
		)
		(fp_text user "License: Apache-2.0"
			(at -0.95 -5.169 180)
			(layer "B.Fab")
			(effects
				(font
					(size 0.7 0.7)
					(thickness 0.15)
				)
				(justify left bottom mirror)
			)
		)
		(fp_text user "${REFERENCE}"
			(at -0.95 -3.168 180)
			(layer "B.Fab")
			(effects
				(font
					(size 0.7 0.7)
					(thickness 0.15)
				)
				(justify left bottom mirror)
			)
		)
		(pad "1" smd roundrect
			(at -0.48 0)
			(size 0.59 0.64)
			(layers "B.Cu" "B.Mask" "B.Paste")
			(roundrect_rratio 0.25)
			(net 271 "Net-(U12A-ZQ0)")
			(pintype "passive")
		)
		(pad "2" smd roundrect
			(at 0.48 0)
			(size 0.59 0.64)
			(layers "B.Cu" "B.Mask" "B.Paste")
			(roundrect_rratio 0.25)
			(net 2 "+1V1")
			(pintype "passive")
		)
	)
	(footprint "antmicro-footprints:SOT-523"
		(layer "B.Cu")
		(at 222.08 129.9 180)
		(property "Reference" "Q5"
			(at 0.23 0.3 180)
			(layer "B.SilkS")
			(effects
				(font
					(size 0.7 0.7)
					(thickness 0.15)
				)
				(justify left bottom mirror)
			)
		)
		(property "Value" "DMG1012T-7"
			(at 0.1 -1.824 0)
			(layer "B.Fab")
			(hide yes)
			(effects
				(font
					(size 0.7 0.7)
					(thickness 0.15)
				)
				(justify left bottom mirror)
			)
		)
		(property "Datasheet" "https://www.diodes.com/assets/Datasheets/ds31783.pdf"
			(at 0 0 180)
			(layer "F.Fab")
			(hide yes)
			(effects
				(font
					(size 1.27 1.27)
					(thickness 0.15)
				)
			)
		)
		(property "Description" "Power MOSFET, N Channel, 20 V, 630 mA, 0.3 ohm, SOT-523, Surface Mount"
			(at 0 0 180)
			(layer "F.Fab")
			(hide yes)
			(effects
				(font
					(size 1.27 1.27)
					(thickness 0.15)
				)
			)
		)
		(property "Author" "Antmicro"
			(at 444.16 259.8 0)
			(layer "B.Fab")
			(hide yes)
			(effects
				(font
					(size 1 1)
					(thickness 0.15)
				)
				(justify mirror)
			)
		)
		(property "License" "Apache-2.0"
			(at 444.16 259.8 0)
			(layer "B.Fab")
			(hide yes)
			(effects
				(font
					(size 1 1)
					(thickness 0.15)
				)
				(justify mirror)
			)
		)
		(property "MPN" "DMG1012T-7"
			(at 444.16 259.8 0)
			(layer "B.Fab")
			(hide yes)
			(effects
				(font
					(size 1 1)
					(thickness 0.15)
				)
				(justify mirror)
			)
		)
		(property "Manufacturer" "Diodes Incorporated"
			(at 444.16 259.8 0)
			(layer "B.Fab")
			(hide yes)
			(effects
				(font
					(size 1 1)
					(thickness 0.15)
				)
				(justify mirror)
			)
		)
		(property "Public" ""
			(at 444.16 259.8 0)
			(layer "B.Fab")
			(hide yes)
			(effects
				(font
					(size 1 1)
					(thickness 0.15)
				)
				(justify mirror)
			)
		)
		(sheetname "/FPGA GPIO/")
		(sheetfile "fpga-gpio.kicad_sch")
		(attr smd)
		(fp_line
			(start -0.277 0.551)
			(end -0.277 0.75)
			(stroke
				(width 0.15)
				(type solid)
			)
			(layer "B.SilkS")
		)
		(fp_line
			(start -0.725 0.551)
			(end -0.277 0.551)
			(stroke
				(width 0.15)
				(type solid)
			)
			(layer "B.SilkS")
		)
		(fp_line
			(start -0.927 0.351)
			(end -0.725 0.551)
			(stroke
				(width 0.15)
				(type solid)
			)
			(layer "B.SilkS")
		)
		(fp_line
			(start -0.927 0.051)
			(end -0.927 0.351)
			(stroke
				(width 0.15)
				(type solid)
			)
			(layer "B.SilkS")
		)
		(fp_circle
			(center -0.9652 -0.9652)
			(end -0.9152 -0.9652)
			(stroke
				(width 0.15)
				(type solid)
			)
			(fill yes)
			(layer "B.SilkS")
		)
		(fp_line
			(start 1.1 1.16)
			(end 1.1 -1.15)
			(stroke
				(width 0.05)
				(type solid)
			)
			(layer "B.CrtYd")
		)
		(fp_line
			(start -1.12 1.16)
			(end 1.1 1.16)
			(stroke
				(width 0.05)
				(type solid)
			)
			(layer "B.CrtYd")
		)
		(fp_line
			(start -1.12 1.16)
			(end -1.12 -1.15)
			(stroke
				(width 0.05)
				(type solid)
			)
			(layer "B.CrtYd")
		)
		(fp_line
			(start -1.12 -1.15)
			(end 1.1 -1.15)
			(stroke
				(width 0.05)
				(type solid)
			)
			(layer "B.CrtYd")
		)
		(fp_line
			(start 0.8 0.425)
			(end 0.8 -0.424)
			(stroke
				(width 0.15)
				(type solid)
			)
			(layer "B.Fab")
		)
		(fp_line
			(start 0.8 0.425)
			(end -0.652 0.425)
			(stroke
				(width 0.15)
				(type solid)
			)
			(layer "B.Fab")
		)
		(fp_line
			(start 0.8 -0.424)
			(end -0.802 -0.424)
			(stroke
				(width 0.15)
				(type solid)
			)
			(layer "B.Fab")
		)
		(fp_line
			(start -0.652 0.425)
			(end -0.802 0.276)
			(stroke
				(width 0.15)
				(type solid)
			)
			(layer "B.Fab")
		)
		(fp_line
			(start -0.802 0.276)
			(end -0.802 -0.424)
			(stroke
				(width 0.15)
				(type solid)
			)
			(layer "B.Fab")
		)
		(fp_circle
			(center -0.9652 -0.9652)
			(end -0.9144 -0.9652)
			(stroke
				(width 0.15)
				(type solid)
			)
			(fill no)
			(layer "B.Fab")
		)
		(fp_text user "${REFERENCE}"
			(at -1.12 -3.824 0)
			(layer "B.Fab")
			(effects
				(font
					(size 0.7 0.7)
					(thickness 0.15)
				)
				(justify left bottom mirror)
			)
		)
		(fp_text user "Author: Antmicro"
			(at -1.12 -6.224 0)
			(layer "B.Fab")
			(effects
				(font
					(size 0.7 0.7)
					(thickness 0.15)
				)
				(justify left bottom mirror)
			)
		)
		(fp_text user "License: Apache-2.0"
			(at -1.12 -5.024 0)
			(layer "B.Fab")
			(effects
				(font
					(size 0.7 0.7)
					(thickness 0.15)
				)
				(justify left bottom mirror)
			)
		)
		(pad "1" smd rect
			(at -0.5 -0.65 180)
			(size 0.4 0.51)
			(layers "B.Cu" "B.Mask" "B.Paste")
			(net 224 "/FPGA GPIO/USER_LED_B")
			(pinfunction "G")
			(pintype "input")
		)
		(pad "2" smd rect
			(at 0.498 -0.65 180)
			(size 0.4 0.51)
			(layers "B.Cu" "B.Mask" "B.Paste")
			(net 417 "GND")
			(pinfunction "S")
			(pintype "passive")
		)
		(pad "3" smd rect
			(at 0 0.652 180)
			(size 0.4 0.51)
			(layers "B.Cu" "B.Mask" "B.Paste")
			(net 540 "Net-(Q5-D)")
			(pinfunction "D")
			(pintype "passive")
		)
	)
	(footprint "antmicro-footprints:C_0402_1005Metric"
		(layer "B.Cu")
		(at 215.1925 129.668 180)
		(descr "Capacitor SMD 0402")
		(tags "capacitor SMD 0402")
		(property "Reference" "C79"
			(at -3.0475 -0.472 0)
			(layer "B.SilkS")
			(effects
				(font
					(size 0.7 0.7)
					(thickness 0.15)
				)
				(justify left bottom mirror)
			)
		)
		(property "Value" "C_100n_0402"
			(at -1.022927 -2.155213 0)
			(layer "B.Fab")
			(hide yes)
			(effects
				(font
					(size 0.7 0.7)
					(thickness 0.15)
				)
				(justify left bottom mirror)
			)
		)
		(property "Datasheet" "https://www.murata.com/products/productdetail?partno=GRM155R61H104KE14%23"
			(at 0 0 180)
			(layer "F.Fab")
			(hide yes)
			(effects
				(font
					(size 1.27 1.27)
					(thickness 0.15)
				)
			)
		)
		(property "Description" "SMD Multilayer Ceramic Capacitor, 0.1 µF, 50 V, 0402 [1005 Metric], ± 10%, X5R, GRM Series"
			(at 0 0 180)
			(layer "F.Fab")
			(hide yes)
			(effects
				(font
					(size 1.27 1.27)
					(thickness 0.15)
				)
			)
		)
		(property "Author" "Antmicro"
			(at 430.385 259.336 0)
			(layer "B.Fab")
			(hide yes)
			(effects
				(font
					(size 1 1)
					(thickness 0.15)
				)
				(justify mirror)
			)
		)
		(property "Dielectric" "X5R"
			(at 430.385 259.336 0)
			(layer "B.Fab")
			(hide yes)
			(effects
				(font
					(size 1 1)
					(thickness 0.15)
				)
				(justify mirror)
			)
		)
		(property "License" "Apache-2.0"
			(at 430.385 259.336 0)
			(layer "B.Fab")
			(hide yes)
			(effects
				(font
					(size 1 1)
					(thickness 0.15)
				)
				(justify mirror)
			)
		)
		(property "MPN" "GRM155R61H104KE14D"
			(at 430.385 259.336 0)
			(layer "B.Fab")
			(hide yes)
			(effects
				(font
					(size 1 1)
					(thickness 0.15)
				)
				(justify mirror)
			)
		)
		(property "Manufacturer" "Murata"
			(at 430.385 259.336 0)
			(layer "B.Fab")
			(hide yes)
			(effects
				(font
					(size 1 1)
					(thickness 0.15)
				)
				(justify mirror)
			)
		)
		(property "Public" ""
			(at 430.385 259.336 0)
			(layer "B.Fab")
			(hide yes)
			(effects
				(font
					(size 1 1)
					(thickness 0.15)
				)
				(justify mirror)
			)
		)
		(property "Val" "100n"
			(at 430.385 259.336 0)
			(layer "B.Fab")
			(hide yes)
			(effects
				(font
					(size 1 1)
					(thickness 0.15)
				)
				(justify mirror)
			)
		)
		(property "Voltage" "50V"
			(at 430.385 259.336 0)
			(layer "B.Fab")
			(hide yes)
			(effects
				(font
					(size 1 1)
					(thickness 0.15)
				)
				(justify mirror)
			)
		)
		(sheetname "/Memory/")
		(sheetfile "memory.kicad_sch")
		(attr smd)
		(fp_rect
			(start -0.925 0.47)
			(end 0.925 -0.47)
			(stroke
				(width 0.05)
				(type default)
			)
			(fill no)
			(layer "B.CrtYd")
		)
		(fp_line
			(start 0.504 0.25)
			(end 0.504 -0.248)
			(stroke
				(width 0.15)
				(type solid)
			)
			(layer "B.Fab")
		)
		(fp_line
			(start 0.504 -0.248)
			(end -0.494 -0.248)
			(stroke
				(width 0.15)
				(type solid)
			)
			(layer "B.Fab")
		)
		(fp_line
			(start -0.494 0.25)
			(end 0.504 0.25)
			(stroke
				(width 0.15)
				(type solid)
			)
			(layer "B.Fab")
		)
		(fp_line
			(start -0.494 -0.248)
			(end -0.494 0.25)
			(stroke
				(width 0.15)
				(type solid)
			)
			(layer "B.Fab")
		)
		(fp_text user "Author: Antmicro"
			(at -0.939 -3.399 0)
			(layer "B.Fab")
			(effects
				(font
					(size 0.7 0.7)
					(thickness 0.15)
				)
				(justify left bottom mirror)
			)
		)
		(fp_text user "${REFERENCE}"
			(at -0.939 -4.599 0)
			(layer "B.Fab")
			(effects
				(font
					(size 0.7 0.7)
					(thickness 0.15)
				)
				(justify left bottom mirror)
			)
		)
		(fp_text user "License: Apache-2.0"
			(at -0.939 -5.799 0)
			(layer "B.Fab")
			(effects
				(font
					(size 0.7 0.7)
					(thickness 0.15)
				)
				(justify left bottom mirror)
			)
		)
		(pad "1" smd roundrect
			(at -0.48 0 180)
			(size 0.59 0.64)
			(layers "B.Cu" "B.Mask" "B.Paste")
			(roundrect_rratio 0.25)
			(net 417 "GND")
			(pintype "passive")
		)
		(pad "2" smd roundrect
			(at 0.48 0 180)
			(size 0.59 0.64)
			(layers "B.Cu" "B.Mask" "B.Paste")
			(roundrect_rratio 0.25)
			(net 137 "SD_VDD")
			(pintype "passive")
		)
	)
	(footprint "antmicro-footprints:R_0402_1005Metric"
		(layer "B.Cu")
		(at 218.975 134.775)
		(descr "Resistor SMD 0402")
		(tags "resistor SMD 0402")
		(property "Reference" "R10"
			(at -0.775 0.45 180)
			(layer "B.SilkS")
			(effects
				(font
					(size 0.7 0.7)
					(thickness 0.15)
				)
				(justify left bottom mirror)
			)
		)
		(property "Value" "R_10k_0402"
			(at -1.011843 -1.772047 180)
			(layer "B.Fab")
			(hide yes)
			(effects
				(font
					(size 0.7 0.7)
					(thickness 0.15)
				)
				(justify left bottom mirror)
			)
		)
		(property "Datasheet" "https://www.bourns.com/docs/product-datasheets/cr.pdf"
			(at 0 0 0)
			(layer "F.Fab")
			(hide yes)
			(effects
				(font
					(size 1.27 1.27)
					(thickness 0.15)
				)
			)
		)
		(property "Description" "SMD Chip Resistor, 10 kohm, ± 1%, 62.5 mW, 0402 [1005 Metric], Thick Film, General Purpose"
			(at 0 0 0)
			(layer "F.Fab")
			(hide yes)
			(effects
				(font
					(size 1.27 1.27)
					(thickness 0.15)
				)
			)
		)
		(property "Author" "Antmicro"
			(at 0 0 0)
			(layer "B.Fab")
			(hide yes)
			(effects
				(font
					(size 1 1)
					(thickness 0.15)
				)
				(justify mirror)
			)
		)
		(property "License" "Apache-2.0"
			(at 0 0 0)
			(layer "B.Fab")
			(hide yes)
			(effects
				(font
					(size 1 1)
					(thickness 0.15)
				)
				(justify mirror)
			)
		)
		(property "MPN" "CR0402-FX-1002GLF"
			(at 0 0 0)
			(layer "B.Fab")
			(hide yes)
			(effects
				(font
					(size 1 1)
					(thickness 0.15)
				)
				(justify mirror)
			)
		)
		(property "Manufacturer" "Bourns"
			(at 0 0 0)
			(layer "B.Fab")
			(hide yes)
			(effects
				(font
					(size 1 1)
					(thickness 0.15)
				)
				(justify mirror)
			)
		)
		(property "Public" ""
			(at 0 0 0)
			(layer "B.Fab")
			(hide yes)
			(effects
				(font
					(size 1 1)
					(thickness 0.15)
				)
				(justify mirror)
			)
		)
		(property "Tolerance" "1%"
			(at 0 0 0)
			(layer "B.Fab")
			(hide yes)
			(effects
				(font
					(size 1 1)
					(thickness 0.15)
				)
				(justify mirror)
			)
		)
		(property "Val" "10k"
			(at 0 0 0)
			(layer "B.Fab")
			(hide yes)
			(effects
				(font
					(size 1 1)
					(thickness 0.15)
				)
				(justify mirror)
			)
		)
		(sheetname "/Supply/")
		(sheetfile "supply.kicad_sch")
		(attr smd)
		(fp_rect
			(start -0.925 0.47)
			(end 0.925 -0.47)
			(stroke
				(width 0.05)
				(type default)
			)
			(fill no)
			(layer "B.CrtYd")
		)
		(fp_rect
			(start -0.5 0.25)
			(end 0.5 -0.25)
			(stroke
				(width 0.15)
				(type solid)
			)
			(fill no)
			(layer "B.Fab")
		)
		(fp_text user "License: Apache-2.0"
			(at -0.95 -5.169 180)
			(layer "B.Fab")
			(effects
				(font
					(size 0.7 0.7)
					(thickness 0.15)
				)
				(justify left bottom mirror)
			)
		)
		(fp_text user "${REFERENCE}"
			(at -0.95 -3.168 180)
			(layer "B.Fab")
			(effects
				(font
					(size 0.7 0.7)
					(thickness 0.15)
				)
				(justify left bottom mirror)
			)
		)
		(fp_text user "Author: Antmicro"
			(at -0.95 -4.169 180)
			(layer "B.Fab")
			(effects
				(font
					(size 0.7 0.7)
					(thickness 0.15)
				)
				(justify left bottom mirror)
			)
		)
		(pad "1" smd roundrect
			(at -0.48 0)
			(size 0.59 0.64)
			(layers "B.Cu" "B.Mask" "B.Paste")
			(roundrect_rratio 0.25)
			(net 334 "VREF_FLAG")
			(pintype "passive")
		)
		(pad "2" smd roundrect
			(at 0.48 0)
			(size 0.59 0.64)
			(layers "B.Cu" "B.Mask" "B.Paste")
			(roundrect_rratio 0.25)
			(net 296 "Net-(R10-Pad2)")
			(pintype "passive")
		)
	)
	(footprint "antmicro-footprints:C_0402_1005Metric"
		(layer "B.Cu")
		(at 219.9 122.8)
		(descr "Capacitor SMD 0402")
		(tags "capacitor SMD 0402")
		(property "Reference" "C195"
			(at 6.55 3.85 0)
			(layer "B.SilkS")
			(effects
				(font
					(size 0.7 0.7)
					(thickness 0.15)
				)
				(justify right bottom mirror)
			)
		)
		(property "Value" "C_10n_0402"
			(at -1.022927 -2.155213 0)
			(layer "B.Fab")
			(hide yes)
			(effects
				(font
					(size 0.7 0.7)
					(thickness 0.15)
				)
				(justify right bottom mirror)
			)
		)
		(property "Datasheet" "https://www.murata.com/products/productdetail?partno=GRM155R71H103KA88%23"
			(at 0 0 0)
			(layer "F.Fab")
			(hide yes)
			(effects
				(font
					(size 1.27 1.27)
					(thickness 0.15)
				)
			)
		)
		(property "Description" "SMD Multilayer Ceramic Capacitor, 10000 pF, 50 V, 0402 [1005 Metric], ± 10%, X7R, GRM Series"
			(at 0 0 0)
			(layer "F.Fab")
			(hide yes)
			(effects
				(font
					(size 1.27 1.27)
					(thickness 0.15)
				)
			)
		)
		(property "Author" "Antmicro"
			(at 0 0 0)
			(layer "B.Fab")
			(hide yes)
			(effects
				(font
					(size 1 1)
					(thickness 0.15)
				)
				(justify mirror)
			)
		)
		(property "Dielectric" "X7R"
			(at 0 0 0)
			(layer "B.Fab")
			(hide yes)
			(effects
				(font
					(size 1 1)
					(thickness 0.15)
				)
				(justify mirror)
			)
		)
		(property "License" "Apache-2.0"
			(at 0 0 0)
			(layer "B.Fab")
			(hide yes)
			(effects
				(font
					(size 1 1)
					(thickness 0.15)
				)
				(justify mirror)
			)
		)
		(property "MPN" "GRM155R71H103KA88D"
			(at 0 0 0)
			(layer "B.Fab")
			(hide yes)
			(effects
				(font
					(size 1 1)
					(thickness 0.15)
				)
				(justify mirror)
			)
		)
		(property "Manufacturer" "Murata"
			(at 0 0 0)
			(layer "B.Fab")
			(hide yes)
			(effects
				(font
					(size 1 1)
					(thickness 0.15)
				)
				(justify mirror)
			)
		)
		(property "Public" ""
			(at 0 0 0)
			(layer "B.Fab")
			(hide yes)
			(effects
				(font
					(size 1 1)
					(thickness 0.15)
				)
				(justify mirror)
			)
		)
		(property "Val" "10n"
			(at 0 0 0)
			(layer "B.Fab")
			(hide yes)
			(effects
				(font
					(size 1 1)
					(thickness 0.15)
				)
				(justify mirror)
			)
		)
		(property "Voltage" "50V"
			(at 0 0 0)
			(layer "B.Fab")
			(hide yes)
			(effects
				(font
					(size 1 1)
					(thickness 0.15)
				)
				(justify mirror)
			)
		)
		(sheetname "/Ethernet/")
		(sheetfile "ethernet.kicad_sch")
		(attr smd)
		(fp_rect
			(start -0.925 0.47)
			(end 0.925 -0.47)
			(stroke
				(width 0.05)
				(type default)
			)
			(fill no)
			(layer "B.CrtYd")
		)
		(fp_line
			(start -0.494 -0.248)
			(end -0.494 0.25)
			(stroke
				(width 0.15)
				(type solid)
			)
			(layer "B.Fab")
		)
		(fp_line
			(start -0.494 0.25)
			(end 0.504 0.25)
			(stroke
				(width 0.15)
				(type solid)
			)
			(layer "B.Fab")
		)
		(fp_line
			(start 0.504 -0.248)
			(end -0.494 -0.248)
			(stroke
				(width 0.15)
				(type solid)
			)
			(layer "B.Fab")
		)
		(fp_line
			(start 0.504 0.25)
			(end 0.504 -0.248)
			(stroke
				(width 0.15)
				(type solid)
			)
			(layer "B.Fab")
		)
		(fp_text user "License: Apache-2.0"
			(at -0.939 -5.799 180)
			(layer "B.Fab")
			(effects
				(font
					(size 0.7 0.7)
					(thickness 0.15)
				)
				(justify left bottom mirror)
			)
		)
		(fp_text user "Author: Antmicro"
			(at -0.939 -3.399 180)
			(layer "B.Fab")
			(effects
				(font
					(size 0.7 0.7)
					(thickness 0.15)
				)
				(justify left bottom mirror)
			)
		)
		(fp_text user "${REFERENCE}"
			(at -0.939 -4.599 180)
			(layer "B.Fab")
			(effects
				(font
					(size 0.7 0.7)
					(thickness 0.15)
				)
				(justify left bottom mirror)
			)
		)
		(pad "1" smd roundrect
			(at -0.48 0)
			(size 0.59 0.64)
			(layers "B.Cu" "B.Mask" "B.Paste")
			(roundrect_rratio 0.25)
			(net 417 "GND")
			(pintype "passive")
		)
		(pad "2" smd roundrect
			(at 0.48 0)
			(size 0.59 0.64)
			(layers "B.Cu" "B.Mask" "B.Paste")
			(roundrect_rratio 0.25)
			(net 418 "+2V5")
			(pintype "passive")
		)
	)
	(footprint "antmicro-footprints:C_0402_1005Metric"
		(layer "B.Cu")
		(at 219.6 150.05 90)
		(descr "Capacitor SMD 0402")
		(tags "capacitor SMD 0402")
		(property "Reference" "C229"
			(at -1.99 1.37 90)
			(layer "B.SilkS")
			(effects
				(font
					(size 0.7 0.7)
					(thickness 0.15)
				)
				(justify right bottom mirror)
			)
		)
		(property "Value" "C_100n_0402"
			(at -1.022927 -2.155213 90)
			(layer "B.Fab")
			(hide yes)
			(effects
				(font
					(size 0.7 0.7)
					(thickness 0.15)
				)
				(justify right bottom mirror)
			)
		)
		(property "Datasheet" "https://www.murata.com/products/productdetail?partno=GRM155R61H104KE14%23"
			(at 0 0 90)
			(layer "F.Fab")
			(hide yes)
			(effects
				(font
					(size 1.27 1.27)
					(thickness 0.15)
				)
			)
		)
		(property "Description" "SMD Multilayer Ceramic Capacitor, 0.1 µF, 50 V, 0402 [1005 Metric], ± 10%, X5R, GRM Series"
			(at 0 0 90)
			(layer "F.Fab")
			(hide yes)
			(effects
				(font
					(size 1.27 1.27)
					(thickness 0.15)
				)
			)
		)
		(property "Author" "Antmicro"
			(at 369.65 -69.55 0)
			(layer "B.Fab")
			(hide yes)
			(effects
				(font
					(size 1 1)
					(thickness 0.15)
				)
				(justify mirror)
			)
		)
		(property "Dielectric" "X5R"
			(at 369.65 -69.55 0)
			(layer "B.Fab")
			(hide yes)
			(effects
				(font
					(size 1 1)
					(thickness 0.15)
				)
				(justify mirror)
			)
		)
		(property "License" "Apache-2.0"
			(at 369.65 -69.55 0)
			(layer "B.Fab")
			(hide yes)
			(effects
				(font
					(size 1 1)
					(thickness 0.15)
				)
				(justify mirror)
			)
		)
		(property "MPN" "GRM155R61H104KE14D"
			(at 369.65 -69.55 0)
			(layer "B.Fab")
			(hide yes)
			(effects
				(font
					(size 1 1)
					(thickness 0.15)
				)
				(justify mirror)
			)
		)
		(property "Manufacturer" "Murata"
			(at 369.65 -69.55 0)
			(layer "B.Fab")
			(hide yes)
			(effects
				(font
					(size 1 1)
					(thickness 0.15)
				)
				(justify mirror)
			)
		)
		(property "Public" ""
			(at 369.65 -69.55 0)
			(layer "B.Fab")
			(hide yes)
			(effects
				(font
					(size 1 1)
					(thickness 0.15)
				)
				(justify mirror)
			)
		)
		(property "Val" "100n"
			(at 369.65 -69.55 0)
			(layer "B.Fab")
			(hide yes)
			(effects
				(font
					(size 1 1)
					(thickness 0.15)
				)
				(justify mirror)
			)
		)
		(property "Voltage" "50V"
			(at 369.65 -69.55 0)
			(layer "B.Fab")
			(hide yes)
			(effects
				(font
					(size 1 1)
					(thickness 0.15)
				)
				(justify mirror)
			)
		)
		(sheetname "/WiFi_Bluetooth/")
		(sheetfile "wifi_bt.kicad_sch")
		(attr smd)
		(fp_rect
			(start -0.925 0.47)
			(end 0.925 -0.47)
			(stroke
				(width 0.05)
				(type default)
			)
			(fill no)
			(layer "B.CrtYd")
		)
		(fp_line
			(start 0.504 -0.248)
			(end -0.494 -0.248)
			(stroke
				(width 0.15)
				(type solid)
			)
			(layer "B.Fab")
		)
		(fp_line
			(start -0.494 -0.248)
			(end -0.494 0.25)
			(stroke
				(width 0.15)
				(type solid)
			)
			(layer "B.Fab")
		)
		(fp_line
			(start 0.504 0.25)
			(end 0.504 -0.248)
			(stroke
				(width 0.15)
				(type solid)
			)
			(layer "B.Fab")
		)
		(fp_line
			(start -0.494 0.25)
			(end 0.504 0.25)
			(stroke
				(width 0.15)
				(type solid)
			)
			(layer "B.Fab")
		)
		(fp_text user "License: Apache-2.0"
			(at -0.939 -5.799 270)
			(layer "B.Fab")
			(effects
				(font
					(size 0.7 0.7)
					(thickness 0.15)
				)
				(justify left bottom mirror)
			)
		)
		(fp_text user "Author: Antmicro"
			(at -0.939 -3.399 270)
			(layer "B.Fab")
			(effects
				(font
					(size 0.7 0.7)
					(thickness 0.15)
				)
				(justify left bottom mirror)
			)
		)
		(fp_text user "${REFERENCE}"
			(at -0.939 -4.599 270)
			(layer "B.Fab")
			(effects
				(font
					(size 0.7 0.7)
					(thickness 0.15)
				)
				(justify left bottom mirror)
			)
		)
		(pad "1" smd roundrect
			(at -0.48 0 90)
			(size 0.59 0.64)
			(layers "B.Cu" "B.Mask" "B.Paste")
			(roundrect_rratio 0.25)
			(net 417 "GND")
			(pintype "passive")
		)
		(pad "2" smd roundrect
			(at 0.48 0 90)
			(size 0.59 0.64)
			(layers "B.Cu" "B.Mask" "B.Paste")
			(roundrect_rratio 0.25)
			(net 50 "+3V3")
			(pintype "passive")
		)
	)
	(footprint "antmicro-footprints:R_0402_1005Metric"
		(layer "B.Cu")
		(at 210.5 147 90)
		(descr "Resistor SMD 0402")
		(tags "resistor SMD 0402")
		(property "Reference" "R86"
			(at -0.92 0.3 270)
			(layer "B.SilkS")
			(effects
				(font
					(size 0.7 0.7)
					(thickness 0.15)
				)
				(justify left bottom mirror)
			)
		)
		(property "Value" "R_10k_0402"
			(at -1.011843 -1.772047 270)
			(layer "B.Fab")
			(hide yes)
			(effects
				(font
					(size 0.7 0.7)
					(thickness 0.15)
				)
				(justify left bottom mirror)
			)
		)
		(property "Datasheet" "https://www.bourns.com/docs/product-datasheets/cr.pdf"
			(at 0 0 90)
			(layer "F.Fab")
			(hide yes)
			(effects
				(font
					(size 1.27 1.27)
					(thickness 0.15)
				)
			)
		)
		(property "Description" "SMD Chip Resistor, 10 kohm, ± 1%, 62.5 mW, 0402 [1005 Metric], Thick Film, General Purpose"
			(at 0 0 90)
			(layer "F.Fab")
			(hide yes)
			(effects
				(font
					(size 1.27 1.27)
					(thickness 0.15)
				)
			)
		)
		(property "Author" "Antmicro"
			(at 357.5 -63.5 0)
			(layer "B.Fab")
			(hide yes)
			(effects
				(font
					(size 1 1)
					(thickness 0.15)
				)
				(justify mirror)
			)
		)
		(property "License" "Apache-2.0"
			(at 357.5 -63.5 0)
			(layer "B.Fab")
			(hide yes)
			(effects
				(font
					(size 1 1)
					(thickness 0.15)
				)
				(justify mirror)
			)
		)
		(property "MPN" "CR0402-FX-1002GLF"
			(at 357.5 -63.5 0)
			(layer "B.Fab")
			(hide yes)
			(effects
				(font
					(size 1 1)
					(thickness 0.15)
				)
				(justify mirror)
			)
		)
		(property "Manufacturer" "Bourns"
			(at 357.5 -63.5 0)
			(layer "B.Fab")
			(hide yes)
			(effects
				(font
					(size 1 1)
					(thickness 0.15)
				)
				(justify mirror)
			)
		)
		(property "Public" ""
			(at 357.5 -63.5 0)
			(layer "B.Fab")
			(hide yes)
			(effects
				(font
					(size 1 1)
					(thickness 0.15)
				)
				(justify mirror)
			)
		)
		(property "Tolerance" "1%"
			(at 357.5 -63.5 0)
			(layer "B.Fab")
			(hide yes)
			(effects
				(font
					(size 1 1)
					(thickness 0.15)
				)
				(justify mirror)
			)
		)
		(property "Val" "10k"
			(at 357.5 -63.5 0)
			(layer "B.Fab")
			(hide yes)
			(effects
				(font
					(size 1 1)
					(thickness 0.15)
				)
				(justify mirror)
			)
		)
		(sheetname "/USB/")
		(sheetfile "usb.kicad_sch")
		(attr smd)
		(fp_rect
			(start -0.925 0.47)
			(end 0.925 -0.47)
			(stroke
				(width 0.05)
				(type default)
			)
			(fill no)
			(layer "B.CrtYd")
		)
		(fp_rect
			(start -0.5 0.25)
			(end 0.5 -0.25)
			(stroke
				(width 0.15)
				(type solid)
			)
			(fill no)
			(layer "B.Fab")
		)
		(fp_text user "Author: Antmicro"
			(at -0.95 -4.169 270)
			(layer "B.Fab")
			(effects
				(font
					(size 0.7 0.7)
					(thickness 0.15)
				)
				(justify left bottom mirror)
			)
		)
		(fp_text user "${REFERENCE}"
			(at -0.95 -3.168 270)
			(layer "B.Fab")
			(effects
				(font
					(size 0.7 0.7)
					(thickness 0.15)
				)
				(justify left bottom mirror)
			)
		)
		(fp_text user "License: Apache-2.0"
			(at -0.95 -5.169 270)
			(layer "B.Fab")
			(effects
				(font
					(size 0.7 0.7)
					(thickness 0.15)
				)
				(justify left bottom mirror)
			)
		)
		(pad "1" smd roundrect
			(at -0.48 0 90)
			(size 0.59 0.64)
			(layers "B.Cu" "B.Mask" "B.Paste")
			(roundrect_rratio 0.25)
			(net 635 "/FPGA GPIO/ULPI.RESET")
			(pintype "passive")
		)
		(pad "2" smd roundrect
			(at 0.48 0 90)
			(size 0.59 0.64)
			(layers "B.Cu" "B.Mask" "B.Paste")
			(roundrect_rratio 0.25)
			(net 649 "VDD")
			(pintype "passive")
		)
	)
	(footprint "antmicro-footprints:R_0402_1005Metric"
		(layer "B.Cu")
		(at 216.37 148.58 180)
		(descr "Resistor SMD 0402")
		(tags "resistor SMD 0402")
		(property "Reference" "R164"
			(at -2.92 -3.81 0)
			(layer "B.SilkS")
			(effects
				(font
					(size 0.7 0.7)
					(thickness 0.15)
				)
				(justify left bottom mirror)
			)
		)
		(property "Value" "R_100k_0402"
			(at -1.011843 -1.772047 0)
			(layer "B.Fab")
			(hide yes)
			(effects
				(font
					(size 0.7 0.7)
					(thickness 0.15)
				)
				(justify left bottom mirror)
			)
		)
		(property "Datasheet" "https://www.bourns.com/docs/product-datasheets/cr.pdf"
			(at 0 0 180)
			(layer "F.Fab")
			(hide yes)
			(effects
				(font
					(size 1.27 1.27)
					(thickness 0.15)
				)
			)
		)
		(property "Description" "SMD Chip Resistor, 100 kohm, ± 1%, 62.5 mW, 0402 [1005 Metric], Thick Film, General Purpose"
			(at 0 0 180)
			(layer "F.Fab")
			(hide yes)
			(effects
				(font
					(size 1.27 1.27)
					(thickness 0.15)
				)
			)
		)
		(property "Author" "Antmicro"
			(at 432.74 297.16 0)
			(layer "B.Fab")
			(hide yes)
			(effects
				(font
					(size 1 1)
					(thickness 0.15)
				)
				(justify mirror)
			)
		)
		(property "License" "Apache-2.0"
			(at 432.74 297.16 0)
			(layer "B.Fab")
			(hide yes)
			(effects
				(font
					(size 1 1)
					(thickness 0.15)
				)
				(justify mirror)
			)
		)
		(property "MPN" "CR0402-FX-1003GLF"
			(at 432.74 297.16 0)
			(layer "B.Fab")
			(hide yes)
			(effects
				(font
					(size 1 1)
					(thickness 0.15)
				)
				(justify mirror)
			)
		)
		(property "Manufacturer" "Bourns"
			(at 432.74 297.16 0)
			(layer "B.Fab")
			(hide yes)
			(effects
				(font
					(size 1 1)
					(thickness 0.15)
				)
				(justify mirror)
			)
		)
		(property "Public" ""
			(at 432.74 297.16 0)
			(layer "B.Fab")
			(hide yes)
			(effects
				(font
					(size 1 1)
					(thickness 0.15)
				)
				(justify mirror)
			)
		)
		(property "Tolerance" "1%"
			(at 432.74 297.16 0)
			(layer "B.Fab")
			(hide yes)
			(effects
				(font
					(size 1 1)
					(thickness 0.15)
				)
				(justify mirror)
			)
		)
		(property "Val" "100k"
			(at 432.74 297.16 0)
			(layer "B.Fab")
			(hide yes)
			(effects
				(font
					(size 1 1)
					(thickness 0.15)
				)
				(justify mirror)
			)
		)
		(sheetname "/USB/")
		(sheetfile "usb.kicad_sch")
		(attr smd)
		(fp_rect
			(start -0.925 0.47)
			(end 0.925 -0.47)
			(stroke
				(width 0.05)
				(type default)
			)
			(fill no)
			(layer "B.CrtYd")
		)
		(fp_rect
			(start -0.5 0.25)
			(end 0.5 -0.25)
			(stroke
				(width 0.15)
				(type solid)
			)
			(fill no)
			(layer "B.Fab")
		)
		(fp_text user "${REFERENCE}"
			(at -0.95 -3.168 0)
			(layer "B.Fab")
			(effects
				(font
					(size 0.7 0.7)
					(thickness 0.15)
				)
				(justify left bottom mirror)
			)
		)
		(fp_text user "Author: Antmicro"
			(at -0.95 -4.169 0)
			(layer "B.Fab")
			(effects
				(font
					(size 0.7 0.7)
					(thickness 0.15)
				)
				(justify left bottom mirror)
			)
		)
		(fp_text user "License: Apache-2.0"
			(at -0.95 -5.169 0)
			(layer "B.Fab")
			(effects
				(font
					(size 0.7 0.7)
					(thickness 0.15)
				)
				(justify left bottom mirror)
			)
		)
		(pad "1" smd roundrect
			(at -0.48 0 180)
			(size 0.59 0.64)
			(layers "B.Cu" "B.Mask" "B.Paste")
			(roundrect_rratio 0.25)
			(net 317 "/USB/~{HUB_RST}")
			(pintype "passive")
		)
		(pad "2" smd roundrect
			(at 0.48 0 180)
			(size 0.59 0.64)
			(layers "B.Cu" "B.Mask" "B.Paste")
			(roundrect_rratio 0.25)
			(net 50 "+3V3")
			(pintype "passive")
		)
	)
	(footprint "antmicro-footprints:C_0402_1005Metric"
		(layer "B.Cu")
		(at 210.5516 121.416)
		(descr "Capacitor SMD 0402")
		(tags "capacitor SMD 0402")
		(property "Reference" "C258"
			(at -3.5766 2.659 0)
			(layer "B.SilkS")
			(effects
				(font
					(size 0.7 0.7)
					(thickness 0.15)
				)
				(justify right bottom mirror)
			)
		)
		(property "Value" "C_100n_0402"
			(at -1.022927 -2.155213 0)
			(layer "B.Fab")
			(hide yes)
			(effects
				(font
					(size 0.7 0.7)
					(thickness 0.15)
				)
				(justify right bottom mirror)
			)
		)
		(property "Datasheet" "https://www.murata.com/products/productdetail?partno=GRM155R61H104KE14%23"
			(at 0 0 0)
			(layer "F.Fab")
			(hide yes)
			(effects
				(font
					(size 1.27 1.27)
					(thickness 0.15)
				)
			)
		)
		(property "Description" "SMD Multilayer Ceramic Capacitor, 0.1 µF, 50 V, 0402 [1005 Metric], ± 10%, X5R, GRM Series"
			(at 0 0 0)
			(layer "F.Fab")
			(hide yes)
			(effects
				(font
					(size 1.27 1.27)
					(thickness 0.15)
				)
			)
		)
		(property "Author" "Antmicro"
			(at 0 0 0)
			(layer "B.Fab")
			(hide yes)
			(effects
				(font
					(size 1 1)
					(thickness 0.15)
				)
				(justify mirror)
			)
		)
		(property "DNP" "DNP"
			(at 0 0 0)
			(layer "B.Fab")
			(hide yes)
			(effects
				(font
					(size 1 1)
					(thickness 0.15)
				)
				(justify mirror)
			)
		)
		(property "Dielectric" "X5R"
			(at 0 0 0)
			(layer "B.Fab")
			(hide yes)
			(effects
				(font
					(size 1 1)
					(thickness 0.15)
				)
				(justify mirror)
			)
		)
		(property "License" "Apache-2.0"
			(at 0 0 0)
			(layer "B.Fab")
			(hide yes)
			(effects
				(font
					(size 1 1)
					(thickness 0.15)
				)
				(justify mirror)
			)
		)
		(property "MPN" "GRM155R61H104KE14D"
			(at 0 0 0)
			(layer "B.Fab")
			(hide yes)
			(effects
				(font
					(size 1 1)
					(thickness 0.15)
				)
				(justify mirror)
			)
		)
		(property "Manufacturer" "Murata"
			(at 0 0 0)
			(layer "B.Fab")
			(hide yes)
			(effects
				(font
					(size 1 1)
					(thickness 0.15)
				)
				(justify mirror)
			)
		)
		(property "Public" ""
			(at 0 0 0)
			(layer "B.Fab")
			(hide yes)
			(effects
				(font
					(size 1 1)
					(thickness 0.15)
				)
				(justify mirror)
			)
		)
		(property "Val" "100n"
			(at 0 0 0)
			(layer "B.Fab")
			(hide yes)
			(effects
				(font
					(size 1 1)
					(thickness 0.15)
				)
				(justify mirror)
			)
		)
		(property "Voltage" "50V"
			(at 0 0 0)
			(layer "B.Fab")
			(hide yes)
			(effects
				(font
					(size 1 1)
					(thickness 0.15)
				)
				(justify mirror)
			)
		)
		(sheetname "/Ethernet/")
		(sheetfile "ethernet.kicad_sch")
		(attr smd dnp)
		(fp_rect
			(start -0.925 0.47)
			(end 0.925 -0.47)
			(stroke
				(width 0.05)
				(type default)
			)
			(fill no)
			(layer "B.CrtYd")
		)
		(fp_line
			(start -0.494 -0.248)
			(end -0.494 0.25)
			(stroke
				(width 0.15)
				(type solid)
			)
			(layer "B.Fab")
		)
		(fp_line
			(start -0.494 0.25)
			(end 0.504 0.25)
			(stroke
				(width 0.15)
				(type solid)
			)
			(layer "B.Fab")
		)
		(fp_line
			(start 0.504 -0.248)
			(end -0.494 -0.248)
			(stroke
				(width 0.15)
				(type solid)
			)
			(layer "B.Fab")
		)
		(fp_line
			(start 0.504 0.25)
			(end 0.504 -0.248)
			(stroke
				(width 0.15)
				(type solid)
			)
			(layer "B.Fab")
		)
		(fp_text user "License: Apache-2.0"
			(at -0.939 -5.799 180)
			(layer "B.Fab")
			(effects
				(font
					(size 0.7 0.7)
					(thickness 0.15)
				)
				(justify left bottom mirror)
			)
		)
		(fp_text user "${REFERENCE}"
			(at -0.939 -4.599 180)
			(layer "B.Fab")
			(effects
				(font
					(size 0.7 0.7)
					(thickness 0.15)
				)
				(justify left bottom mirror)
			)
		)
		(fp_text user "Author: Antmicro"
			(at -0.939 -3.399 180)
			(layer "B.Fab")
			(effects
				(font
					(size 0.7 0.7)
					(thickness 0.15)
				)
				(justify left bottom mirror)
			)
		)
		(pad "1" smd roundrect
			(at -0.48 0)
			(size 0.59 0.64)
			(layers "B.Cu" "B.Mask" "B.Paste")
			(roundrect_rratio 0.25)
			(net 10 "MSS_REFCLK_P")
			(pintype "passive")
		)
		(pad "2" smd roundrect
			(at 0.48 0)
			(size 0.59 0.64)
			(layers "B.Cu" "B.Mask" "B.Paste")
			(roundrect_rratio 0.25)
			(net 169 "/Ethernet/SGMII_CO_P")
			(pintype "passive")
		)
	)
	(footprint "antmicro-footprints:C_0402_1005Metric"
		(layer "B.Cu")
		(at 225.33 123.45 -90)
		(descr "Capacitor SMD 0402")
		(tags "capacitor SMD 0402")
		(property "Reference" "C19"
			(at -3 0.03 270)
			(layer "B.SilkS")
			(effects
				(font
					(size 0.7 0.7)
					(thickness 0.15)
				)
				(justify left bottom mirror)
			)
		)
		(property "Value" "C_100n_0402"
			(at -1.022927 -2.155213 90)
			(layer "B.Fab")
			(hide yes)
			(effects
				(font
					(size 0.7 0.7)
					(thickness 0.15)
				)
				(justify left bottom mirror)
			)
		)
		(property "Datasheet" "https://www.murata.com/products/productdetail?partno=GRM155R61H104KE14%23"
			(at 0 0 270)
			(layer "F.Fab")
			(hide yes)
			(effects
				(font
					(size 1.27 1.27)
					(thickness 0.15)
				)
			)
		)
		(property "Description" "SMD Multilayer Ceramic Capacitor, 0.1 µF, 50 V, 0402 [1005 Metric], ± 10%, X5R, GRM Series"
			(at 0 0 270)
			(layer "F.Fab")
			(hide yes)
			(effects
				(font
					(size 1.27 1.27)
					(thickness 0.15)
				)
			)
		)
		(property "Author" "Antmicro"
			(at 101.88 348.78 0)
			(layer "B.Fab")
			(hide yes)
			(effects
				(font
					(size 1 1)
					(thickness 0.15)
				)
				(justify mirror)
			)
		)
		(property "Dielectric" "X5R"
			(at 101.88 348.78 0)
			(layer "B.Fab")
			(hide yes)
			(effects
				(font
					(size 1 1)
					(thickness 0.15)
				)
				(justify mirror)
			)
		)
		(property "License" "Apache-2.0"
			(at 101.88 348.78 0)
			(layer "B.Fab")
			(hide yes)
			(effects
				(font
					(size 1 1)
					(thickness 0.15)
				)
				(justify mirror)
			)
		)
		(property "MPN" "GRM155R61H104KE14D"
			(at 101.88 348.78 0)
			(layer "B.Fab")
			(hide yes)
			(effects
				(font
					(size 1 1)
					(thickness 0.15)
				)
				(justify mirror)
			)
		)
		(property "Manufacturer" "Murata"
			(at 101.88 348.78 0)
			(layer "B.Fab")
			(hide yes)
			(effects
				(font
					(size 1 1)
					(thickness 0.15)
				)
				(justify mirror)
			)
		)
		(property "Public" ""
			(at 101.88 348.78 0)
			(layer "B.Fab")
			(hide yes)
			(effects
				(font
					(size 1 1)
					(thickness 0.15)
				)
				(justify mirror)
			)
		)
		(property "Val" "100n"
			(at 101.88 348.78 0)
			(layer "B.Fab")
			(hide yes)
			(effects
				(font
					(size 1 1)
					(thickness 0.15)
				)
				(justify mirror)
			)
		)
		(property "Voltage" "50V"
			(at 101.88 348.78 0)
			(layer "B.Fab")
			(hide yes)
			(effects
				(font
					(size 1 1)
					(thickness 0.15)
				)
				(justify mirror)
			)
		)
		(sheetname "/FPGA GPIO/")
		(sheetfile "fpga-gpio.kicad_sch")
		(attr smd)
		(fp_rect
			(start -0.925 0.47)
			(end 0.925 -0.47)
			(stroke
				(width 0.05)
				(type default)
			)
			(fill no)
			(layer "B.CrtYd")
		)
		(fp_line
			(start -0.494 0.25)
			(end 0.504 0.25)
			(stroke
				(width 0.15)
				(type solid)
			)
			(layer "B.Fab")
		)
		(fp_line
			(start 0.504 0.25)
			(end 0.504 -0.248)
			(stroke
				(width 0.15)
				(type solid)
			)
			(layer "B.Fab")
		)
		(fp_line
			(start -0.494 -0.248)
			(end -0.494 0.25)
			(stroke
				(width 0.15)
				(type solid)
			)
			(layer "B.Fab")
		)
		(fp_line
			(start 0.504 -0.248)
			(end -0.494 -0.248)
			(stroke
				(width 0.15)
				(type solid)
			)
			(layer "B.Fab")
		)
		(fp_text user "License: Apache-2.0"
			(at -0.939 -5.799 90)
			(layer "B.Fab")
			(effects
				(font
					(size 0.7 0.7)
					(thickness 0.15)
				)
				(justify left bottom mirror)
			)
		)
		(fp_text user "Author: Antmicro"
			(at -0.939 -3.399 90)
			(layer "B.Fab")
			(effects
				(font
					(size 0.7 0.7)
					(thickness 0.15)
				)
				(justify left bottom mirror)
			)
		)
		(fp_text user "${REFERENCE}"
			(at -0.939 -4.599 90)
			(layer "B.Fab")
			(effects
				(font
					(size 0.7 0.7)
					(thickness 0.15)
				)
				(justify left bottom mirror)
			)
		)
		(pad "1" smd roundrect
			(at -0.48 0 270)
			(size 0.59 0.64)
			(layers "B.Cu" "B.Mask" "B.Paste")
			(roundrect_rratio 0.25)
			(net 50 "+3V3")
			(pintype "passive")
		)
		(pad "2" smd roundrect
			(at 0.48 0 270)
			(size 0.59 0.64)
			(layers "B.Cu" "B.Mask" "B.Paste")
			(roundrect_rratio 0.25)
			(net 417 "GND")
			(pintype "passive")
		)
	)
	(footprint "antmicro-footprints:C_0402_1005Metric"
		(layer "B.Cu")
		(at 184.8045 123.8755 -90)
		(descr "Capacitor SMD 0402")
		(tags "capacitor SMD 0402")
		(property "Reference" "C147"
			(at -1.2005 0.4795 270)
			(layer "B.SilkS")
			(effects
				(font
					(size 0.7 0.7)
					(thickness 0.15)
				)
				(justify left bottom mirror)
			)
		)
		(property "Value" "C_1u_0402"
			(at -1.022927 -2.155213 90)
			(layer "B.Fab")
			(hide yes)
			(effects
				(font
					(size 0.7 0.7)
					(thickness 0.15)
				)
				(justify left bottom mirror)
			)
		)
		(property "Datasheet" "https://product.tdk.com/en/search/capacitor/ceramic/mlcc/info?part_no=C1005X6S1A105K050BC"
			(at 0 0 270)
			(layer "F.Fab")
			(hide yes)
			(effects
				(font
					(size 1.27 1.27)
					(thickness 0.15)
				)
			)
		)
		(property "Description" "SMD Multilayer Ceramic Capacitor, 1 µF, 10 V, 0402 [1005 Metric], ± 10%, X6S, C"
			(at 0 0 270)
			(layer "F.Fab")
			(hide yes)
			(effects
				(font
					(size 1.27 1.27)
					(thickness 0.15)
				)
			)
		)
		(property "Author" "Antmicro"
			(at 60.929 308.68 0)
			(layer "B.Fab")
			(hide yes)
			(effects
				(font
					(size 1 1)
					(thickness 0.15)
				)
				(justify mirror)
			)
		)
		(property "Dielectric" "X5R"
			(at 60.929 308.68 0)
			(layer "B.Fab")
			(hide yes)
			(effects
				(font
					(size 1 1)
					(thickness 0.15)
				)
				(justify mirror)
			)
		)
		(property "License" "Apache-2.0"
			(at 60.929 308.68 0)
			(layer "B.Fab")
			(hide yes)
			(effects
				(font
					(size 1 1)
					(thickness 0.15)
				)
				(justify mirror)
			)
		)
		(property "MPN" "C1005X6S1A105K050BC"
			(at 60.929 308.68 0)
			(layer "B.Fab")
			(hide yes)
			(effects
				(font
					(size 1 1)
					(thickness 0.15)
				)
				(justify mirror)
			)
		)
		(property "Manufacturer" "TDK"
			(at 60.929 308.68 0)
			(layer "B.Fab")
			(hide yes)
			(effects
				(font
					(size 1 1)
					(thickness 0.15)
				)
				(justify mirror)
			)
		)
		(property "Public" ""
			(at 60.929 308.68 0)
			(layer "B.Fab")
			(hide yes)
			(effects
				(font
					(size 1 1)
					(thickness 0.15)
				)
				(justify mirror)
			)
		)
		(property "Val" "1u"
			(at 60.929 308.68 0)
			(layer "B.Fab")
			(hide yes)
			(effects
				(font
					(size 1 1)
					(thickness 0.15)
				)
				(justify mirror)
			)
		)
		(property "Voltage" "16V"
			(at 60.929 308.68 0)
			(layer "B.Fab")
			(hide yes)
			(effects
				(font
					(size 1 1)
					(thickness 0.15)
				)
				(justify mirror)
			)
		)
		(sheetname "/LPDDR4/")
		(sheetfile "lpddr.kicad_sch")
		(attr smd)
		(fp_rect
			(start -0.925 0.47)
			(end 0.925 -0.47)
			(stroke
				(width 0.05)
				(type default)
			)
			(fill no)
			(layer "B.CrtYd")
		)
		(fp_line
			(start -0.494 0.25)
			(end 0.504 0.25)
			(stroke
				(width 0.15)
				(type solid)
			)
			(layer "B.Fab")
		)
		(fp_line
			(start 0.504 0.25)
			(end 0.504 -0.248)
			(stroke
				(width 0.15)
				(type solid)
			)
			(layer "B.Fab")
		)
		(fp_line
			(start -0.494 -0.248)
			(end -0.494 0.25)
			(stroke
				(width 0.15)
				(type solid)
			)
			(layer "B.Fab")
		)
		(fp_line
			(start 0.504 -0.248)
			(end -0.494 -0.248)
			(stroke
				(width 0.15)
				(type solid)
			)
			(layer "B.Fab")
		)
		(fp_text user "License: Apache-2.0"
			(at -0.939 -5.799 90)
			(layer "B.Fab")
			(effects
				(font
					(size 0.7 0.7)
					(thickness 0.15)
				)
				(justify left bottom mirror)
			)
		)
		(fp_text user "${REFERENCE}"
			(at -0.939 -4.599 90)
			(layer "B.Fab")
			(effects
				(font
					(size 0.7 0.7)
					(thickness 0.15)
				)
				(justify left bottom mirror)
			)
		)
		(fp_text user "Author: Antmicro"
			(at -0.939 -3.399 90)
			(layer "B.Fab")
			(effects
				(font
					(size 0.7 0.7)
					(thickness 0.15)
				)
				(justify left bottom mirror)
			)
		)
		(pad "1" smd roundrect
			(at -0.48 0 270)
			(size 0.59 0.64)
			(layers "B.Cu" "B.Mask" "B.Paste")
			(roundrect_rratio 0.25)
			(net 417 "GND")
			(pintype "passive")
		)
		(pad "2" smd roundrect
			(at 0.48 0 270)
			(size 0.59 0.64)
			(layers "B.Cu" "B.Mask" "B.Paste")
			(roundrect_rratio 0.25)
			(net 2 "+1V1")
			(pintype "passive")
		)
	)
	(footprint "antmicro-footprints:C_0402_1005Metric"
		(layer "B.Cu")
		(at 177.7 134.1 90)
		(descr "Capacitor SMD 0402")
		(tags "capacitor SMD 0402")
		(property "Reference" "C135"
			(at -1.34 1.44 90)
			(layer "B.SilkS")
			(effects
				(font
					(size 0.7 0.7)
					(thickness 0.15)
				)
				(justify right bottom mirror)
			)
		)
		(property "Value" "C_1u_0402"
			(at -1.022927 -2.155213 90)
			(layer "B.Fab")
			(hide yes)
			(effects
				(font
					(size 0.7 0.7)
					(thickness 0.15)
				)
				(justify right bottom mirror)
			)
		)
		(property "Datasheet" "https://product.tdk.com/en/search/capacitor/ceramic/mlcc/info?part_no=C1005X6S1A105K050BC"
			(at 0 0 90)
			(layer "F.Fab")
			(hide yes)
			(effects
				(font
					(size 1.27 1.27)
					(thickness 0.15)
				)
			)
		)
		(property "Description" "SMD Multilayer Ceramic Capacitor, 1 µF, 10 V, 0402 [1005 Metric], ± 10%, X6S, C"
			(at 0 0 90)
			(layer "F.Fab")
			(hide yes)
			(effects
				(font
					(size 1.27 1.27)
					(thickness 0.15)
				)
			)
		)
		(property "Author" "Antmicro"
			(at 311.8 -43.6 0)
			(layer "B.Fab")
			(hide yes)
			(effects
				(font
					(size 1 1)
					(thickness 0.15)
				)
				(justify mirror)
			)
		)
		(property "Dielectric" "X5R"
			(at 311.8 -43.6 0)
			(layer "B.Fab")
			(hide yes)
			(effects
				(font
					(size 1 1)
					(thickness 0.15)
				)
				(justify mirror)
			)
		)
		(property "License" "Apache-2.0"
			(at 311.8 -43.6 0)
			(layer "B.Fab")
			(hide yes)
			(effects
				(font
					(size 1 1)
					(thickness 0.15)
				)
				(justify mirror)
			)
		)
		(property "MPN" "C1005X6S1A105K050BC"
			(at 311.8 -43.6 0)
			(layer "B.Fab")
			(hide yes)
			(effects
				(font
					(size 1 1)
					(thickness 0.15)
				)
				(justify mirror)
			)
		)
		(property "Manufacturer" "TDK"
			(at 311.8 -43.6 0)
			(layer "B.Fab")
			(hide yes)
			(effects
				(font
					(size 1 1)
					(thickness 0.15)
				)
				(justify mirror)
			)
		)
		(property "Public" ""
			(at 311.8 -43.6 0)
			(layer "B.Fab")
			(hide yes)
			(effects
				(font
					(size 1 1)
					(thickness 0.15)
				)
				(justify mirror)
			)
		)
		(property "Val" "1u"
			(at 311.8 -43.6 0)
			(layer "B.Fab")
			(hide yes)
			(effects
				(font
					(size 1 1)
					(thickness 0.15)
				)
				(justify mirror)
			)
		)
		(property "Voltage" "16V"
			(at 311.8 -43.6 0)
			(layer "B.Fab")
			(hide yes)
			(effects
				(font
					(size 1 1)
					(thickness 0.15)
				)
				(justify mirror)
			)
		)
		(sheetname "/LPDDR4/")
		(sheetfile "lpddr.kicad_sch")
		(attr smd)
		(fp_rect
			(start -0.925 0.47)
			(end 0.925 -0.47)
			(stroke
				(width 0.05)
				(type default)
			)
			(fill no)
			(layer "B.CrtYd")
		)
		(fp_line
			(start 0.504 -0.248)
			(end -0.494 -0.248)
			(stroke
				(width 0.15)
				(type solid)
			)
			(layer "B.Fab")
		)
		(fp_line
			(start -0.494 -0.248)
			(end -0.494 0.25)
			(stroke
				(width 0.15)
				(type solid)
			)
			(layer "B.Fab")
		)
		(fp_line
			(start 0.504 0.25)
			(end 0.504 -0.248)
			(stroke
				(width 0.15)
				(type solid)
			)
			(layer "B.Fab")
		)
		(fp_line
			(start -0.494 0.25)
			(end 0.504 0.25)
			(stroke
				(width 0.15)
				(type solid)
			)
			(layer "B.Fab")
		)
		(fp_text user "Author: Antmicro"
			(at -0.939 -3.399 270)
			(layer "B.Fab")
			(effects
				(font
					(size 0.7 0.7)
					(thickness 0.15)
				)
				(justify left bottom mirror)
			)
		)
		(fp_text user "${REFERENCE}"
			(at -0.939 -4.599 270)
			(layer "B.Fab")
			(effects
				(font
					(size 0.7 0.7)
					(thickness 0.15)
				)
				(justify left bottom mirror)
			)
		)
		(fp_text user "License: Apache-2.0"
			(at -0.939 -5.799 270)
			(layer "B.Fab")
			(effects
				(font
					(size 0.7 0.7)
					(thickness 0.15)
				)
				(justify left bottom mirror)
			)
		)
		(pad "1" smd roundrect
			(at -0.48 0 90)
			(size 0.59 0.64)
			(layers "B.Cu" "B.Mask" "B.Paste")
			(roundrect_rratio 0.25)
			(net 417 "GND")
			(pintype "passive")
		)
		(pad "2" smd roundrect
			(at 0.48 0 90)
			(size 0.59 0.64)
			(layers "B.Cu" "B.Mask" "B.Paste")
			(roundrect_rratio 0.25)
			(net 2 "+1V1")
			(pintype "passive")
		)
	)
	(footprint "antmicro-footprints:C_0402_1005Metric"
		(layer "B.Cu")
		(at 199.91 136.684 -90)
		(descr "Capacitor SMD 0402")
		(tags "capacitor SMD 0402")
		(property "Reference" "C34"
			(at -7.334 9.635 90)
			(layer "B.SilkS")
			(effects
				(font
					(size 0.7 0.7)
					(thickness 0.15)
				)
				(justify left bottom mirror)
			)
		)
		(property "Value" "C_10n_0402"
			(at -1.022927 -2.155213 90)
			(layer "B.Fab")
			(hide yes)
			(effects
				(font
					(size 0.7 0.7)
					(thickness 0.15)
				)
				(justify left bottom mirror)
			)
		)
		(property "Datasheet" "https://www.murata.com/products/productdetail?partno=GRM155R71H103KA88%23"
			(at 0 0 270)
			(layer "F.Fab")
			(hide yes)
			(effects
				(font
					(size 1.27 1.27)
					(thickness 0.15)
				)
			)
		)
		(property "Description" "SMD Multilayer Ceramic Capacitor, 10000 pF, 50 V, 0402 [1005 Metric], ± 10%, X7R, GRM Series"
			(at 0 0 270)
			(layer "F.Fab")
			(hide yes)
			(effects
				(font
					(size 1.27 1.27)
					(thickness 0.15)
				)
			)
		)
		(property "Author" "Antmicro"
			(at 63.226 336.594 0)
			(layer "B.Fab")
			(hide yes)
			(effects
				(font
					(size 1 1)
					(thickness 0.15)
				)
				(justify mirror)
			)
		)
		(property "Dielectric" "X7R"
			(at 63.226 336.594 0)
			(layer "B.Fab")
			(hide yes)
			(effects
				(font
					(size 1 1)
					(thickness 0.15)
				)
				(justify mirror)
			)
		)
		(property "License" "Apache-2.0"
			(at 63.226 336.594 0)
			(layer "B.Fab")
			(hide yes)
			(effects
				(font
					(size 1 1)
					(thickness 0.15)
				)
				(justify mirror)
			)
		)
		(property "MPN" "GRM155R71H103KA88D"
			(at 63.226 336.594 0)
			(layer "B.Fab")
			(hide yes)
			(effects
				(font
					(size 1 1)
					(thickness 0.15)
				)
				(justify mirror)
			)
		)
		(property "Manufacturer" "Murata"
			(at 63.226 336.594 0)
			(layer "B.Fab")
			(hide yes)
			(effects
				(font
					(size 1 1)
					(thickness 0.15)
				)
				(justify mirror)
			)
		)
		(property "Public" ""
			(at 63.226 336.594 0)
			(layer "B.Fab")
			(hide yes)
			(effects
				(font
					(size 1 1)
					(thickness 0.15)
				)
				(justify mirror)
			)
		)
		(property "Val" "10n"
			(at 63.226 336.594 0)
			(layer "B.Fab")
			(hide yes)
			(effects
				(font
					(size 1 1)
					(thickness 0.15)
				)
				(justify mirror)
			)
		)
		(property "Voltage" "50V"
			(at 63.226 336.594 0)
			(layer "B.Fab")
			(hide yes)
			(effects
				(font
					(size 1 1)
					(thickness 0.15)
				)
				(justify mirror)
			)
		)
		(sheetname "/FPGA Supply/")
		(sheetfile "fpga-supply.kicad_sch")
		(attr smd)
		(fp_rect
			(start -0.925 0.47)
			(end 0.925 -0.47)
			(stroke
				(width 0.05)
				(type default)
			)
			(fill no)
			(layer "B.CrtYd")
		)
		(fp_line
			(start -0.494 0.25)
			(end 0.504 0.25)
			(stroke
				(width 0.15)
				(type solid)
			)
			(layer "B.Fab")
		)
		(fp_line
			(start 0.504 0.25)
			(end 0.504 -0.248)
			(stroke
				(width 0.15)
				(type solid)
			)
			(layer "B.Fab")
		)
		(fp_line
			(start -0.494 -0.248)
			(end -0.494 0.25)
			(stroke
				(width 0.15)
				(type solid)
			)
			(layer "B.Fab")
		)
		(fp_line
			(start 0.504 -0.248)
			(end -0.494 -0.248)
			(stroke
				(width 0.15)
				(type solid)
			)
			(layer "B.Fab")
		)
		(fp_text user "License: Apache-2.0"
			(at -0.939 -5.799 90)
			(layer "B.Fab")
			(effects
				(font
					(size 0.7 0.7)
					(thickness 0.15)
				)
				(justify left bottom mirror)
			)
		)
		(fp_text user "${REFERENCE}"
			(at -0.939 -4.599 90)
			(layer "B.Fab")
			(effects
				(font
					(size 0.7 0.7)
					(thickness 0.15)
				)
				(justify left bottom mirror)
			)
		)
		(fp_text user "Author: Antmicro"
			(at -0.939 -3.399 90)
			(layer "B.Fab")
			(effects
				(font
					(size 0.7 0.7)
					(thickness 0.15)
				)
				(justify left bottom mirror)
			)
		)
		(pad "1" smd roundrect
			(at -0.48 0 270)
			(size 0.59 0.64)
			(layers "B.Cu" "B.Mask" "B.Paste")
			(roundrect_rratio 0.25)
			(net 417 "GND")
			(pintype "passive")
		)
		(pad "2" smd roundrect
			(at 0.48 0 270)
			(size 0.59 0.64)
			(layers "B.Cu" "B.Mask" "B.Paste")
			(roundrect_rratio 0.25)
			(net 418 "+2V5")
			(pintype "passive")
		)
	)
	(footprint "antmicro-footprints:R_0402_1005Metric"
		(layer "B.Cu")
		(at 226.68 131.6)
		(descr "Resistor SMD 0402")
		(tags "resistor SMD 0402")
		(property "Reference" "R82"
			(at 2.92 0.4 180)
			(layer "B.SilkS")
			(effects
				(font
					(size 0.7 0.7)
					(thickness 0.15)
				)
				(justify left bottom mirror)
			)
		)
		(property "Value" "R_100k_0402"
			(at -1.011843 -1.772047 180)
			(layer "B.Fab")
			(hide yes)
			(effects
				(font
					(size 0.7 0.7)
					(thickness 0.15)
				)
				(justify left bottom mirror)
			)
		)
		(property "Datasheet" "https://www.bourns.com/docs/product-datasheets/cr.pdf"
			(at 0 0 0)
			(layer "F.Fab")
			(hide yes)
			(effects
				(font
					(size 1.27 1.27)
					(thickness 0.15)
				)
			)
		)
		(property "Description" "SMD Chip Resistor, 100 kohm, ± 1%, 62.5 mW, 0402 [1005 Metric], Thick Film, General Purpose"
			(at 0 0 0)
			(layer "F.Fab")
			(hide yes)
			(effects
				(font
					(size 1.27 1.27)
					(thickness 0.15)
				)
			)
		)
		(property "Author" "Antmicro"
			(at 0 0 0)
			(layer "B.Fab")
			(hide yes)
			(effects
				(font
					(size 1 1)
					(thickness 0.15)
				)
				(justify mirror)
			)
		)
		(property "License" "Apache-2.0"
			(at 0 0 0)
			(layer "B.Fab")
			(hide yes)
			(effects
				(font
					(size 1 1)
					(thickness 0.15)
				)
				(justify mirror)
			)
		)
		(property "MPN" "CR0402-FX-1003GLF"
			(at 0 0 0)
			(layer "B.Fab")
			(hide yes)
			(effects
				(font
					(size 1 1)
					(thickness 0.15)
				)
				(justify mirror)
			)
		)
		(property "Manufacturer" "Bourns"
			(at 0 0 0)
			(layer "B.Fab")
			(hide yes)
			(effects
				(font
					(size 1 1)
					(thickness 0.15)
				)
				(justify mirror)
			)
		)
		(property "Public" ""
			(at 0 0 0)
			(layer "B.Fab")
			(hide yes)
			(effects
				(font
					(size 1 1)
					(thickness 0.15)
				)
				(justify mirror)
			)
		)
		(property "Tolerance" "1%"
			(at 0 0 0)
			(layer "B.Fab")
			(hide yes)
			(effects
				(font
					(size 1 1)
					(thickness 0.15)
				)
				(justify mirror)
			)
		)
		(property "Val" "100k"
			(at 0 0 0)
			(layer "B.Fab")
			(hide yes)
			(effects
				(font
					(size 1 1)
					(thickness 0.15)
				)
				(justify mirror)
			)
		)
		(sheetname "/FPGA GPIO/")
		(sheetfile "fpga-gpio.kicad_sch")
		(attr smd)
		(fp_rect
			(start -0.925 0.47)
			(end 0.925 -0.47)
			(stroke
				(width 0.05)
				(type default)
			)
			(fill no)
			(layer "B.CrtYd")
		)
		(fp_rect
			(start -0.5 0.25)
			(end 0.5 -0.25)
			(stroke
				(width 0.15)
				(type solid)
			)
			(fill no)
			(layer "B.Fab")
		)
		(fp_text user "Author: Antmicro"
			(at -0.95 -4.169 180)
			(layer "B.Fab")
			(effects
				(font
					(size 0.7 0.7)
					(thickness 0.15)
				)
				(justify left bottom mirror)
			)
		)
		(fp_text user "License: Apache-2.0"
			(at -0.95 -5.169 180)
			(layer "B.Fab")
			(effects
				(font
					(size 0.7 0.7)
					(thickness 0.15)
				)
				(justify left bottom mirror)
			)
		)
		(fp_text user "${REFERENCE}"
			(at -0.95 -3.168 180)
			(layer "B.Fab")
			(effects
				(font
					(size 0.7 0.7)
					(thickness 0.15)
				)
				(justify left bottom mirror)
			)
		)
		(pad "1" smd roundrect
			(at -0.48 0)
			(size 0.59 0.64)
			(layers "B.Cu" "B.Mask" "B.Paste")
			(roundrect_rratio 0.25)
			(net 417 "GND")
			(pintype "passive")
		)
		(pad "2" smd roundrect
			(at 0.48 0)
			(size 0.59 0.64)
			(layers "B.Cu" "B.Mask" "B.Paste")
			(roundrect_rratio 0.25)
			(net 342 "/FPGA GPIO/USER_LED_R")
			(pintype "passive")
		)
	)
	(footprint "antmicro-footprints:C_0402_1005Metric"
		(layer "B.Cu")
		(at 216.361 123.254 -90)
		(descr "Capacitor SMD 0402")
		(tags "capacitor SMD 0402")
		(property "Reference" "C253"
			(at 1.886 -0.689 90)
			(layer "B.SilkS")
			(effects
				(font
					(size 0.7 0.7)
					(thickness 0.15)
				)
				(justify left bottom mirror)
			)
		)
		(property "Value" "C_1u_0402"
			(at -1.022927 -2.155213 90)
			(layer "B.Fab")
			(hide yes)
			(effects
				(font
					(size 0.7 0.7)
					(thickness 0.15)
				)
				(justify left bottom mirror)
			)
		)
		(property "Datasheet" "https://product.tdk.com/en/search/capacitor/ceramic/mlcc/info?part_no=C1005X6S1A105K050BC"
			(at 0 0 270)
			(layer "F.Fab")
			(hide yes)
			(effects
				(font
					(size 1.27 1.27)
					(thickness 0.15)
				)
			)
		)
		(property "Description" "SMD Multilayer Ceramic Capacitor, 1 µF, 10 V, 0402 [1005 Metric], ± 10%, X6S, C"
			(at 0 0 270)
			(layer "F.Fab")
			(hide yes)
			(effects
				(font
					(size 1.27 1.27)
					(thickness 0.15)
				)
			)
		)
		(property "Author" "Antmicro"
			(at 93.107 339.615 0)
			(layer "B.Fab")
			(hide yes)
			(effects
				(font
					(size 1 1)
					(thickness 0.15)
				)
				(justify mirror)
			)
		)
		(property "Dielectric" ""
			(at 93.107 339.615 0)
			(layer "B.Fab")
			(hide yes)
			(effects
				(font
					(size 1 1)
					(thickness 0.15)
				)
				(justify mirror)
			)
		)
		(property "License" "Apache-2.0"
			(at 93.107 339.615 0)
			(layer "B.Fab")
			(hide yes)
			(effects
				(font
					(size 1 1)
					(thickness 0.15)
				)
				(justify mirror)
			)
		)
		(property "MPN" "C1005X6S1A105K050BC"
			(at 93.107 339.615 0)
			(layer "B.Fab")
			(hide yes)
			(effects
				(font
					(size 1 1)
					(thickness 0.15)
				)
				(justify mirror)
			)
		)
		(property "Manufacturer" "TDK"
			(at 93.107 339.615 0)
			(layer "B.Fab")
			(hide yes)
			(effects
				(font
					(size 1 1)
					(thickness 0.15)
				)
				(justify mirror)
			)
		)
		(property "Public" ""
			(at 93.107 339.615 0)
			(layer "B.Fab")
			(hide yes)
			(effects
				(font
					(size 1 1)
					(thickness 0.15)
				)
				(justify mirror)
			)
		)
		(property "Val" "1u"
			(at 93.107 339.615 0)
			(layer "B.Fab")
			(hide yes)
			(effects
				(font
					(size 1 1)
					(thickness 0.15)
				)
				(justify mirror)
			)
		)
		(property "Voltage" ""
			(at 93.107 339.615 0)
			(layer "B.Fab")
			(hide yes)
			(effects
				(font
					(size 1 1)
					(thickness 0.15)
				)
				(justify mirror)
			)
		)
		(sheetname "/Ethernet/")
		(sheetfile "ethernet.kicad_sch")
		(attr smd)
		(fp_rect
			(start -0.925 0.47)
			(end 0.925 -0.47)
			(stroke
				(width 0.05)
				(type default)
			)
			(fill no)
			(layer "B.CrtYd")
		)
		(fp_line
			(start -0.494 0.25)
			(end 0.504 0.25)
			(stroke
				(width 0.15)
				(type solid)
			)
			(layer "B.Fab")
		)
		(fp_line
			(start 0.504 0.25)
			(end 0.504 -0.248)
			(stroke
				(width 0.15)
				(type solid)
			)
			(layer "B.Fab")
		)
		(fp_line
			(start -0.494 -0.248)
			(end -0.494 0.25)
			(stroke
				(width 0.15)
				(type solid)
			)
			(layer "B.Fab")
		)
		(fp_line
			(start 0.504 -0.248)
			(end -0.494 -0.248)
			(stroke
				(width 0.15)
				(type solid)
			)
			(layer "B.Fab")
		)
		(fp_text user "Author: Antmicro"
			(at -0.939 -3.399 90)
			(layer "B.Fab")
			(effects
				(font
					(size 0.7 0.7)
					(thickness 0.15)
				)
				(justify left bottom mirror)
			)
		)
		(fp_text user "License: Apache-2.0"
			(at -0.939 -5.799 90)
			(layer "B.Fab")
			(effects
				(font
					(size 0.7 0.7)
					(thickness 0.15)
				)
				(justify left bottom mirror)
			)
		)
		(fp_text user "${REFERENCE}"
			(at -0.939 -4.599 90)
			(layer "B.Fab")
			(effects
				(font
					(size 0.7 0.7)
					(thickness 0.15)
				)
				(justify left bottom mirror)
			)
		)
		(pad "1" smd roundrect
			(at -0.48 0 270)
			(size 0.59 0.64)
			(layers "B.Cu" "B.Mask" "B.Paste")
			(roundrect_rratio 0.25)
			(net 417 "GND")
			(pintype "passive")
		)
		(pad "2" smd roundrect
			(at 0.48 0 270)
			(size 0.59 0.64)
			(layers "B.Cu" "B.Mask" "B.Paste")
			(roundrect_rratio 0.25)
			(net 47 "+1V05")
			(pintype "passive")
		)
	)
	(footprint "antmicro-footprints:C_0402_1005Metric"
		(layer "B.Cu")
		(at 195.89 131.1 -90)
		(descr "Capacitor SMD 0402")
		(tags "capacitor SMD 0402")
		(property "Reference" "C38"
			(at 0.85 0.49 0)
			(layer "B.SilkS")
			(effects
				(font
					(size 0.7 0.7)
					(thickness 0.15)
				)
				(justify left bottom mirror)
			)
		)
		(property "Value" "C_4n7_0402"
			(at -1.022927 -2.155213 90)
			(layer "B.Fab")
			(hide yes)
			(effects
				(font
					(size 0.7 0.7)
					(thickness 0.15)
				)
				(justify left bottom mirror)
			)
		)
		(property "Datasheet" "https://product.tdk.com/en/search/capacitor/ceramic/mlcc/info?part_no=CGA2B3X7S2A472K050BB"
			(at 0 0 270)
			(layer "F.Fab")
			(hide yes)
			(effects
				(font
					(size 1.27 1.27)
					(thickness 0.15)
				)
			)
		)
		(property "Description" "SMD Multilayer Ceramic Capacitor, 4700 pF, 100 V, 0402 [1005 Metric], ± 10%, X7S, CGA"
			(at 0 0 270)
			(layer "F.Fab")
			(hide yes)
			(effects
				(font
					(size 1.27 1.27)
					(thickness 0.15)
				)
			)
		)
		(property "Author" "Antmicro"
			(at 64.79 326.99 0)
			(layer "B.Fab")
			(hide yes)
			(effects
				(font
					(size 1 1)
					(thickness 0.15)
				)
				(justify mirror)
			)
		)
		(property "Dielectric" "X7R"
			(at 64.79 326.99 0)
			(layer "B.Fab")
			(hide yes)
			(effects
				(font
					(size 1 1)
					(thickness 0.15)
				)
				(justify mirror)
			)
		)
		(property "License" "Apache-2.0"
			(at 64.79 326.99 0)
			(layer "B.Fab")
			(hide yes)
			(effects
				(font
					(size 1 1)
					(thickness 0.15)
				)
				(justify mirror)
			)
		)
		(property "MPN" "CGA2B3X7S2A472K050BB"
			(at 64.79 326.99 0)
			(layer "B.Fab")
			(hide yes)
			(effects
				(font
					(size 1 1)
					(thickness 0.15)
				)
				(justify mirror)
			)
		)
		(property "Manufacturer" "TDK"
			(at 64.79 326.99 0)
			(layer "B.Fab")
			(hide yes)
			(effects
				(font
					(size 1 1)
					(thickness 0.15)
				)
				(justify mirror)
			)
		)
		(property "Public" ""
			(at 64.79 326.99 0)
			(layer "B.Fab")
			(hide yes)
			(effects
				(font
					(size 1 1)
					(thickness 0.15)
				)
				(justify mirror)
			)
		)
		(property "Val" "4n7"
			(at 64.79 326.99 0)
			(layer "B.Fab")
			(hide yes)
			(effects
				(font
					(size 1 1)
					(thickness 0.15)
				)
				(justify mirror)
			)
		)
		(property "Voltage" "25V"
			(at 64.79 326.99 0)
			(layer "B.Fab")
			(hide yes)
			(effects
				(font
					(size 1 1)
					(thickness 0.15)
				)
				(justify mirror)
			)
		)
		(sheetname "/FPGA Supply/")
		(sheetfile "fpga-supply.kicad_sch")
		(attr smd)
		(fp_rect
			(start -0.925 0.47)
			(end 0.925 -0.47)
			(stroke
				(width 0.05)
				(type default)
			)
			(fill no)
			(layer "B.CrtYd")
		)
		(fp_line
			(start -0.494 0.25)
			(end 0.504 0.25)
			(stroke
				(width 0.15)
				(type solid)
			)
			(layer "B.Fab")
		)
		(fp_line
			(start 0.504 0.25)
			(end 0.504 -0.248)
			(stroke
				(width 0.15)
				(type solid)
			)
			(layer "B.Fab")
		)
		(fp_line
			(start -0.494 -0.248)
			(end -0.494 0.25)
			(stroke
				(width 0.15)
				(type solid)
			)
			(layer "B.Fab")
		)
		(fp_line
			(start 0.504 -0.248)
			(end -0.494 -0.248)
			(stroke
				(width 0.15)
				(type solid)
			)
			(layer "B.Fab")
		)
		(fp_text user "${REFERENCE}"
			(at -0.939 -4.599 90)
			(layer "B.Fab")
			(effects
				(font
					(size 0.7 0.7)
					(thickness 0.15)
				)
				(justify left bottom mirror)
			)
		)
		(fp_text user "License: Apache-2.0"
			(at -0.939 -5.799 90)
			(layer "B.Fab")
			(effects
				(font
					(size 0.7 0.7)
					(thickness 0.15)
				)
				(justify left bottom mirror)
			)
		)
		(fp_text user "Author: Antmicro"
			(at -0.939 -3.399 90)
			(layer "B.Fab")
			(effects
				(font
					(size 0.7 0.7)
					(thickness 0.15)
				)
				(justify left bottom mirror)
			)
		)
		(pad "1" smd roundrect
			(at -0.48 0 270)
			(size 0.59 0.64)
			(layers "B.Cu" "B.Mask" "B.Paste")
			(roundrect_rratio 0.25)
			(net 417 "GND")
			(pintype "passive")
		)
		(pad "2" smd roundrect
			(at 0.48 0 270)
			(size 0.59 0.64)
			(layers "B.Cu" "B.Mask" "B.Paste")
			(roundrect_rratio 0.25)
			(net 48 "+1V8")
			(pintype "passive")
		)
	)
	(footprint "antmicro-footprints:R_0402_1005Metric"
		(layer "B.Cu")
		(at 217.94 125.67 -135)
		(descr "Resistor SMD 0402")
		(tags "resistor SMD 0402")
		(property "Reference" "R102"
			(at 1.647559 -1.407142 225)
			(layer "B.SilkS")
			(effects
				(font
					(size 0.7 0.7)
					(thickness 0.15)
				)
				(justify right bottom mirror)
			)
		)
		(property "Value" "R_10k_0402"
			(at -1.011843 -1.772046 45)
			(layer "B.Fab")
			(hide yes)
			(effects
				(font
					(size 0.7 0.7)
					(thickness 0.15)
				)
				(justify left bottom mirror)
			)
		)
		(property "Datasheet" "https://www.bourns.com/docs/product-datasheets/cr.pdf"
			(at 0 0 225)
			(layer "F.Fab")
			(hide yes)
			(effects
				(font
					(size 1.27 1.27)
					(thickness 0.15)
				)
			)
		)
		(property "Description" "SMD Chip Resistor, 10 kohm, ± 1%, 62.5 mW, 0402 [1005 Metric], Thick Film, General Purpose"
			(at 0 0 225)
			(layer "F.Fab")
			(hide yes)
			(effects
				(font
					(size 1.27 1.27)
					(thickness 0.15)
				)
			)
		)
		(property "Author" "Antmicro"
			(at 283.184743 368.638961 0)
			(layer "B.Fab")
			(hide yes)
			(effects
				(font
					(size 1 1)
					(thickness 0.15)
				)
				(justify mirror)
			)
		)
		(property "License" "Apache-2.0"
			(at 283.184743 368.638961 0)
			(layer "B.Fab")
			(hide yes)
			(effects
				(font
					(size 1 1)
					(thickness 0.15)
				)
				(justify mirror)
			)
		)
		(property "MPN" "CR0402-FX-1002GLF"
			(at 283.184743 368.638961 0)
			(layer "B.Fab")
			(hide yes)
			(effects
				(font
					(size 1 1)
					(thickness 0.15)
				)
				(justify mirror)
			)
		)
		(property "Manufacturer" "Bourns"
			(at 283.184743 368.638961 0)
			(layer "B.Fab")
			(hide yes)
			(effects
				(font
					(size 1 1)
					(thickness 0.15)
				)
				(justify mirror)
			)
		)
		(property "Public" ""
			(at 283.184743 368.638961 0)
			(layer "B.Fab")
			(hide yes)
			(effects
				(font
					(size 1 1)
					(thickness 0.15)
				)
				(justify mirror)
			)
		)
		(property "Tolerance" "1%"
			(at 283.184743 368.638961 0)
			(layer "B.Fab")
			(hide yes)
			(effects
				(font
					(size 1 1)
					(thickness 0.15)
				)
				(justify mirror)
			)
		)
		(property "Val" "10k"
			(at 283.184743 368.638961 0)
			(layer "B.Fab")
			(hide yes)
			(effects
				(font
					(size 1 1)
					(thickness 0.15)
				)
				(justify mirror)
			)
		)
		(sheetname "/Ethernet/")
		(sheetfile "ethernet.kicad_sch")
		(attr smd)
		(fp_poly
			(pts
				(xy -0.925 0.47) (xy 0.925 0.47) (xy 0.925 -0.47) (xy -0.925 -0.47)
			)
			(stroke
				(width 0.05)
				(type default)
			)
			(fill no)
			(layer "B.CrtYd")
		)
		(fp_poly
			(pts
				(xy -0.5 0.25) (xy 0.5 0.25) (xy 0.5 -0.25) (xy -0.5 -0.25)
			)
			(stroke
				(width 0.15)
				(type solid)
			)
			(fill no)
			(layer "B.Fab")
		)
		(fp_text user "Author: Antmicro"
			(at -0.95 -4.169 45)
			(layer "B.Fab")
			(effects
				(font
					(size 0.7 0.7)
					(thickness 0.15)
				)
				(justify left bottom mirror)
			)
		)
		(fp_text user "License: Apache-2.0"
			(at -0.949999 -5.169 45)
			(layer "B.Fab")
			(effects
				(font
					(size 0.7 0.7)
					(thickness 0.15)
				)
				(justify left bottom mirror)
			)
		)
		(fp_text user "${REFERENCE}"
			(at -0.95 -3.168 45)
			(layer "B.Fab")
			(effects
				(font
					(size 0.7 0.7)
					(thickness 0.15)
				)
				(justify left bottom mirror)
			)
		)
		(pad "1" smd roundrect
			(at -0.48 0 225)
			(size 0.59 0.64)
			(layers "B.Cu" "B.Mask" "B.Paste")
			(roundrect_rratio 0.25)
			(net 617 "/Ethernet/LED0")
			(pintype "passive")
		)
		(pad "2" smd roundrect
			(at 0.48 0 225)
			(size 0.59 0.64)
			(layers "B.Cu" "B.Mask" "B.Paste")
			(roundrect_rratio 0.25)
			(net 50 "+3V3")
			(pintype "passive")
		)
	)
	(footprint "antmicro-footprints:C_0402_1005Metric"
		(layer "B.Cu")
		(at 215 141.3 90)
		(descr "Capacitor SMD 0402")
		(tags "capacitor SMD 0402")
		(property "Reference" "C186"
			(at 3.64 0.08 90)
			(layer "B.SilkS")
			(effects
				(font
					(size 0.7 0.7)
					(thickness 0.15)
				)
				(justify right bottom mirror)
			)
		)
		(property "Value" "C_100n_0402"
			(at -1.022927 -2.155213 90)
			(layer "B.Fab")
			(hide yes)
			(effects
				(font
					(size 0.7 0.7)
					(thickness 0.15)
				)
				(justify right bottom mirror)
			)
		)
		(property "Datasheet" "https://www.murata.com/products/productdetail?partno=GRM155R61H104KE14%23"
			(at 0 0 90)
			(layer "F.Fab")
			(hide yes)
			(effects
				(font
					(size 1.27 1.27)
					(thickness 0.15)
				)
			)
		)
		(property "Description" "SMD Multilayer Ceramic Capacitor, 0.1 µF, 50 V, 0402 [1005 Metric], ± 10%, X5R, GRM Series"
			(at 0 0 90)
			(layer "F.Fab")
			(hide yes)
			(effects
				(font
					(size 1.27 1.27)
					(thickness 0.15)
				)
			)
		)
		(property "Author" "Antmicro"
			(at 356.3 -73.7 0)
			(layer "B.Fab")
			(hide yes)
			(effects
				(font
					(size 1 1)
					(thickness 0.15)
				)
				(justify mirror)
			)
		)
		(property "Dielectric" "X5R"
			(at 356.3 -73.7 0)
			(layer "B.Fab")
			(hide yes)
			(effects
				(font
					(size 1 1)
					(thickness 0.15)
				)
				(justify mirror)
			)
		)
		(property "License" "Apache-2.0"
			(at 356.3 -73.7 0)
			(layer "B.Fab")
			(hide yes)
			(effects
				(font
					(size 1 1)
					(thickness 0.15)
				)
				(justify mirror)
			)
		)
		(property "MPN" "GRM155R61H104KE14D"
			(at 356.3 -73.7 0)
			(layer "B.Fab")
			(hide yes)
			(effects
				(font
					(size 1 1)
					(thickness 0.15)
				)
				(justify mirror)
			)
		)
		(property "Manufacturer" "Murata"
			(at 356.3 -73.7 0)
			(layer "B.Fab")
			(hide yes)
			(effects
				(font
					(size 1 1)
					(thickness 0.15)
				)
				(justify mirror)
			)
		)
		(property "Public" ""
			(at 356.3 -73.7 0)
			(layer "B.Fab")
			(hide yes)
			(effects
				(font
					(size 1 1)
					(thickness 0.15)
				)
				(justify mirror)
			)
		)
		(property "Val" "100n"
			(at 356.3 -73.7 0)
			(layer "B.Fab")
			(hide yes)
			(effects
				(font
					(size 1 1)
					(thickness 0.15)
				)
				(justify mirror)
			)
		)
		(property "Voltage" "50V"
			(at 356.3 -73.7 0)
			(layer "B.Fab")
			(hide yes)
			(effects
				(font
					(size 1 1)
					(thickness 0.15)
				)
				(justify mirror)
			)
		)
		(sheetname "/USB/")
		(sheetfile "usb.kicad_sch")
		(attr smd)
		(fp_rect
			(start -0.925 0.47)
			(end 0.925 -0.47)
			(stroke
				(width 0.05)
				(type default)
			)
			(fill no)
			(layer "B.CrtYd")
		)
		(fp_line
			(start 0.504 -0.248)
			(end -0.494 -0.248)
			(stroke
				(width 0.15)
				(type solid)
			)
			(layer "B.Fab")
		)
		(fp_line
			(start -0.494 -0.248)
			(end -0.494 0.25)
			(stroke
				(width 0.15)
				(type solid)
			)
			(layer "B.Fab")
		)
		(fp_line
			(start 0.504 0.25)
			(end 0.504 -0.248)
			(stroke
				(width 0.15)
				(type solid)
			)
			(layer "B.Fab")
		)
		(fp_line
			(start -0.494 0.25)
			(end 0.504 0.25)
			(stroke
				(width 0.15)
				(type solid)
			)
			(layer "B.Fab")
		)
		(fp_text user "Author: Antmicro"
			(at -0.939 -3.399 270)
			(layer "B.Fab")
			(effects
				(font
					(size 0.7 0.7)
					(thickness 0.15)
				)
				(justify left bottom mirror)
			)
		)
		(fp_text user "License: Apache-2.0"
			(at -0.939 -5.799 270)
			(layer "B.Fab")
			(effects
				(font
					(size 0.7 0.7)
					(thickness 0.15)
				)
				(justify left bottom mirror)
			)
		)
		(fp_text user "${REFERENCE}"
			(at -0.939 -4.599 270)
			(layer "B.Fab")
			(effects
				(font
					(size 0.7 0.7)
					(thickness 0.15)
				)
				(justify left bottom mirror)
			)
		)
		(pad "1" smd roundrect
			(at -0.48 0 90)
			(size 0.59 0.64)
			(layers "B.Cu" "B.Mask" "B.Paste")
			(roundrect_rratio 0.25)
			(net 417 "GND")
			(pintype "passive")
		)
		(pad "2" smd roundrect
			(at 0.48 0 90)
			(size 0.59 0.64)
			(layers "B.Cu" "B.Mask" "B.Paste")
			(roundrect_rratio 0.25)
			(net 152 "/USB/VDDIO")
			(pintype "passive")
		)
	)
	(footprint "antmicro-footprints:C_0402_1005Metric"
		(layer "B.Cu")
		(at 217.361 123.254 -90)
		(descr "Capacitor SMD 0402")
		(tags "capacitor SMD 0402")
		(property "Reference" "C219"
			(at 1.816 -3.409 90)
			(layer "B.SilkS")
			(effects
				(font
					(size 0.7 0.7)
					(thickness 0.15)
				)
				(justify left bottom mirror)
			)
		)
		(property "Value" "C_10u_0402"
			(at -1.022927 -2.155213 90)
			(layer "B.Fab")
			(hide yes)
			(effects
				(font
					(size 0.7 0.7)
					(thickness 0.15)
				)
				(justify left bottom mirror)
			)
		)
		(property "Datasheet" "https://www.yageo.com/en/Chart/Download/pdf/CC0402MRX5R5BB106"
			(at 0 0 270)
			(layer "F.Fab")
			(hide yes)
			(effects
				(font
					(size 1.27 1.27)
					(thickness 0.15)
				)
			)
		)
		(property "Description" "SMD Multilayer Ceramic Capacitor, 10 µF, 6.3 V, 0402 [1005 Metric], ± 20%, X5R, CC Series"
			(at 0 0 270)
			(layer "F.Fab")
			(hide yes)
			(effects
				(font
					(size 1.27 1.27)
					(thickness 0.15)
				)
			)
		)
		(property "Author" "Antmicro"
			(at 94.107 340.615 0)
			(layer "B.Fab")
			(hide yes)
			(effects
				(font
					(size 1 1)
					(thickness 0.15)
				)
				(justify mirror)
			)
		)
		(property "Dielectric" ""
			(at 94.107 340.615 0)
			(layer "B.Fab")
			(hide yes)
			(effects
				(font
					(size 1 1)
					(thickness 0.15)
				)
				(justify mirror)
			)
		)
		(property "License" "Apache-2.0"
			(at 94.107 340.615 0)
			(layer "B.Fab")
			(hide yes)
			(effects
				(font
					(size 1 1)
					(thickness 0.15)
				)
				(justify mirror)
			)
		)
		(property "MPN" "CC0402MRX5R5BB106"
			(at 94.107 340.615 0)
			(layer "B.Fab")
			(hide yes)
			(effects
				(font
					(size 1 1)
					(thickness 0.15)
				)
				(justify mirror)
			)
		)
		(property "Manufacturer" "YAGEO"
			(at 94.107 340.615 0)
			(layer "B.Fab")
			(hide yes)
			(effects
				(font
					(size 1 1)
					(thickness 0.15)
				)
				(justify mirror)
			)
		)
		(property "Public" ""
			(at 94.107 340.615 0)
			(layer "B.Fab")
			(hide yes)
			(effects
				(font
					(size 1 1)
					(thickness 0.15)
				)
				(justify mirror)
			)
		)
		(property "Val" "10u"
			(at 94.107 340.615 0)
			(layer "B.Fab")
			(hide yes)
			(effects
				(font
					(size 1 1)
					(thickness 0.15)
				)
				(justify mirror)
			)
		)
		(property "Voltage" ""
			(at 94.107 340.615 0)
			(layer "B.Fab")
			(hide yes)
			(effects
				(font
					(size 1 1)
					(thickness 0.15)
				)
				(justify mirror)
			)
		)
		(sheetname "/Ethernet/")
		(sheetfile "ethernet.kicad_sch")
		(attr smd)
		(fp_rect
			(start -0.925 0.47)
			(end 0.925 -0.47)
			(stroke
				(width 0.05)
				(type default)
			)
			(fill no)
			(layer "B.CrtYd")
		)
		(fp_line
			(start -0.494 0.25)
			(end 0.504 0.25)
			(stroke
				(width 0.15)
				(type solid)
			)
			(layer "B.Fab")
		)
		(fp_line
			(start 0.504 0.25)
			(end 0.504 -0.248)
			(stroke
				(width 0.15)
				(type solid)
			)
			(layer "B.Fab")
		)
		(fp_line
			(start -0.494 -0.248)
			(end -0.494 0.25)
			(stroke
				(width 0.15)
				(type solid)
			)
			(layer "B.Fab")
		)
		(fp_line
			(start 0.504 -0.248)
			(end -0.494 -0.248)
			(stroke
				(width 0.15)
				(type solid)
			)
			(layer "B.Fab")
		)
		(fp_text user "Author: Antmicro"
			(at -0.939 -3.399 90)
			(layer "B.Fab")
			(effects
				(font
					(size 0.7 0.7)
					(thickness 0.15)
				)
				(justify left bottom mirror)
			)
		)
		(fp_text user "License: Apache-2.0"
			(at -0.939 -5.799 90)
			(layer "B.Fab")
			(effects
				(font
					(size 0.7 0.7)
					(thickness 0.15)
				)
				(justify left bottom mirror)
			)
		)
		(fp_text user "${REFERENCE}"
			(at -0.939 -4.599 90)
			(layer "B.Fab")
			(effects
				(font
					(size 0.7 0.7)
					(thickness 0.15)
				)
				(justify left bottom mirror)
			)
		)
		(pad "1" smd roundrect
			(at -0.48 0 270)
			(size 0.59 0.64)
			(layers "B.Cu" "B.Mask" "B.Paste")
			(roundrect_rratio 0.25)
			(net 417 "GND")
			(pintype "passive")
		)
		(pad "2" smd roundrect
			(at 0.48 0 270)
			(size 0.59 0.64)
			(layers "B.Cu" "B.Mask" "B.Paste")
			(roundrect_rratio 0.25)
			(net 47 "+1V05")
			(pintype "passive")
		)
	)
	(footprint "antmicro-footprints:TP_SMD_0.75mm"
		(layer "B.Cu")
		(at 176.45 140.9 180)
		(property "Reference" "TP4"
			(at -1.875 0.1 45)
			(layer "B.SilkS")
			(hide yes)
			(effects
				(font
					(size 0.7 0.7)
					(thickness 0.15)
				)
				(justify left bottom mirror)
			)
		)
		(property "Value" "TP_0.75mm_SMD"
			(at 0 -1.2 0)
			(layer "B.Fab")
			(hide yes)
			(effects
				(font
					(size 0.7 0.7)
					(thickness 0.15)
				)
				(justify left bottom mirror)
			)
		)
		(property "Description" "SMT test point"
			(at 0 0 0)
			(layer "B.Fab")
			(hide yes)
			(effects
				(font
					(size 1.27 1.27)
					(thickness 0.15)
				)
				(justify mirror)
			)
		)
		(property "MPN" ""
			(at 0 0 0)
			(unlocked yes)
			(layer "B.Fab")
			(hide yes)
			(effects
				(font
					(size 1 1)
					(thickness 0.15)
				)
				(justify mirror)
			)
		)
		(property "Manufacturer" ""
			(at 0 0 0)
			(unlocked yes)
			(layer "B.Fab")
			(hide yes)
			(effects
				(font
					(size 1 1)
					(thickness 0.15)
				)
				(justify mirror)
			)
		)
		(property "Author" "Antmicro"
			(at 0 0 0)
			(unlocked yes)
			(layer "B.Fab")
			(hide yes)
			(effects
				(font
					(size 1 1)
					(thickness 0.15)
				)
				(justify mirror)
			)
		)
		(property "License" "Apache-2.0"
			(at 0 0 0)
			(unlocked yes)
			(layer "B.Fab")
			(hide yes)
			(effects
				(font
					(size 1 1)
					(thickness 0.15)
				)
				(justify mirror)
			)
		)
		(property "Public" "False"
			(at 0 0 0)
			(unlocked yes)
			(layer "B.Fab")
			(hide yes)
			(effects
				(font
					(size 1 1)
					(thickness 0.15)
				)
				(justify mirror)
			)
		)
		(sheetname "/Supply/")
		(sheetfile "supply.kicad_sch")
		(attr exclude_from_pos_files exclude_from_bom)
		(fp_circle
			(center 0 0)
			(end 0.475 0)
			(stroke
				(width 0.05)
				(type default)
			)
			(fill no)
			(layer "B.CrtYd")
		)
		(fp_text user "Author: Antmicro"
			(at -0.4 -3.901 0)
			(layer "B.Fab")
			(effects
				(font
					(size 0.7 0.7)
					(thickness 0.15)
				)
				(justify left bottom mirror)
			)
		)
		(fp_text user "License: Apache-2.0"
			(at -0.4 -5.101 0)
			(layer "B.Fab")
			(effects
				(font
					(size 0.7 0.7)
					(thickness 0.15)
				)
				(justify left bottom mirror)
			)
		)
		(fp_text user "${REFERENCE}"
			(at -0.4 -2.7 0)
			(layer "B.Fab")
			(effects
				(font
					(size 0.7 0.7)
					(thickness 0.15)
				)
				(justify left bottom mirror)
			)
		)
		(pad "1" smd circle
			(at 0 0 180)
			(size 0.75 0.75)
			(layers "B.Cu" "B.Mask")
			(net 209 "/Supply/SENSE1_P")
			(pinfunction "1")
			(pintype "passive")
		)
	)
	(footprint "antmicro-footprints:C_0402_1005Metric"
		(layer "B.Cu")
		(at 195.3 126.8 180)
		(descr "Capacitor SMD 0402")
		(tags "capacitor SMD 0402")
		(property "Reference" "C9"
			(at 0.85 0.125 0)
			(layer "B.SilkS")
			(effects
				(font
					(size 0.7 0.7)
					(thickness 0.15)
				)
				(justify left bottom mirror)
			)
		)
		(property "Value" "C_4n7_0402"
			(at -1.022927 -2.155213 0)
			(layer "B.Fab")
			(hide yes)
			(effects
				(font
					(size 0.7 0.7)
					(thickness 0.15)
				)
				(justify left bottom mirror)
			)
		)
		(property "Datasheet" "https://product.tdk.com/en/search/capacitor/ceramic/mlcc/info?part_no=CGA2B3X7S2A472K050BB"
			(at 0 0 180)
			(layer "F.Fab")
			(hide yes)
			(effects
				(font
					(size 1.27 1.27)
					(thickness 0.15)
				)
			)
		)
		(property "Description" "SMD Multilayer Ceramic Capacitor, 4700 pF, 100 V, 0402 [1005 Metric], ± 10%, X7S, CGA"
			(at 0 0 180)
			(layer "F.Fab")
			(hide yes)
			(effects
				(font
					(size 1.27 1.27)
					(thickness 0.15)
				)
			)
		)
		(property "Author" "Antmicro"
			(at 390.6 253.6 0)
			(layer "B.Fab")
			(hide yes)
			(effects
				(font
					(size 1 1)
					(thickness 0.15)
				)
				(justify mirror)
			)
		)
		(property "Dielectric" "X7R"
			(at 390.6 253.6 0)
			(layer "B.Fab")
			(hide yes)
			(effects
				(font
					(size 1 1)
					(thickness 0.15)
				)
				(justify mirror)
			)
		)
		(property "License" "Apache-2.0"
			(at 390.6 253.6 0)
			(layer "B.Fab")
			(hide yes)
			(effects
				(font
					(size 1 1)
					(thickness 0.15)
				)
				(justify mirror)
			)
		)
		(property "MPN" "CGA2B3X7S2A472K050BB"
			(at 390.6 253.6 0)
			(layer "B.Fab")
			(hide yes)
			(effects
				(font
					(size 1 1)
					(thickness 0.15)
				)
				(justify mirror)
			)
		)
		(property "Manufacturer" "TDK"
			(at 390.6 253.6 0)
			(layer "B.Fab")
			(hide yes)
			(effects
				(font
					(size 1 1)
					(thickness 0.15)
				)
				(justify mirror)
			)
		)
		(property "Public" ""
			(at 390.6 253.6 0)
			(layer "B.Fab")
			(hide yes)
			(effects
				(font
					(size 1 1)
					(thickness 0.15)
				)
				(justify mirror)
			)
		)
		(property "Val" "4n7"
			(at 390.6 253.6 0)
			(layer "B.Fab")
			(hide yes)
			(effects
				(font
					(size 1 1)
					(thickness 0.15)
				)
				(justify mirror)
			)
		)
		(property "Voltage" "25V"
			(at 390.6 253.6 0)
			(layer "B.Fab")
			(hide yes)
			(effects
				(font
					(size 1 1)
					(thickness 0.15)
				)
				(justify mirror)
			)
		)
		(sheetname "/FPGA Supply/")
		(sheetfile "fpga-supply.kicad_sch")
		(attr smd)
		(fp_rect
			(start -0.925 0.47)
			(end 0.925 -0.47)
			(stroke
				(width 0.05)
				(type default)
			)
			(fill no)
			(layer "B.CrtYd")
		)
		(fp_line
			(start 0.504 0.25)
			(end 0.504 -0.248)
			(stroke
				(width 0.15)
				(type solid)
			)
			(layer "B.Fab")
		)
		(fp_line
			(start 0.504 -0.248)
			(end -0.494 -0.248)
			(stroke
				(width 0.15)
				(type solid)
			)
			(layer "B.Fab")
		)
		(fp_line
			(start -0.494 0.25)
			(end 0.504 0.25)
			(stroke
				(width 0.15)
				(type solid)
			)
			(layer "B.Fab")
		)
		(fp_line
			(start -0.494 -0.248)
			(end -0.494 0.25)
			(stroke
				(width 0.15)
				(type solid)
			)
			(layer "B.Fab")
		)
		(fp_text user "${REFERENCE}"
			(at -0.939 -4.599 0)
			(layer "B.Fab")
			(effects
				(font
					(size 0.7 0.7)
					(thickness 0.15)
				)
				(justify left bottom mirror)
			)
		)
		(fp_text user "Author: Antmicro"
			(at -0.939 -3.399 0)
			(layer "B.Fab")
			(effects
				(font
					(size 0.7 0.7)
					(thickness 0.15)
				)
				(justify left bottom mirror)
			)
		)
		(fp_text user "License: Apache-2.0"
			(at -0.939 -5.799 0)
			(layer "B.Fab")
			(effects
				(font
					(size 0.7 0.7)
					(thickness 0.15)
				)
				(justify left bottom mirror)
			)
		)
		(pad "1" smd roundrect
			(at -0.48 0 180)
			(size 0.59 0.64)
			(layers "B.Cu" "B.Mask" "B.Paste")
			(roundrect_rratio 0.25)
			(net 417 "GND")
			(pintype "passive")
		)
		(pad "2" smd roundrect
			(at 0.48 0 180)
			(size 0.59 0.64)
			(layers "B.Cu" "B.Mask" "B.Paste")
			(roundrect_rratio 0.25)
			(net 2 "+1V1")
			(pintype "passive")
		)
	)
	(footprint "antmicro-footprints:R_0402_1005Metric"
		(layer "B.Cu")
		(at 208.25 134.35 180)
		(descr "Resistor SMD 0402")
		(tags "resistor SMD 0402")
		(property "Reference" "R39"
			(at 0.85 -0.4 0)
			(layer "B.SilkS")
			(effects
				(font
					(size 0.7 0.7)
					(thickness 0.15)
				)
				(justify left bottom mirror)
			)
		)
		(property "Value" "R_4k7_0402"
			(at -1.011843 -1.772047 0)
			(layer "B.Fab")
			(hide yes)
			(effects
				(font
					(size 0.7 0.7)
					(thickness 0.15)
				)
				(justify left bottom mirror)
			)
		)
		(property "Datasheet" "https://www.bourns.com/docs/product-datasheets/cr.pdf"
			(at 0 0 180)
			(layer "F.Fab")
			(hide yes)
			(effects
				(font
					(size 1.27 1.27)
					(thickness 0.15)
				)
			)
		)
		(property "Description" "SMD Chip Resistor, 4.7 kohm, ± 1%, 62.5 mW, 0402 [1005 Metric], Thick Film, General Purpose"
			(at 0 0 180)
			(layer "F.Fab")
			(hide yes)
			(effects
				(font
					(size 1.27 1.27)
					(thickness 0.15)
				)
			)
		)
		(property "Author" "Antmicro"
			(at 416.5 268.7 0)
			(layer "B.Fab")
			(hide yes)
			(effects
				(font
					(size 1 1)
					(thickness 0.15)
				)
				(justify mirror)
			)
		)
		(property "DNP" "DNP"
			(at 416.5 268.7 0)
			(layer "B.Fab")
			(hide yes)
			(effects
				(font
					(size 1 1)
					(thickness 0.15)
				)
				(justify mirror)
			)
		)
		(property "License" "Apache-2.0"
			(at 416.5 268.7 0)
			(layer "B.Fab")
			(hide yes)
			(effects
				(font
					(size 1 1)
					(thickness 0.15)
				)
				(justify mirror)
			)
		)
		(property "MPN" "CR0402-FX-4701GLF"
			(at 416.5 268.7 0)
			(layer "B.Fab")
			(hide yes)
			(effects
				(font
					(size 1 1)
					(thickness 0.15)
				)
				(justify mirror)
			)
		)
		(property "Manufacturer" "Bourns"
			(at 416.5 268.7 0)
			(layer "B.Fab")
			(hide yes)
			(effects
				(font
					(size 1 1)
					(thickness 0.15)
				)
				(justify mirror)
			)
		)
		(property "Public" ""
			(at 416.5 268.7 0)
			(layer "B.Fab")
			(hide yes)
			(effects
				(font
					(size 1 1)
					(thickness 0.15)
				)
				(justify mirror)
			)
		)
		(property "Tolerance" "1%"
			(at 416.5 268.7 0)
			(layer "B.Fab")
			(hide yes)
			(effects
				(font
					(size 1 1)
					(thickness 0.15)
				)
				(justify mirror)
			)
		)
		(property "Val" "4k7"
			(at 416.5 268.7 0)
			(layer "B.Fab")
			(hide yes)
			(effects
				(font
					(size 1 1)
					(thickness 0.15)
				)
				(justify mirror)
			)
		)
		(sheetname "/FPGA Config/")
		(sheetfile "fpga-config.kicad_sch")
		(attr smd dnp)
		(fp_rect
			(start -0.925 0.47)
			(end 0.925 -0.47)
			(stroke
				(width 0.05)
				(type default)
			)
			(fill no)
			(layer "B.CrtYd")
		)
		(fp_rect
			(start -0.5 0.25)
			(end 0.5 -0.25)
			(stroke
				(width 0.15)
				(type solid)
			)
			(fill no)
			(layer "B.Fab")
		)
		(fp_text user "${REFERENCE}"
			(at -0.95 -3.168 0)
			(layer "B.Fab")
			(effects
				(font
					(size 0.7 0.7)
					(thickness 0.15)
				)
				(justify left bottom mirror)
			)
		)
		(fp_text user "License: Apache-2.0"
			(at -0.95 -5.169 0)
			(layer "B.Fab")
			(effects
				(font
					(size 0.7 0.7)
					(thickness 0.15)
				)
				(justify left bottom mirror)
			)
		)
		(fp_text user "Author: Antmicro"
			(at -0.95 -4.169 0)
			(layer "B.Fab")
			(effects
				(font
					(size 0.7 0.7)
					(thickness 0.15)
				)
				(justify left bottom mirror)
			)
		)
		(pad "1" smd roundrect
			(at -0.48 0 180)
			(size 0.59 0.64)
			(layers "B.Cu" "B.Mask" "B.Paste")
			(roundrect_rratio 0.25)
			(net 50 "+3V3")
			(pintype "passive")
		)
		(pad "2" smd roundrect
			(at 0.48 0 180)
			(size 0.59 0.64)
			(layers "B.Cu" "B.Mask" "B.Paste")
			(roundrect_rratio 0.25)
			(net 254 "Net-(U1D-FF_EXIT_N)")
			(pintype "passive")
		)
	)
	(footprint "antmicro-footprints:C_0402_1005Metric"
		(layer "B.Cu")
		(at 208.1 149.38 180)
		(descr "Capacitor SMD 0402")
		(tags "capacitor SMD 0402")
		(property "Reference" "C249"
			(at 4.9 18.375 0)
			(layer "B.SilkS")
			(effects
				(font
					(size 0.7 0.7)
					(thickness 0.15)
				)
				(justify left bottom mirror)
			)
		)
		(property "Value" "C_10u_10V_0402"
			(at -1.022927 -2.155213 0)
			(layer "B.Fab")
			(hide yes)
			(effects
				(font
					(size 0.7 0.7)
					(thickness 0.15)
				)
				(justify left bottom mirror)
			)
		)
		(property "Datasheet" "https://www.murata.com/products/productdetail?partno=GRM155R61A106ME11%23"
			(at 0 0 180)
			(layer "F.Fab")
			(hide yes)
			(effects
				(font
					(size 1.27 1.27)
					(thickness 0.15)
				)
			)
		)
		(property "Description" "Multilayer Ceramic Capacitors MLCC - SMD/SMT 10 uF 10 VDC 20% 0402 X5R"
			(at 0 0 180)
			(layer "F.Fab")
			(hide yes)
			(effects
				(font
					(size 1.27 1.27)
					(thickness 0.15)
				)
			)
		)
		(property "Author" "Antmicro"
			(at 416.2 298.76 0)
			(layer "B.Fab")
			(hide yes)
			(effects
				(font
					(size 1 1)
					(thickness 0.15)
				)
				(justify mirror)
			)
		)
		(property "Dielectric" "X5R"
			(at 416.2 298.76 0)
			(layer "B.Fab")
			(hide yes)
			(effects
				(font
					(size 1 1)
					(thickness 0.15)
				)
				(justify mirror)
			)
		)
		(property "License" "Apache-2.0"
			(at 416.2 298.76 0)
			(layer "B.Fab")
			(hide yes)
			(effects
				(font
					(size 1 1)
					(thickness 0.15)
				)
				(justify mirror)
			)
		)
		(property "MPN" "GRM155R61A106ME11D"
			(at 416.2 298.76 0)
			(layer "B.Fab")
			(hide yes)
			(effects
				(font
					(size 1 1)
					(thickness 0.15)
				)
				(justify mirror)
			)
		)
		(property "Manufacturer" "Murata"
			(at 416.2 298.76 0)
			(layer "B.Fab")
			(hide yes)
			(effects
				(font
					(size 1 1)
					(thickness 0.15)
				)
				(justify mirror)
			)
		)
		(property "Public" ""
			(at 416.2 298.76 0)
			(layer "B.Fab")
			(hide yes)
			(effects
				(font
					(size 1 1)
					(thickness 0.15)
				)
				(justify mirror)
			)
		)
		(property "Val" "10u"
			(at 416.2 298.76 0)
			(layer "B.Fab")
			(hide yes)
			(effects
				(font
					(size 1 1)
					(thickness 0.15)
				)
				(justify mirror)
			)
		)
		(property "Voltage" "10V"
			(at 416.2 298.76 0)
			(layer "B.Fab")
			(hide yes)
			(effects
				(font
					(size 1 1)
					(thickness 0.15)
				)
				(justify mirror)
			)
		)
		(sheetname "/MIPI CrossLink/")
		(sheetfile "crosslink.kicad_sch")
		(attr smd)
		(fp_rect
			(start -0.925 0.47)
			(end 0.925 -0.47)
			(stroke
				(width 0.05)
				(type default)
			)
			(fill no)
			(layer "B.CrtYd")
		)
		(fp_line
			(start 0.504 0.25)
			(end 0.504 -0.248)
			(stroke
				(width 0.15)
				(type solid)
			)
			(layer "B.Fab")
		)
		(fp_line
			(start 0.504 -0.248)
			(end -0.494 -0.248)
			(stroke
				(width 0.15)
				(type solid)
			)
			(layer "B.Fab")
		)
		(fp_line
			(start -0.494 0.25)
			(end 0.504 0.25)
			(stroke
				(width 0.15)
				(type solid)
			)
			(layer "B.Fab")
		)
		(fp_line
			(start -0.494 -0.248)
			(end -0.494 0.25)
			(stroke
				(width 0.15)
				(type solid)
			)
			(layer "B.Fab")
		)
		(fp_text user "License: Apache-2.0"
			(at -0.939 -5.799 0)
			(layer "B.Fab")
			(effects
				(font
					(size 0.7 0.7)
					(thickness 0.15)
				)
				(justify left bottom mirror)
			)
		)
		(fp_text user "${REFERENCE}"
			(at -0.939 -4.599 0)
			(layer "B.Fab")
			(effects
				(font
					(size 0.7 0.7)
					(thickness 0.15)
				)
				(justify left bottom mirror)
			)
		)
		(fp_text user "Author: Antmicro"
			(at -0.939 -3.399 0)
			(layer "B.Fab")
			(effects
				(font
					(size 0.7 0.7)
					(thickness 0.15)
				)
				(justify left bottom mirror)
			)
		)
		(pad "1" smd roundrect
			(at -0.48 0 180)
			(size 0.59 0.64)
			(layers "B.Cu" "B.Mask" "B.Paste")
			(roundrect_rratio 0.25)
			(net 417 "GND")
			(pintype "passive")
		)
		(pad "2" smd roundrect
			(at 0.48 0 180)
			(size 0.59 0.64)
			(layers "B.Cu" "B.Mask" "B.Paste")
			(roundrect_rratio 0.25)
			(net 211 "/MIPI CrossLink/CL_VCCPLL_DPHY1")
			(pintype "passive")
		)
	)
	(footprint "antmicro-footprints:TP_SMD_0.75mm"
		(layer "B.Cu")
		(at 190.75 144.95 180)
		(property "Reference" "TP38"
			(at 0 0.6 0)
			(layer "B.SilkS")
			(hide yes)
			(effects
				(font
					(size 0.7 0.7)
					(thickness 0.15)
				)
				(justify left bottom mirror)
			)
		)
		(property "Value" "TP_0.75mm_SMD"
			(at 0 -1.2 0)
			(layer "B.Fab")
			(hide yes)
			(effects
				(font
					(size 0.7 0.7)
					(thickness 0.15)
				)
				(justify left bottom mirror)
			)
		)
		(property "Description" "SMT test point"
			(at 0 0 0)
			(layer "B.Fab")
			(hide yes)
			(effects
				(font
					(size 1.27 1.27)
					(thickness 0.15)
				)
				(justify mirror)
			)
		)
		(property "MPN" ""
			(at 0 0 0)
			(unlocked yes)
			(layer "B.Fab")
			(hide yes)
			(effects
				(font
					(size 1 1)
					(thickness 0.15)
				)
				(justify mirror)
			)
		)
		(property "Manufacturer" ""
			(at 0 0 0)
			(unlocked yes)
			(layer "B.Fab")
			(hide yes)
			(effects
				(font
					(size 1 1)
					(thickness 0.15)
				)
				(justify mirror)
			)
		)
		(property "Author" "Antmicro"
			(at 0 0 0)
			(unlocked yes)
			(layer "B.Fab")
			(hide yes)
			(effects
				(font
					(size 1 1)
					(thickness 0.15)
				)
				(justify mirror)
			)
		)
		(property "License" "Apache-2.0"
			(at 0 0 0)
			(unlocked yes)
			(layer "B.Fab")
			(hide yes)
			(effects
				(font
					(size 1 1)
					(thickness 0.15)
				)
				(justify mirror)
			)
		)
		(property "Public" "False"
			(at 0 0 0)
			(unlocked yes)
			(layer "B.Fab")
			(hide yes)
			(effects
				(font
					(size 1 1)
					(thickness 0.15)
				)
				(justify mirror)
			)
		)
		(sheetname "/Supply/")
		(sheetfile "supply.kicad_sch")
		(attr exclude_from_pos_files exclude_from_bom)
		(fp_circle
			(center 0 0)
			(end 0.475 0)
			(stroke
				(width 0.05)
				(type default)
			)
			(fill no)
			(layer "B.CrtYd")
		)
		(fp_text user "Author: Antmicro"
			(at -0.4 -3.901 0)
			(layer "B.Fab")
			(effects
				(font
					(size 0.7 0.7)
					(thickness 0.15)
				)
				(justify left bottom mirror)
			)
		)
		(fp_text user "${REFERENCE}"
			(at -0.4 -2.7 0)
			(layer "B.Fab")
			(effects
				(font
					(size 0.7 0.7)
					(thickness 0.15)
				)
				(justify left bottom mirror)
			)
		)
		(fp_text user "License: Apache-2.0"
			(at -0.4 -5.101 0)
			(layer "B.Fab")
			(effects
				(font
					(size 0.7 0.7)
					(thickness 0.15)
				)
				(justify left bottom mirror)
			)
		)
		(pad "1" smd circle
			(at 0 0 180)
			(size 0.75 0.75)
			(layers "B.Cu" "B.Mask")
			(net 417 "GND")
			(pinfunction "1")
			(pintype "passive")
		)
	)
	(footprint "antmicro-footprints:R_0402_1005Metric"
		(layer "B.Cu")
		(at 216.015 142.6 -90)
		(descr "Resistor SMD 0402")
		(tags "resistor SMD 0402")
		(property "Reference" "R66"
			(at -1.15 -1.435 90)
			(layer "B.SilkS")
			(effects
				(font
					(size 0.7 0.7)
					(thickness 0.15)
				)
				(justify left bottom mirror)
			)
		)
		(property "Value" "R_270k_0402"
			(at -1.011843 -1.772047 90)
			(layer "B.Fab")
			(hide yes)
			(effects
				(font
					(size 0.7 0.7)
					(thickness 0.15)
				)
				(justify left bottom mirror)
			)
		)
		(property "Datasheet" "https://www.bourns.com/docs/product-datasheets/cr.pdf"
			(at 0 0 270)
			(layer "F.Fab")
			(hide yes)
			(effects
				(font
					(size 1.27 1.27)
					(thickness 0.15)
				)
			)
		)
		(property "Description" "SMD Chip Resistor"
			(at 0 0 270)
			(layer "F.Fab")
			(hide yes)
			(effects
				(font
					(size 1.27 1.27)
					(thickness 0.15)
				)
			)
		)
		(property "Author" "Antmicro"
			(at 73.415 358.615 0)
			(layer "B.Fab")
			(hide yes)
			(effects
				(font
					(size 1 1)
					(thickness 0.15)
				)
				(justify mirror)
			)
		)
		(property "License" "Apache-2.0"
			(at 73.415 358.615 0)
			(layer "B.Fab")
			(hide yes)
			(effects
				(font
					(size 1 1)
					(thickness 0.15)
				)
				(justify mirror)
			)
		)
		(property "MPN" "CR0402-FX-2703GLF"
			(at 73.415 358.615 0)
			(layer "B.Fab")
			(hide yes)
			(effects
				(font
					(size 1 1)
					(thickness 0.15)
				)
				(justify mirror)
			)
		)
		(property "Manufacturer" "Bourns"
			(at 73.415 358.615 0)
			(layer "B.Fab")
			(hide yes)
			(effects
				(font
					(size 1 1)
					(thickness 0.15)
				)
				(justify mirror)
			)
		)
		(property "Public" ""
			(at 73.415 358.615 0)
			(layer "B.Fab")
			(hide yes)
			(effects
				(font
					(size 1 1)
					(thickness 0.15)
				)
				(justify mirror)
			)
		)
		(property "Tolerance" "1%"
			(at 73.415 358.615 0)
			(layer "B.Fab")
			(hide yes)
			(effects
				(font
					(size 1 1)
					(thickness 0.15)
				)
				(justify mirror)
			)
		)
		(property "Val" "270k"
			(at 73.415 358.615 0)
			(layer "B.Fab")
			(hide yes)
			(effects
				(font
					(size 1 1)
					(thickness 0.15)
				)
				(justify mirror)
			)
		)
		(sheetname "/USB/")
		(sheetfile "usb.kicad_sch")
		(attr smd)
		(fp_rect
			(start -0.925 0.47)
			(end 0.925 -0.47)
			(stroke
				(width 0.05)
				(type default)
			)
			(fill no)
			(layer "B.CrtYd")
		)
		(fp_rect
			(start -0.5 0.25)
			(end 0.5 -0.25)
			(stroke
				(width 0.15)
				(type solid)
			)
			(fill no)
			(layer "B.Fab")
		)
		(fp_text user "License: Apache-2.0"
			(at -0.95 -5.169 90)
			(layer "B.Fab")
			(effects
				(font
					(size 0.7 0.7)
					(thickness 0.15)
				)
				(justify left bottom mirror)
			)
		)
		(fp_text user "Author: Antmicro"
			(at -0.95 -4.169 90)
			(layer "B.Fab")
			(effects
				(font
					(size 0.7 0.7)
					(thickness 0.15)
				)
				(justify left bottom mirror)
			)
		)
		(fp_text user "${REFERENCE}"
			(at -0.95 -3.168 90)
			(layer "B.Fab")
			(effects
				(font
					(size 0.7 0.7)
					(thickness 0.15)
				)
				(justify left bottom mirror)
			)
		)
		(pad "1" smd roundrect
			(at -0.48 0 270)
			(size 0.59 0.64)
			(layers "B.Cu" "B.Mask" "B.Paste")
			(roundrect_rratio 0.25)
			(net 636 "/FPGA GPIO/ULPI.CLK")
			(pintype "passive")
		)
		(pad "2" smd roundrect
			(at 0.48 0 270)
			(size 0.59 0.64)
			(layers "B.Cu" "B.Mask" "B.Paste")
			(roundrect_rratio 0.25)
			(net 152 "/USB/VDDIO")
			(pintype "passive")
		)
	)
	(footprint "antmicro-footprints:C_0402_1005Metric"
		(layer "B.Cu")
		(at 197.99 134.73 90)
		(descr "Capacitor SMD 0402")
		(tags "capacitor SMD 0402")
		(property "Reference" "C55"
			(at 6.98 -9.565 270)
			(layer "B.SilkS")
			(effects
				(font
					(size 0.7 0.7)
					(thickness 0.15)
				)
				(justify left bottom mirror)
			)
		)
		(property "Value" "C_10n_0402"
			(at -1.022927 -2.155213 270)
			(layer "B.Fab")
			(hide yes)
			(effects
				(font
					(size 0.7 0.7)
					(thickness 0.15)
				)
				(justify left bottom mirror)
			)
		)
		(property "Datasheet" "https://www.murata.com/products/productdetail?partno=GRM155R71H103KA88%23"
			(at 0 0 90)
			(layer "F.Fab")
			(hide yes)
			(effects
				(font
					(size 1.27 1.27)
					(thickness 0.15)
				)
			)
		)
		(property "Description" "SMD Multilayer Ceramic Capacitor, 10000 pF, 50 V, 0402 [1005 Metric], ± 10%, X7R, GRM Series"
			(at 0 0 90)
			(layer "F.Fab")
			(hide yes)
			(effects
				(font
					(size 1.27 1.27)
					(thickness 0.15)
				)
			)
		)
		(property "Author" "Antmicro"
			(at 332.72 -63.26 0)
			(layer "B.Fab")
			(hide yes)
			(effects
				(font
					(size 1 1)
					(thickness 0.15)
				)
				(justify mirror)
			)
		)
		(property "Dielectric" "X7R"
			(at 332.72 -63.26 0)
			(layer "B.Fab")
			(hide yes)
			(effects
				(font
					(size 1 1)
					(thickness 0.15)
				)
				(justify mirror)
			)
		)
		(property "License" "Apache-2.0"
			(at 332.72 -63.26 0)
			(layer "B.Fab")
			(hide yes)
			(effects
				(font
					(size 1 1)
					(thickness 0.15)
				)
				(justify mirror)
			)
		)
		(property "MPN" "GRM155R71H103KA88D"
			(at 332.72 -63.26 0)
			(layer "B.Fab")
			(hide yes)
			(effects
				(font
					(size 1 1)
					(thickness 0.15)
				)
				(justify mirror)
			)
		)
		(property "Manufacturer" "Murata"
			(at 332.72 -63.26 0)
			(layer "B.Fab")
			(hide yes)
			(effects
				(font
					(size 1 1)
					(thickness 0.15)
				)
				(justify mirror)
			)
		)
		(property "Public" ""
			(at 332.72 -63.26 0)
			(layer "B.Fab")
			(hide yes)
			(effects
				(font
					(size 1 1)
					(thickness 0.15)
				)
				(justify mirror)
			)
		)
		(property "Val" "10n"
			(at 332.72 -63.26 0)
			(layer "B.Fab")
			(hide yes)
			(effects
				(font
					(size 1 1)
					(thickness 0.15)
				)
				(justify mirror)
			)
		)
		(property "Voltage" "50V"
			(at 332.72 -63.26 0)
			(layer "B.Fab")
			(hide yes)
			(effects
				(font
					(size 1 1)
					(thickness 0.15)
				)
				(justify mirror)
			)
		)
		(sheetname "/FPGA Supply/")
		(sheetfile "fpga-supply.kicad_sch")
		(attr smd)
		(fp_rect
			(start -0.925 0.47)
			(end 0.925 -0.47)
			(stroke
				(width 0.05)
				(type default)
			)
			(fill no)
			(layer "B.CrtYd")
		)
		(fp_line
			(start 0.504 -0.248)
			(end -0.494 -0.248)
			(stroke
				(width 0.15)
				(type solid)
			)
			(layer "B.Fab")
		)
		(fp_line
			(start -0.494 -0.248)
			(end -0.494 0.25)
			(stroke
				(width 0.15)
				(type solid)
			)
			(layer "B.Fab")
		)
		(fp_line
			(start 0.504 0.25)
			(end 0.504 -0.248)
			(stroke
				(width 0.15)
				(type solid)
			)
			(layer "B.Fab")
		)
		(fp_line
			(start -0.494 0.25)
			(end 0.504 0.25)
			(stroke
				(width 0.15)
				(type solid)
			)
			(layer "B.Fab")
		)
		(fp_text user "License: Apache-2.0"
			(at -0.939 -5.799 270)
			(layer "B.Fab")
			(effects
				(font
					(size 0.7 0.7)
					(thickness 0.15)
				)
				(justify left bottom mirror)
			)
		)
		(fp_text user "Author: Antmicro"
			(at -0.939 -3.399 270)
			(layer "B.Fab")
			(effects
				(font
					(size 0.7 0.7)
					(thickness 0.15)
				)
				(justify left bottom mirror)
			)
		)
		(fp_text user "${REFERENCE}"
			(at -0.939 -4.599 270)
			(layer "B.Fab")
			(effects
				(font
					(size 0.7 0.7)
					(thickness 0.15)
				)
				(justify left bottom mirror)
			)
		)
		(pad "1" smd roundrect
			(at -0.48 0 90)
			(size 0.59 0.64)
			(layers "B.Cu" "B.Mask" "B.Paste")
			(roundrect_rratio 0.25)
			(net 417 "GND")
			(pintype "passive")
		)
		(pad "2" smd roundrect
			(at 0.48 0 90)
			(size 0.59 0.64)
			(layers "B.Cu" "B.Mask" "B.Paste")
			(roundrect_rratio 0.25)
			(net 47 "+1V05")
			(pintype "passive")
		)
	)
	(footprint "antmicro-footprints:C_0402_1005Metric"
		(layer "B.Cu")
		(at 203.51 135.96 -90)
		(descr "Capacitor SMD 0402")
		(tags "capacitor SMD 0402")
		(property "Reference" "C52"
			(at -3.06 -0.49 90)
			(layer "B.SilkS")
			(effects
				(font
					(size 0.7 0.7)
					(thickness 0.15)
				)
				(justify left bottom mirror)
			)
		)
		(property "Value" "C_1n_0402"
			(at -1.022927 -2.155213 90)
			(layer "B.Fab")
			(hide yes)
			(effects
				(font
					(size 0.7 0.7)
					(thickness 0.15)
				)
				(justify left bottom mirror)
			)
		)
		(property "Datasheet" "https://www.murata.com/products/productdetail?partno=GRM1555C1H102JA01%23"
			(at 0 0 270)
			(layer "F.Fab")
			(hide yes)
			(effects
				(font
					(size 1.27 1.27)
					(thickness 0.15)
				)
			)
		)
		(property "Description" "SMD Multilayer Ceramic Capacitor, 1000 pF, 50 V, 0402 [1005 Metric], ± 5%, C0G / NP0, GRM Series"
			(at 0 0 270)
			(layer "F.Fab")
			(hide yes)
			(effects
				(font
					(size 1.27 1.27)
					(thickness 0.15)
				)
			)
		)
		(property "Author" "Antmicro"
			(at 67.55 339.47 0)
			(layer "B.Fab")
			(hide yes)
			(effects
				(font
					(size 1 1)
					(thickness 0.15)
				)
				(justify mirror)
			)
		)
		(property "Dielectric" "C0G"
			(at 67.55 339.47 0)
			(layer "B.Fab")
			(hide yes)
			(effects
				(font
					(size 1 1)
					(thickness 0.15)
				)
				(justify mirror)
			)
		)
		(property "License" "Apache-2.0"
			(at 67.55 339.47 0)
			(layer "B.Fab")
			(hide yes)
			(effects
				(font
					(size 1 1)
					(thickness 0.15)
				)
				(justify mirror)
			)
		)
		(property "MPN" "GRM1555C1H102JA01D"
			(at 67.55 339.47 0)
			(layer "B.Fab")
			(hide yes)
			(effects
				(font
					(size 1 1)
					(thickness 0.15)
				)
				(justify mirror)
			)
		)
		(property "Manufacturer" "Murata"
			(at 67.55 339.47 0)
			(layer "B.Fab")
			(hide yes)
			(effects
				(font
					(size 1 1)
					(thickness 0.15)
				)
				(justify mirror)
			)
		)
		(property "Public" ""
			(at 67.55 339.47 0)
			(layer "B.Fab")
			(hide yes)
			(effects
				(font
					(size 1 1)
					(thickness 0.15)
				)
				(justify mirror)
			)
		)
		(property "Val" "1n"
			(at 67.55 339.47 0)
			(layer "B.Fab")
			(hide yes)
			(effects
				(font
					(size 1 1)
					(thickness 0.15)
				)
				(justify mirror)
			)
		)
		(property "Voltage" "50V"
			(at 67.55 339.47 0)
			(layer "B.Fab")
			(hide yes)
			(effects
				(font
					(size 1 1)
					(thickness 0.15)
				)
				(justify mirror)
			)
		)
		(sheetname "/FPGA Supply/")
		(sheetfile "fpga-supply.kicad_sch")
		(attr smd)
		(fp_rect
			(start -0.925 0.47)
			(end 0.925 -0.47)
			(stroke
				(width 0.05)
				(type default)
			)
			(fill no)
			(layer "B.CrtYd")
		)
		(fp_line
			(start -0.494 0.25)
			(end 0.504 0.25)
			(stroke
				(width 0.15)
				(type solid)
			)
			(layer "B.Fab")
		)
		(fp_line
			(start 0.504 0.25)
			(end 0.504 -0.248)
			(stroke
				(width 0.15)
				(type solid)
			)
			(layer "B.Fab")
		)
		(fp_line
			(start -0.494 -0.248)
			(end -0.494 0.25)
			(stroke
				(width 0.15)
				(type solid)
			)
			(layer "B.Fab")
		)
		(fp_line
			(start 0.504 -0.248)
			(end -0.494 -0.248)
			(stroke
				(width 0.15)
				(type solid)
			)
			(layer "B.Fab")
		)
		(fp_text user "License: Apache-2.0"
			(at -0.939 -5.799 90)
			(layer "B.Fab")
			(effects
				(font
					(size 0.7 0.7)
					(thickness 0.15)
				)
				(justify left bottom mirror)
			)
		)
		(fp_text user "${REFERENCE}"
			(at -0.939 -4.599 90)
			(layer "B.Fab")
			(effects
				(font
					(size 0.7 0.7)
					(thickness 0.15)
				)
				(justify left bottom mirror)
			)
		)
		(fp_text user "Author: Antmicro"
			(at -0.939 -3.399 90)
			(layer "B.Fab")
			(effects
				(font
					(size 0.7 0.7)
					(thickness 0.15)
				)
				(justify left bottom mirror)
			)
		)
		(pad "1" smd roundrect
			(at -0.48 0 270)
			(size 0.59 0.64)
			(layers "B.Cu" "B.Mask" "B.Paste")
			(roundrect_rratio 0.25)
			(net 417 "GND")
			(pintype "passive")
		)
		(pad "2" smd roundrect
			(at 0.48 0 270)
			(size 0.59 0.64)
			(layers "B.Cu" "B.Mask" "B.Paste")
			(roundrect_rratio 0.25)
			(net 649 "VDD")
			(pintype "passive")
		)
	)
	(footprint "antmicro-footprints:R_0603_1608Metric"
		(layer "B.Cu")
		(at 176.95 139.1375 90)
		(descr "Resistor SMD 0603")
		(tags "resistor SMD 0603")
		(property "Reference" "R21"
			(at 1.0625 2.525 0)
			(layer "B.SilkS")
			(effects
				(font
					(size 0.7 0.7)
					(thickness 0.15)
				)
				(justify left bottom mirror)
			)
		)
		(property "Value" "R_0R01_0603"
			(at 0 -1.6 270)
			(layer "B.Fab")
			(hide yes)
			(effects
				(font
					(size 0.7 0.7)
					(thickness 0.15)
				)
				(justify left bottom mirror)
			)
		)
		(property "Datasheet" "https://www.bourns.com/docs/product-datasheets/cfn-a.pdf"
			(at 0 0 90)
			(layer "F.Fab")
			(hide yes)
			(effects
				(font
					(size 1.27 1.27)
					(thickness 0.15)
				)
			)
		)
		(property "Description" "SMD Chip Resistor, 10 mohm, ± 1%, 0.5 W, 0603 [1608 Metric], Metal Foil, Current Sensing"
			(at 0 0 90)
			(layer "F.Fab")
			(hide yes)
			(effects
				(font
					(size 1.27 1.27)
					(thickness 0.15)
				)
			)
		)
		(property "Author" "Antmicro"
			(at 316.0875 -37.8125 0)
			(layer "B.Fab")
			(hide yes)
			(effects
				(font
					(size 1 1)
					(thickness 0.15)
				)
				(justify mirror)
			)
		)
		(property "License" "Apache-2.0"
			(at 316.0875 -37.8125 0)
			(layer "B.Fab")
			(hide yes)
			(effects
				(font
					(size 1 1)
					(thickness 0.15)
				)
				(justify mirror)
			)
		)
		(property "MPN" "CFN0603AFZ-R010ELF"
			(at 316.0875 -37.8125 0)
			(layer "B.Fab")
			(hide yes)
			(effects
				(font
					(size 1 1)
					(thickness 0.15)
				)
				(justify mirror)
			)
		)
		(property "Manufacturer" "Bourns"
			(at 316.0875 -37.8125 0)
			(layer "B.Fab")
			(hide yes)
			(effects
				(font
					(size 1 1)
					(thickness 0.15)
				)
				(justify mirror)
			)
		)
		(property "Public" ""
			(at 316.0875 -37.8125 0)
			(layer "B.Fab")
			(hide yes)
			(effects
				(font
					(size 1 1)
					(thickness 0.15)
				)
				(justify mirror)
			)
		)
		(property "Tolerance" "1%"
			(at 316.0875 -37.8125 0)
			(layer "B.Fab")
			(hide yes)
			(effects
				(font
					(size 1 1)
					(thickness 0.15)
				)
				(justify mirror)
			)
		)
		(property "Val" "0R01"
			(at 316.0875 -37.8125 0)
			(layer "B.Fab")
			(hide yes)
			(effects
				(font
					(size 1 1)
					(thickness 0.15)
				)
				(justify mirror)
			)
		)
		(sheetname "/Supply/")
		(sheetfile "supply.kicad_sch")
		(attr smd)
		(fp_line
			(start -0.15 -0.4)
			(end 0.15 -0.4)
			(stroke
				(width 0.15)
				(type solid)
			)
			(layer "B.SilkS")
		)
		(fp_line
			(start -0.15 0.4)
			(end 0.15 0.4)
			(stroke
				(width 0.15)
				(type solid)
			)
			(layer "B.SilkS")
		)
		(fp_rect
			(start -1.25 0.65)
			(end 1.25 -0.65)
			(stroke
				(width 0.05)
				(type solid)
			)
			(fill no)
			(layer "B.CrtYd")
		)
		(fp_rect
			(start -0.8 0.4)
			(end 0.8 -0.4)
			(stroke
				(width 0.15)
				(type solid)
			)
			(fill no)
			(layer "B.Fab")
		)
		(fp_text user "License: Apache-2.0"
			(at -1.25 -5.9 270)
			(layer "B.Fab")
			(effects
				(font
					(size 0.7 0.7)
					(thickness 0.15)
				)
				(justify left bottom mirror)
			)
		)
		(fp_text user "Author: Antmicro"
			(at -1.25 -4.9 270)
			(layer "B.Fab")
			(effects
				(font
					(size 0.7 0.7)
					(thickness 0.15)
				)
				(justify left bottom mirror)
			)
		)
		(fp_text user "${REFERENCE}"
			(at -1.25 -3.898 270)
			(layer "B.Fab")
			(effects
				(font
					(size 0.7 0.7)
					(thickness 0.15)
				)
				(justify left bottom mirror)
			)
		)
		(pad "1" smd roundrect
			(at -0.7 0 90)
			(size 0.8 1)
			(layers "B.Cu" "B.Mask" "B.Paste")
			(roundrect_rratio 0.2)
			(net 209 "/Supply/SENSE1_P")
			(pintype "passive")
		)
		(pad "2" smd roundrect
			(at 0.7 0 90)
			(size 0.8 1)
			(layers "B.Cu" "B.Mask" "B.Paste")
			(roundrect_rratio 0.2)
			(net 50 "+3V3")
			(pintype "passive")
		)
	)
	(footprint "antmicro-footprints:R_0402_1005Metric"
		(layer "B.Cu")
		(at 218.95 128.05 180)
		(descr "Resistor SMD 0402")
		(tags "resistor SMD 0402")
		(property "Reference" "R9"
			(at 0.96 0.38 90)
			(layer "B.SilkS")
			(effects
				(font
					(size 0.7 0.7)
					(thickness 0.15)
				)
				(justify left bottom mirror)
			)
		)
		(property "Value" "R_0R_0402"
			(at -1.011843 -1.772047 0)
			(layer "B.Fab")
			(hide yes)
			(effects
				(font
					(size 0.7 0.7)
					(thickness 0.15)
				)
				(justify left bottom mirror)
			)
		)
		(property "Datasheet" "https://industrial.panasonic.com/cdbs/www-data/pdf/RDA0000/AOA0000C301.pdf"
			(at 0 0 180)
			(layer "F.Fab")
			(hide yes)
			(effects
				(font
					(size 1.27 1.27)
					(thickness 0.15)
				)
			)
		)
		(property "Description" "SMD Chip Resistor, Jumper, 0 ohm, 100 mW, 0402 [1005 Metric], Thick Film, General Purpose"
			(at 0 0 180)
			(layer "F.Fab")
			(hide yes)
			(effects
				(font
					(size 1.27 1.27)
					(thickness 0.15)
				)
			)
		)
		(property "Author" "Antmicro"
			(at 437.9 256.1 0)
			(layer "B.Fab")
			(hide yes)
			(effects
				(font
					(size 1 1)
					(thickness 0.15)
				)
				(justify mirror)
			)
		)
		(property "Current" "1A"
			(at 437.9 256.1 0)
			(layer "B.Fab")
			(hide yes)
			(effects
				(font
					(size 1 1)
					(thickness 0.15)
				)
				(justify mirror)
			)
		)
		(property "License" "Apache-2.0"
			(at 437.9 256.1 0)
			(layer "B.Fab")
			(hide yes)
			(effects
				(font
					(size 1 1)
					(thickness 0.15)
				)
				(justify mirror)
			)
		)
		(property "MPN" "ERJ2GE0R00X"
			(at 437.9 256.1 0)
			(layer "B.Fab")
			(hide yes)
			(effects
				(font
					(size 1 1)
					(thickness 0.15)
				)
				(justify mirror)
			)
		)
		(property "Manufacturer" "Panasonic"
			(at 437.9 256.1 0)
			(layer "B.Fab")
			(hide yes)
			(effects
				(font
					(size 1 1)
					(thickness 0.15)
				)
				(justify mirror)
			)
		)
		(property "Public" ""
			(at 437.9 256.1 0)
			(layer "B.Fab")
			(hide yes)
			(effects
				(font
					(size 1 1)
					(thickness 0.15)
				)
				(justify mirror)
			)
		)
		(property "Tolerance" "~"
			(at 437.9 256.1 0)
			(layer "B.Fab")
			(hide yes)
			(effects
				(font
					(size 1 1)
					(thickness 0.15)
				)
				(justify mirror)
			)
		)
		(property "Val" "0R"
			(at 437.9 256.1 0)
			(layer "B.Fab")
			(hide yes)
			(effects
				(font
					(size 1 1)
					(thickness 0.15)
				)
				(justify mirror)
			)
		)
		(sheetname "/Supply/")
		(sheetfile "supply.kicad_sch")
		(attr smd)
		(fp_rect
			(start -0.925 0.47)
			(end 0.925 -0.47)
			(stroke
				(width 0.05)
				(type default)
			)
			(fill no)
			(layer "B.CrtYd")
		)
		(fp_rect
			(start -0.5 0.25)
			(end 0.5 -0.25)
			(stroke
				(width 0.15)
				(type solid)
			)
			(fill no)
			(layer "B.Fab")
		)
		(fp_text user "Author: Antmicro"
			(at -0.95 -4.169 0)
			(layer "B.Fab")
			(effects
				(font
					(size 0.7 0.7)
					(thickness 0.15)
				)
				(justify left bottom mirror)
			)
		)
		(fp_text user "${REFERENCE}"
			(at -0.95 -3.168 0)
			(layer "B.Fab")
			(effects
				(font
					(size 0.7 0.7)
					(thickness 0.15)
				)
				(justify left bottom mirror)
			)
		)
		(fp_text user "License: Apache-2.0"
			(at -0.95 -5.169 0)
			(layer "B.Fab")
			(effects
				(font
					(size 0.7 0.7)
					(thickness 0.15)
				)
				(justify left bottom mirror)
			)
		)
		(pad "1" smd roundrect
			(at -0.48 0 180)
			(size 0.59 0.64)
			(layers "B.Cu" "B.Mask" "B.Paste")
			(roundrect_rratio 0.25)
			(net 188 "Net-(R9-Pad1)")
			(pintype "passive")
		)
		(pad "2" smd roundrect
			(at 0.48 0 180)
			(size 0.59 0.64)
			(layers "B.Cu" "B.Mask" "B.Paste")
			(roundrect_rratio 0.25)
			(net 49 "VDDAUX")
			(pintype "passive")
		)
	)
	(footprint "antmicro-footprints:R_0402_1005Metric"
		(layer "B.Cu")
		(at 210.1925 133.347 180)
		(descr "Resistor SMD 0402")
		(tags "resistor SMD 0402")
		(property "Reference" "R30"
			(at -1.6075 -3.353 0)
			(layer "B.SilkS")
			(effects
				(font
					(size 0.7 0.7)
					(thickness 0.15)
				)
				(justify left bottom mirror)
			)
		)
		(property "Value" "R_10k_0402"
			(at -1.011843 -1.772047 0)
			(layer "B.Fab")
			(hide yes)
			(effects
				(font
					(size 0.7 0.7)
					(thickness 0.15)
				)
				(justify left bottom mirror)
			)
		)
		(property "Datasheet" "https://www.bourns.com/docs/product-datasheets/cr.pdf"
			(at 0 0 180)
			(layer "F.Fab")
			(hide yes)
			(effects
				(font
					(size 1.27 1.27)
					(thickness 0.15)
				)
			)
		)
		(property "Description" "SMD Chip Resistor, 10 kohm, ± 1%, 62.5 mW, 0402 [1005 Metric], Thick Film, General Purpose"
			(at 0 0 180)
			(layer "F.Fab")
			(hide yes)
			(effects
				(font
					(size 1.27 1.27)
					(thickness 0.15)
				)
			)
		)
		(property "Author" "Antmicro"
			(at 420.385 266.694 0)
			(layer "B.Fab")
			(hide yes)
			(effects
				(font
					(size 1 1)
					(thickness 0.15)
				)
				(justify mirror)
			)
		)
		(property "License" "Apache-2.0"
			(at 420.385 266.694 0)
			(layer "B.Fab")
			(hide yes)
			(effects
				(font
					(size 1 1)
					(thickness 0.15)
				)
				(justify mirror)
			)
		)
		(property "MPN" "CR0402-FX-1002GLF"
			(at 420.385 266.694 0)
			(layer "B.Fab")
			(hide yes)
			(effects
				(font
					(size 1 1)
					(thickness 0.15)
				)
				(justify mirror)
			)
		)
		(property "Manufacturer" "Bourns"
			(at 420.385 266.694 0)
			(layer "B.Fab")
			(hide yes)
			(effects
				(font
					(size 1 1)
					(thickness 0.15)
				)
				(justify mirror)
			)
		)
		(property "Public" ""
			(at 420.385 266.694 0)
			(layer "B.Fab")
			(hide yes)
			(effects
				(font
					(size 1 1)
					(thickness 0.15)
				)
				(justify mirror)
			)
		)
		(property "Tolerance" "1%"
			(at 420.385 266.694 0)
			(layer "B.Fab")
			(hide yes)
			(effects
				(font
					(size 1 1)
					(thickness 0.15)
				)
				(justify mirror)
			)
		)
		(property "Val" "10k"
			(at 420.385 266.694 0)
			(layer "B.Fab")
			(hide yes)
			(effects
				(font
					(size 1 1)
					(thickness 0.15)
				)
				(justify mirror)
			)
		)
		(sheetname "/Memory/")
		(sheetfile "memory.kicad_sch")
		(attr smd)
		(fp_rect
			(start -0.925 0.47)
			(end 0.925 -0.47)
			(stroke
				(width 0.05)
				(type default)
			)
			(fill no)
			(layer "B.CrtYd")
		)
		(fp_rect
			(start -0.5 0.25)
			(end 0.5 -0.25)
			(stroke
				(width 0.15)
				(type solid)
			)
			(fill no)
			(layer "B.Fab")
		)
		(fp_text user "License: Apache-2.0"
			(at -0.95 -5.169 0)
			(layer "B.Fab")
			(effects
				(font
					(size 0.7 0.7)
					(thickness 0.15)
				)
				(justify left bottom mirror)
			)
		)
		(fp_text user "${REFERENCE}"
			(at -0.95 -3.168 0)
			(layer "B.Fab")
			(effects
				(font
					(size 0.7 0.7)
					(thickness 0.15)
				)
				(justify left bottom mirror)
			)
		)
		(fp_text user "Author: Antmicro"
			(at -0.95 -4.169 0)
			(layer "B.Fab")
			(effects
				(font
					(size 0.7 0.7)
					(thickness 0.15)
				)
				(justify left bottom mirror)
			)
		)
		(pad "1" smd roundrect
			(at -0.48 0 180)
			(size 0.59 0.64)
			(layers "B.Cu" "B.Mask" "B.Paste")
			(roundrect_rratio 0.25)
			(net 417 "GND")
			(pintype "passive")
		)
		(pad "2" smd roundrect
			(at 0.48 0 180)
			(size 0.59 0.64)
			(layers "B.Cu" "B.Mask" "B.Paste")
			(roundrect_rratio 0.25)
			(net 390 "/FPGA MSSIO/EMMC.STRB")
			(pintype "passive")
		)
	)
	(footprint "antmicro-footprints:R_0402_1005Metric"
		(layer "B.Cu")
		(at 225.6 143.345 180)
		(descr "Resistor SMD 0402")
		(tags "resistor SMD 0402")
		(property "Reference" "R149"
			(at -3.8 -0.405 0)
			(layer "B.SilkS")
			(effects
				(font
					(size 0.7 0.7)
					(thickness 0.15)
				)
				(justify left bottom mirror)
			)
		)
		(property "Value" "R_10k_0402"
			(at -1.011843 -1.772047 0)
			(layer "B.Fab")
			(hide yes)
			(effects
				(font
					(size 0.7 0.7)
					(thickness 0.15)
				)
				(justify left bottom mirror)
			)
		)
		(property "Datasheet" "https://www.bourns.com/docs/product-datasheets/cr.pdf"
			(at 0 0 180)
			(layer "F.Fab")
			(hide yes)
			(effects
				(font
					(size 1.27 1.27)
					(thickness 0.15)
				)
			)
		)
		(property "Description" "SMD Chip Resistor, 10 kohm, ± 1%, 62.5 mW, 0402 [1005 Metric], Thick Film, General Purpose"
			(at 0 0 180)
			(layer "F.Fab")
			(hide yes)
			(effects
				(font
					(size 1.27 1.27)
					(thickness 0.15)
				)
			)
		)
		(property "Author" "Antmicro"
			(at 451.2 286.69 0)
			(layer "B.Fab")
			(hide yes)
			(effects
				(font
					(size 1 1)
					(thickness 0.15)
				)
				(justify mirror)
			)
		)
		(property "License" "Apache-2.0"
			(at 451.2 286.69 0)
			(layer "B.Fab")
			(hide yes)
			(effects
				(font
					(size 1 1)
					(thickness 0.15)
				)
				(justify mirror)
			)
		)
		(property "MPN" "CR0402-FX-1002GLF"
			(at 451.2 286.69 0)
			(layer "B.Fab")
			(hide yes)
			(effects
				(font
					(size 1 1)
					(thickness 0.15)
				)
				(justify mirror)
			)
		)
		(property "Manufacturer" "Bourns"
			(at 451.2 286.69 0)
			(layer "B.Fab")
			(hide yes)
			(effects
				(font
					(size 1 1)
					(thickness 0.15)
				)
				(justify mirror)
			)
		)
		(property "Public" ""
			(at 451.2 286.69 0)
			(layer "B.Fab")
			(hide yes)
			(effects
				(font
					(size 1 1)
					(thickness 0.15)
				)
				(justify mirror)
			)
		)
		(property "Tolerance" "1%"
			(at 451.2 286.69 0)
			(layer "B.Fab")
			(hide yes)
			(effects
				(font
					(size 1 1)
					(thickness 0.15)
				)
				(justify mirror)
			)
		)
		(property "Val" "10k"
			(at 451.2 286.69 0)
			(layer "B.Fab")
			(hide yes)
			(effects
				(font
					(size 1 1)
					(thickness 0.15)
				)
				(justify mirror)
			)
		)
		(sheetname "/WiFi_Bluetooth/")
		(sheetfile "wifi_bt.kicad_sch")
		(attr smd)
		(fp_rect
			(start -0.925 0.47)
			(end 0.925 -0.47)
			(stroke
				(width 0.05)
				(type default)
			)
			(fill no)
			(layer "B.CrtYd")
		)
		(fp_rect
			(start -0.5 0.25)
			(end 0.5 -0.25)
			(stroke
				(width 0.15)
				(type solid)
			)
			(fill no)
			(layer "B.Fab")
		)
		(fp_text user "License: Apache-2.0"
			(at -0.95 -5.169 0)
			(layer "B.Fab")
			(effects
				(font
					(size 0.7 0.7)
					(thickness 0.15)
				)
				(justify left bottom mirror)
			)
		)
		(fp_text user "${REFERENCE}"
			(at -0.95 -3.168 0)
			(layer "B.Fab")
			(effects
				(font
					(size 0.7 0.7)
					(thickness 0.15)
				)
				(justify left bottom mirror)
			)
		)
		(fp_text user "Author: Antmicro"
			(at -0.95 -4.169 0)
			(layer "B.Fab")
			(effects
				(font
					(size 0.7 0.7)
					(thickness 0.15)
				)
				(justify left bottom mirror)
			)
		)
		(pad "1" smd roundrect
			(at -0.48 0 180)
			(size 0.59 0.64)
			(layers "B.Cu" "B.Mask" "B.Paste")
			(roundrect_rratio 0.25)
			(net 417 "GND")
			(pintype "passive")
		)
		(pad "2" smd roundrect
			(at 0.48 0 180)
			(size 0.59 0.64)
			(layers "B.Cu" "B.Mask" "B.Paste")
			(roundrect_rratio 0.25)
			(net 423 "/WiFi_Bluetooth/STRAP_2")
			(pintype "passive")
		)
	)
	(footprint "antmicro-footprints:C_0402_1005Metric"
		(layer "B.Cu")
		(at 195.87 146.76 -90)
		(descr "Capacitor SMD 0402")
		(tags "capacitor SMD 0402")
		(property "Reference" "C182"
			(at 0.79 0.02 90)
			(layer "B.SilkS")
			(effects
				(font
					(size 0.7 0.7)
					(thickness 0.15)
				)
				(justify left bottom mirror)
			)
		)
		(property "Value" "C_100n_0402"
			(at -1.022927 -2.155213 90)
			(layer "B.Fab")
			(hide yes)
			(effects
				(font
					(size 0.7 0.7)
					(thickness 0.15)
				)
				(justify left bottom mirror)
			)
		)
		(property "Datasheet" "https://www.murata.com/products/productdetail?partno=GRM155R61H104KE14%23"
			(at 0 0 270)
			(layer "F.Fab")
			(hide yes)
			(effects
				(font
					(size 1.27 1.27)
					(thickness 0.15)
				)
			)
		)
		(property "Description" "SMD Multilayer Ceramic Capacitor, 0.1 µF, 50 V, 0402 [1005 Metric], ± 10%, X5R, GRM Series"
			(at 0 0 270)
			(layer "F.Fab")
			(hide yes)
			(effects
				(font
					(size 1.27 1.27)
					(thickness 0.15)
				)
			)
		)
		(property "Author" "Antmicro"
			(at 49.11 342.63 0)
			(layer "B.Fab")
			(hide yes)
			(effects
				(font
					(size 1 1)
					(thickness 0.15)
				)
				(justify mirror)
			)
		)
		(property "Dielectric" "X5R"
			(at 49.11 342.63 0)
			(layer "B.Fab")
			(hide yes)
			(effects
				(font
					(size 1 1)
					(thickness 0.15)
				)
				(justify mirror)
			)
		)
		(property "License" "Apache-2.0"
			(at 49.11 342.63 0)
			(layer "B.Fab")
			(hide yes)
			(effects
				(font
					(size 1 1)
					(thickness 0.15)
				)
				(justify mirror)
			)
		)
		(property "MPN" "GRM155R61H104KE14D"
			(at 49.11 342.63 0)
			(layer "B.Fab")
			(hide yes)
			(effects
				(font
					(size 1 1)
					(thickness 0.15)
				)
				(justify mirror)
			)
		)
		(property "Manufacturer" "Murata"
			(at 49.11 342.63 0)
			(layer "B.Fab")
			(hide yes)
			(effects
				(font
					(size 1 1)
					(thickness 0.15)
				)
				(justify mirror)
			)
		)
		(property "Public" ""
			(at 49.11 342.63 0)
			(layer "B.Fab")
			(hide yes)
			(effects
				(font
					(size 1 1)
					(thickness 0.15)
				)
				(justify mirror)
			)
		)
		(property "Val" "100n"
			(at 49.11 342.63 0)
			(layer "B.Fab")
			(hide yes)
			(effects
				(font
					(size 1 1)
					(thickness 0.15)
				)
				(justify mirror)
			)
		)
		(property "Voltage" "50V"
			(at 49.11 342.63 0)
			(layer "B.Fab")
			(hide yes)
			(effects
				(font
					(size 1 1)
					(thickness 0.15)
				)
				(justify mirror)
			)
		)
		(sheetname "/HDMI/")
		(sheetfile "hdmi.kicad_sch")
		(attr smd)
		(fp_rect
			(start -0.925 0.47)
			(end 0.925 -0.47)
			(stroke
				(width 0.05)
				(type default)
			)
			(fill no)
			(layer "B.CrtYd")
		)
		(fp_line
			(start -0.494 0.25)
			(end 0.504 0.25)
			(stroke
				(width 0.15)
				(type solid)
			)
			(layer "B.Fab")
		)
		(fp_line
			(start 0.504 0.25)
			(end 0.504 -0.248)
			(stroke
				(width 0.15)
				(type solid)
			)
			(layer "B.Fab")
		)
		(fp_line
			(start -0.494 -0.248)
			(end -0.494 0.25)
			(stroke
				(width 0.15)
				(type solid)
			)
			(layer "B.Fab")
		)
		(fp_line
			(start 0.504 -0.248)
			(end -0.494 -0.248)
			(stroke
				(width 0.15)
				(type solid)
			)
			(layer "B.Fab")
		)
		(fp_text user "${REFERENCE}"
			(at -0.939 -4.599 90)
			(layer "B.Fab")
			(effects
				(font
					(size 0.7 0.7)
					(thickness 0.15)
				)
				(justify left bottom mirror)
			)
		)
		(fp_text user "License: Apache-2.0"
			(at -0.939 -5.799 90)
			(layer "B.Fab")
			(effects
				(font
					(size 0.7 0.7)
					(thickness 0.15)
				)
				(justify left bottom mirror)
			)
		)
		(fp_text user "Author: Antmicro"
			(at -0.939 -3.399 90)
			(layer "B.Fab")
			(effects
				(font
					(size 0.7 0.7)
					(thickness 0.15)
				)
				(justify left bottom mirror)
			)
		)
		(pad "1" smd roundrect
			(at -0.48 0 270)
			(size 0.59 0.64)
			(layers "B.Cu" "B.Mask" "B.Paste")
			(roundrect_rratio 0.25)
			(net 553 "/HDMI/HDMI_3V3")
			(pintype "passive")
		)
		(pad "2" smd roundrect
			(at 0.48 0 270)
			(size 0.59 0.64)
			(layers "B.Cu" "B.Mask" "B.Paste")
			(roundrect_rratio 0.25)
			(net 417 "GND")
			(pintype "passive")
		)
	)
	(footprint "antmicro-footprints:C_0402_1005Metric"
		(layer "B.Cu")
		(at 219.05 148.27)
		(descr "Capacitor SMD 0402")
		(tags "capacitor SMD 0402")
		(property "Reference" "C113"
			(at 5.84 -8.77 0)
			(layer "B.SilkS")
			(effects
				(font
					(size 0.7 0.7)
					(thickness 0.15)
				)
				(justify right bottom mirror)
			)
		)
		(property "Value" "C_4u7_0402"
			(at -1.022927 -2.155213 0)
			(layer "B.Fab")
			(hide yes)
			(effects
				(font
					(size 0.7 0.7)
					(thickness 0.15)
				)
				(justify right bottom mirror)
			)
		)
		(property "Datasheet" "https://www.murata.com/products/productdetail?partno=GRM155R61A475MEAA%23"
			(at 0 0 0)
			(layer "F.Fab")
			(hide yes)
			(effects
				(font
					(size 1.27 1.27)
					(thickness 0.15)
				)
			)
		)
		(property "Description" "SMD Multilayer Ceramic Capacitor, 4.7 µF, 10 V, 0402 [1005 Metric], ± 20%, X5R, GRM Series"
			(at 0 0 0)
			(layer "F.Fab")
			(hide yes)
			(effects
				(font
					(size 1.27 1.27)
					(thickness 0.15)
				)
			)
		)
		(property "Author" "Antmicro"
			(at 0 0 0)
			(layer "B.Fab")
			(hide yes)
			(effects
				(font
					(size 1 1)
					(thickness 0.15)
				)
				(justify mirror)
			)
		)
		(property "Dielectric" ""
			(at 0 0 0)
			(layer "B.Fab")
			(hide yes)
			(effects
				(font
					(size 1 1)
					(thickness 0.15)
				)
				(justify mirror)
			)
		)
		(property "License" "Apache-2.0"
			(at 0 0 0)
			(layer "B.Fab")
			(hide yes)
			(effects
				(font
					(size 1 1)
					(thickness 0.15)
				)
				(justify mirror)
			)
		)
		(property "MPN" "GRM155R61A475MEAAD"
			(at 0 0 0)
			(layer "B.Fab")
			(hide yes)
			(effects
				(font
					(size 1 1)
					(thickness 0.15)
				)
				(justify mirror)
			)
		)
		(property "Manufacturer" "Murata"
			(at 0 0 0)
			(layer "B.Fab")
			(hide yes)
			(effects
				(font
					(size 1 1)
					(thickness 0.15)
				)
				(justify mirror)
			)
		)
		(property "Public" ""
			(at 0 0 0)
			(layer "B.Fab")
			(hide yes)
			(effects
				(font
					(size 1 1)
					(thickness 0.15)
				)
				(justify mirror)
			)
		)
		(property "Val" "4u7"
			(at 0 0 0)
			(layer "B.Fab")
			(hide yes)
			(effects
				(font
					(size 1 1)
					(thickness 0.15)
				)
				(justify mirror)
			)
		)
		(property "Voltage" ""
			(at 0 0 0)
			(layer "B.Fab")
			(hide yes)
			(effects
				(font
					(size 1 1)
					(thickness 0.15)
				)
				(justify mirror)
			)
		)
		(sheetname "/WiFi_Bluetooth/")
		(sheetfile "wifi_bt.kicad_sch")
		(attr smd)
		(fp_rect
			(start -0.925 0.47)
			(end 0.925 -0.47)
			(stroke
				(width 0.05)
				(type default)
			)
			(fill no)
			(layer "B.CrtYd")
		)
		(fp_line
			(start -0.494 -0.248)
			(end -0.494 0.25)
			(stroke
				(width 0.15)
				(type solid)
			)
			(layer "B.Fab")
		)
		(fp_line
			(start -0.494 0.25)
			(end 0.504 0.25)
			(stroke
				(width 0.15)
				(type solid)
			)
			(layer "B.Fab")
		)
		(fp_line
			(start 0.504 -0.248)
			(end -0.494 -0.248)
			(stroke
				(width 0.15)
				(type solid)
			)
			(layer "B.Fab")
		)
		(fp_line
			(start 0.504 0.25)
			(end 0.504 -0.248)
			(stroke
				(width 0.15)
				(type solid)
			)
			(layer "B.Fab")
		)
		(fp_text user "License: Apache-2.0"
			(at -0.939 -5.799 180)
			(layer "B.Fab")
			(effects
				(font
					(size 0.7 0.7)
					(thickness 0.15)
				)
				(justify left bottom mirror)
			)
		)
		(fp_text user "${REFERENCE}"
			(at -0.939 -4.599 180)
			(layer "B.Fab")
			(effects
				(font
					(size 0.7 0.7)
					(thickness 0.15)
				)
				(justify left bottom mirror)
			)
		)
		(fp_text user "Author: Antmicro"
			(at -0.939 -3.399 180)
			(layer "B.Fab")
			(effects
				(font
					(size 0.7 0.7)
					(thickness 0.15)
				)
				(justify left bottom mirror)
			)
		)
		(pad "1" smd roundrect
			(at -0.48 0)
			(size 0.59 0.64)
			(layers "B.Cu" "B.Mask" "B.Paste")
			(roundrect_rratio 0.25)
			(net 151 "Net-(U26A-VIN_LDO)")
			(pintype "passive")
		)
		(pad "2" smd roundrect
			(at 0.48 0)
			(size 0.59 0.64)
			(layers "B.Cu" "B.Mask" "B.Paste")
			(roundrect_rratio 0.25)
			(net 417 "GND")
			(pintype "passive")
		)
	)
	(footprint "antmicro-footprints:SOT-23-3"
		(layer "B.Cu")
		(at 197.804498 148.636571 45)
		(property "Reference" "Q9"
			(at -1.172331 2.580184 45)
			(layer "B.SilkS")
			(effects
				(font
					(size 0.7 0.7)
					(thickness 0.15)
				)
				(justify right bottom mirror)
			)
		)
		(property "Value" "AO3401A"
			(at -1.9 -2.7 45)
			(layer "B.Fab")
			(hide yes)
			(effects
				(font
					(size 0.7 0.7)
					(thickness 0.15)
				)
				(justify right bottom mirror)
			)
		)
		(property "Datasheet" "http://aosmd.com/res/data_sheets/AO3401A.pdf"
			(at 0 0 45)
			(layer "F.Fab")
			(hide yes)
			(effects
				(font
					(size 1.27 1.27)
					(thickness 0.15)
				)
			)
		)
		(property "Description" "Power MOSFET, P Channel, 30 V, 4 A, 0.07 ohm, SOT-23, Surface Mount"
			(at 0 0 45)
			(layer "F.Fab")
			(hide yes)
			(effects
				(font
					(size 1.27 1.27)
					(thickness 0.15)
				)
			)
		)
		(property "Author" "Antmicro"
			(at 163.037524 -96.334259 0)
			(layer "B.Fab")
			(hide yes)
			(effects
				(font
					(size 1 1)
					(thickness 0.15)
				)
				(justify mirror)
			)
		)
		(property "License" "Apache-2.0"
			(at 163.037524 -96.334259 0)
			(layer "B.Fab")
			(hide yes)
			(effects
				(font
					(size 1 1)
					(thickness 0.15)
				)
				(justify mirror)
			)
		)
		(property "MPN" "AO3401A"
			(at 163.037524 -96.334259 0)
			(layer "B.Fab")
			(hide yes)
			(effects
				(font
					(size 1 1)
					(thickness 0.15)
				)
				(justify mirror)
			)
		)
		(property "Manufacturer" "AOSMD"
			(at 163.037524 -96.334259 0)
			(layer "B.Fab")
			(hide yes)
			(effects
				(font
					(size 1 1)
					(thickness 0.15)
				)
				(justify mirror)
			)
		)
		(sheetname "/Bottom Connector/")
		(sheetfile "bottom-connector.kicad_sch")
		(attr smd)
		(fp_line
			(start -0.7 -1.5)
			(end -0.7 -1.35)
			(stroke
				(width 0.15)
				(type solid)
			)
			(layer "B.SilkS")
		)
		(fp_line
			(start 0.7 -1.5)
			(end -0.7 -1.5)
			(stroke
				(width 0.15)
				(type solid)
			)
			(layer "B.SilkS")
		)
		(fp_line
			(start -1.45 1.35)
			(end -0.85 1.35)
			(stroke
				(width 0.15)
				(type solid)
			)
			(layer "B.SilkS")
		)
		(fp_line
			(start 0.7 -0.4)
			(end 0.7 -1.5)
			(stroke
				(width 0.15)
				(type solid)
			)
			(layer "B.SilkS")
		)
		(fp_line
			(start -0.85 1.35)
			(end -0.7 1.5)
			(stroke
				(width 0.15)
				(type solid)
			)
			(layer "B.SilkS")
		)
		(fp_line
			(start 0.7 0.4)
			(end 0.7 1.5)
			(stroke
				(width 0.15)
				(type solid)
			)
			(layer "B.SilkS")
		)
		(fp_line
			(start 0.7 1.5)
			(end -0.7 1.5)
			(stroke
				(width 0.15)
				(type solid)
			)
			(layer "B.SilkS")
		)
		(fp_line
			(start -1.749999 -1.4)
			(end -1.749999 -0.5)
			(stroke
				(width 0.05)
				(type solid)
			)
			(layer "B.CrtYd")
		)
		(fp_line
			(start -0.85 -1.65)
			(end -0.85 -1.4)
			(stroke
				(width 0.05)
				(type solid)
			)
			(layer "B.CrtYd")
		)
		(fp_line
			(start -0.85 -1.4)
			(end -1.749999 -1.4)
			(stroke
				(width 0.05)
				(type solid)
			)
			(layer "B.CrtYd")
		)
		(fp_line
			(start -1.749999 -0.5)
			(end -0.85 -0.5)
			(stroke
				(width 0.05)
				(type solid)
			)
			(layer "B.CrtYd")
		)
		(fp_line
			(start -0.85 -0.5)
			(end -0.85 0.5)
			(stroke
				(width 0.05)
				(type solid)
			)
			(layer "B.CrtYd")
		)
		(fp_line
			(start -1.749999 0.5)
			(end -1.749999 1.4)
			(stroke
				(width 0.05)
				(type solid)
			)
			(layer "B.CrtYd")
		)
		(fp_line
			(start 0.85 -1.65)
			(end -0.85 -1.65)
			(stroke
				(width 0.05)
				(type solid)
			)
			(layer "B.CrtYd")
		)
		(fp_line
			(start -0.85 0.5)
			(end -1.749999 0.5)
			(stroke
				(width 0.05)
				(type solid)
			)
			(layer "B.CrtYd")
		)
		(fp_line
			(start 0.85 -0.45)
			(end 0.85 -1.65)
			(stroke
				(width 0.05)
				(type solid)
			)
			(layer "B.CrtYd")
		)
		(fp_line
			(start -0.900001 1.4)
			(end -1.749999 1.4)
			(stroke
				(width 0.05)
				(type solid)
			)
			(layer "B.CrtYd")
		)
		(fp_line
			(start -0.9 1.6)
			(end -0.900001 1.4)
			(stroke
				(width 0.05)
				(type solid)
			)
			(layer "B.CrtYd")
		)
		(fp_line
			(start -0.9 1.6)
			(end 0.825 1.6)
			(stroke
				(width 0.05)
				(type solid)
			)
			(layer "B.CrtYd")
		)
		(fp_line
			(start 0.825 0.45)
			(end 1.75 0.45)
			(stroke
				(width 0.05)
				(type solid)
			)
			(layer "B.CrtYd")
		)
		(fp_line
			(start 1.75 -0.45)
			(end 0.85 -0.45)
			(stroke
				(width 0.05)
				(type solid)
			)
			(layer "B.CrtYd")
		)
		(fp_line
			(start 1.75 0.45)
			(end 1.75 -0.45)
			(stroke
				(width 0.05)
				(type solid)
			)
			(layer "B.CrtYd")
		)
		(fp_line
			(start 0.825 1.6)
			(end 0.825 0.45)
			(stroke
				(width 0.05)
				(type solid)
			)
			(layer "B.CrtYd")
		)
		(fp_line
			(start -0.712 -1.519)
			(end 0.688 -1.519)
			(stroke
				(width 0.15)
				(type solid)
			)
			(layer "B.Fab")
		)
		(fp_line
			(start 0.688 -1.519)
			(end 0.688 1.52)
			(stroke
				(width 0.15)
				(type solid)
			)
			(layer "B.Fab")
		)
		(fp_line
			(start -0.712001 1.325)
			(end -0.712 -1.523001)
			(stroke
				(width 0.15)
				(type solid)
			)
			(layer "B.Fab")
		)
		(fp_line
			(start -0.437 1.526)
			(end -0.712001 1.325)
			(stroke
				(width 0.15)
				(type solid)
			)
			(layer "B.Fab")
		)
		(fp_line
			(start -0.437 1.526)
			(end 0.688 1.525999)
			(stroke
				(width 0.15)
				(type solid)
			)
			(layer "B.Fab")
		)
		(fp_text user "${REFERENCE}"
			(at -1.837 -4 225)
			(layer "B.Fab")
			(effects
				(font
					(size 0.7 0.7)
					(thickness 0.15)
				)
				(justify left bottom mirror)
			)
		)
		(fp_text user "License: Apache-2.0"
			(at -1.8 -6.8 225)
			(layer "B.Fab")
			(effects
				(font
					(size 0.7 0.7)
					(thickness 0.15)
				)
				(justify left bottom mirror)
			)
		)
		(fp_text user "Author: Antmicro"
			(at -1.837 -5.3 225)
			(layer "B.Fab")
			(effects
				(font
					(size 0.7 0.7)
					(thickness 0.15)
				)
				(justify left bottom mirror)
			)
		)
		(pad "1" smd roundrect
			(at -1.1 0.951 45)
			(size 1 0.6)
			(layers "B.Cu" "B.Mask" "B.Paste")
			(roundrect_rratio 0.15)
			(net 411 "Net-(Q3-BIAS)")
			(pinfunction "G")
			(pintype "input")
		)
		(pad "2" smd roundrect
			(at -1.1 -0.949 45)
			(size 1 0.6)
			(layers "B.Cu" "B.Mask" "B.Paste")
			(roundrect_rratio 0.15)
			(net 90 "+5V")
			(pinfunction "S")
			(pintype "passive")
		)
		(pad "3" smd roundrect
			(at 1.1 0.0005 45)
			(size 1 0.6)
			(layers "B.Cu" "B.Mask" "B.Paste")
			(roundrect_rratio 0.15)
			(net 410 "Net-(Q3-D)")
			(pinfunction "D")
			(pintype "passive")
		)
	)
	(footprint "antmicro-footprints:C_0402_1005Metric"
		(layer "B.Cu")
		(at 194.41 130.616)
		(descr "Capacitor SMD 0402")
		(tags "capacitor SMD 0402")
		(property "Reference" "C30"
			(at -0.81 0.434 180)
			(layer "B.SilkS")
			(effects
				(font
					(size 0.7 0.7)
					(thickness 0.15)
				)
				(justify left bottom mirror)
			)
		)
		(property "Value" "C_1n_0402"
			(at -1.022927 -2.155213 180)
			(layer "B.Fab")
			(hide yes)
			(effects
				(font
					(size 0.7 0.7)
					(thickness 0.15)
				)
				(justify left bottom mirror)
			)
		)
		(property "Datasheet" "https://www.murata.com/products/productdetail?partno=GRM1555C1H102JA01%23"
			(at 0 0 0)
			(layer "F.Fab")
			(hide yes)
			(effects
				(font
					(size 1.27 1.27)
					(thickness 0.15)
				)
			)
		)
		(property "Description" "SMD Multilayer Ceramic Capacitor, 1000 pF, 50 V, 0402 [1005 Metric], ± 5%, C0G / NP0, GRM Series"
			(at 0 0 0)
			(layer "F.Fab")
			(hide yes)
			(effects
				(font
					(size 1.27 1.27)
					(thickness 0.15)
				)
			)
		)
		(property "Author" "Antmicro"
			(at 0 0 0)
			(layer "B.Fab")
			(hide yes)
			(effects
				(font
					(size 1 1)
					(thickness 0.15)
				)
				(justify mirror)
			)
		)
		(property "Dielectric" "C0G"
			(at 0 0 0)
			(layer "B.Fab")
			(hide yes)
			(effects
				(font
					(size 1 1)
					(thickness 0.15)
				)
				(justify mirror)
			)
		)
		(property "License" "Apache-2.0"
			(at 0 0 0)
			(layer "B.Fab")
			(hide yes)
			(effects
				(font
					(size 1 1)
					(thickness 0.15)
				)
				(justify mirror)
			)
		)
		(property "MPN" "GRM1555C1H102JA01D"
			(at 0 0 0)
			(layer "B.Fab")
			(hide yes)
			(effects
				(font
					(size 1 1)
					(thickness 0.15)
				)
				(justify mirror)
			)
		)
		(property "Manufacturer" "Murata"
			(at 0 0 0)
			(layer "B.Fab")
			(hide yes)
			(effects
				(font
					(size 1 1)
					(thickness 0.15)
				)
				(justify mirror)
			)
		)
		(property "Public" ""
			(at 0 0 0)
			(layer "B.Fab")
			(hide yes)
			(effects
				(font
					(size 1 1)
					(thickness 0.15)
				)
				(justify mirror)
			)
		)
		(property "Val" "1n"
			(at 0 0 0)
			(layer "B.Fab")
			(hide yes)
			(effects
				(font
					(size 1 1)
					(thickness 0.15)
				)
				(justify mirror)
			)
		)
		(property "Voltage" "50V"
			(at 0 0 0)
			(layer "B.Fab")
			(hide yes)
			(effects
				(font
					(size 1 1)
					(thickness 0.15)
				)
				(justify mirror)
			)
		)
		(sheetname "/FPGA Supply/")
		(sheetfile "fpga-supply.kicad_sch")
		(attr smd)
		(fp_rect
			(start -0.925 0.47)
			(end 0.925 -0.47)
			(stroke
				(width 0.05)
				(type default)
			)
			(fill no)
			(layer "B.CrtYd")
		)
		(fp_line
			(start -0.494 -0.248)
			(end -0.494 0.25)
			(stroke
				(width 0.15)
				(type solid)
			)
			(layer "B.Fab")
		)
		(fp_line
			(start -0.494 0.25)
			(end 0.504 0.25)
			(stroke
				(width 0.15)
				(type solid)
			)
			(layer "B.Fab")
		)
		(fp_line
			(start 0.504 -0.248)
			(end -0.494 -0.248)
			(stroke
				(width 0.15)
				(type solid)
			)
			(layer "B.Fab")
		)
		(fp_line
			(start 0.504 0.25)
			(end 0.504 -0.248)
			(stroke
				(width 0.15)
				(type solid)
			)
			(layer "B.Fab")
		)
		(fp_text user "Author: Antmicro"
			(at -0.939 -3.399 180)
			(layer "B.Fab")
			(effects
				(font
					(size 0.7 0.7)
					(thickness 0.15)
				)
				(justify left bottom mirror)
			)
		)
		(fp_text user "${REFERENCE}"
			(at -0.939 -4.599 180)
			(layer "B.Fab")
			(effects
				(font
					(size 0.7 0.7)
					(thickness 0.15)
				)
				(justify left bottom mirror)
			)
		)
		(fp_text user "License: Apache-2.0"
			(at -0.939 -5.799 180)
			(layer "B.Fab")
			(effects
				(font
					(size 0.7 0.7)
					(thickness 0.15)
				)
				(justify left bottom mirror)
			)
		)
		(pad "1" smd roundrect
			(at -0.48 0)
			(size 0.59 0.64)
			(layers "B.Cu" "B.Mask" "B.Paste")
			(roundrect_rratio 0.25)
			(net 417 "GND")
			(pintype "passive")
		)
		(pad "2" smd roundrect
			(at 0.48 0)
			(size 0.59 0.64)
			(layers "B.Cu" "B.Mask" "B.Paste")
			(roundrect_rratio 0.25)
			(net 418 "+2V5")
			(pintype "passive")
		)
	)
	(footprint "antmicro-footprints:XSON-8_1x1.95mm_P0.5mm"
		(layer "B.Cu")
		(at 219.32 141.62)
		(property "Reference" "U29"
			(at -1.78 2.15 0)
			(layer "B.SilkS")
			(effects
				(font
					(size 0.7 0.7)
					(thickness 0.15)
				)
				(justify right bottom mirror)
			)
		)
		(property "Value" "NTS0102_XSON"
			(at 0 -2.2 0)
			(layer "B.Fab")
			(hide yes)
			(effects
				(font
					(size 0.7 0.7)
					(thickness 0.15)
				)
				(justify right bottom mirror)
			)
		)
		(property "Datasheet" "http://www.farnell.com/datasheets/1760723.pdf"
			(at 0 0 0)
			(layer "F.Fab")
			(hide yes)
			(effects
				(font
					(size 1.27 1.27)
					(thickness 0.15)
				)
			)
		)
		(property "Description" "Transceiver, 1.65 V to 3.6 V, XSON-8"
			(at 0 0 0)
			(layer "F.Fab")
			(hide yes)
			(effects
				(font
					(size 1.27 1.27)
					(thickness 0.15)
				)
			)
		)
		(property "Author" "Antmicro"
			(at 0 0 0)
			(layer "B.Fab")
			(hide yes)
			(effects
				(font
					(size 1 1)
					(thickness 0.15)
				)
				(justify mirror)
			)
		)
		(property "License" "Apache-2.0"
			(at 0 0 0)
			(layer "B.Fab")
			(hide yes)
			(effects
				(font
					(size 1 1)
					(thickness 0.15)
				)
				(justify mirror)
			)
		)
		(property "MPN" "NTS0102GT"
			(at 0 0 0)
			(layer "B.Fab")
			(hide yes)
			(effects
				(font
					(size 1 1)
					(thickness 0.15)
				)
				(justify mirror)
			)
		)
		(property "Manufacturer" "NXP"
			(at 0 0 0)
			(layer "B.Fab")
			(hide yes)
			(effects
				(font
					(size 1 1)
					(thickness 0.15)
				)
				(justify mirror)
			)
		)
		(sheetname "/FPGA GPIO/")
		(sheetfile "fpga-gpio.kicad_sch")
		(attr smd)
		(fp_line
			(start -0.5 1.1)
			(end 0.5 1.1)
			(stroke
				(width 0.15)
				(type solid)
			)
			(layer "B.SilkS")
		)
		(fp_line
			(start 0.5 -1.1)
			(end -0.5 -1.1)
			(stroke
				(width 0.15)
				(type solid)
			)
			(layer "B.SilkS")
		)
		(fp_circle
			(center -0.75 1.1)
			(end -0.701 1.1)
			(stroke
				(width 0.15)
				(type solid)
			)
			(fill no)
			(layer "B.SilkS")
		)
		(fp_rect
			(start -0.8 1.2)
			(end 0.8 -1.2)
			(stroke
				(width 0.05)
				(type solid)
			)
			(fill no)
			(layer "B.CrtYd")
		)
		(fp_line
			(start -0.5305 -1)
			(end -0.5305 1.001)
			(stroke
				(width 0.15)
				(type solid)
			)
			(layer "B.Fab")
		)
		(fp_line
			(start -0.5305 1.001)
			(end 0.5305 1.001)
			(stroke
				(width 0.15)
				(type solid)
			)
			(layer "B.Fab")
		)
		(fp_line
			(start 0.5305 -1)
			(end -0.5305 -1)
			(stroke
				(width 0.15)
				(type solid)
			)
			(layer "B.Fab")
		)
		(fp_line
			(start 0.5305 1.001)
			(end 0.5305 -1)
			(stroke
				(width 0.15)
				(type solid)
			)
			(layer "B.Fab")
		)
		(fp_text user "${REFERENCE}"
			(at -0.527 -5.905 180)
			(layer "B.Fab")
			(effects
				(font
					(size 0.7 0.7)
					(thickness 0.15)
				)
				(justify left bottom mirror)
			)
		)
		(fp_text user "License: Apache-2.0"
			(at -0.527 -8.306 180)
			(layer "B.Fab")
			(effects
				(font
					(size 0.7 0.7)
					(thickness 0.15)
				)
				(justify left bottom mirror)
			)
		)
		(fp_text user "Author: Antmicro"
			(at -0.527 -7.105 180)
			(layer "B.Fab")
			(effects
				(font
					(size 0.7 0.7)
					(thickness 0.15)
				)
				(justify left bottom mirror)
			)
		)
		(pad "1" smd roundrect
			(at -0.45 0.75 180)
			(size 0.6 0.3)
			(layers "B.Cu" "B.Mask" "B.Paste")
			(roundrect_rratio 0.25)
			(net 129 "/FPGA GPIO/WiFi.CLK")
			(pinfunction "B_{2}")
			(pintype "bidirectional")
		)
		(pad "2" smd roundrect
			(at -0.45 0.25 180)
			(size 0.6 0.25)
			(layers "B.Cu" "B.Mask" "B.Paste")
			(roundrect_rratio 0.25)
			(net 417 "GND")
			(pinfunction "GND")
			(pintype "power_in")
		)
		(pad "3" smd roundrect
			(at -0.45 -0.25 180)
			(size 0.6 0.25)
			(layers "B.Cu" "B.Mask" "B.Paste")
			(roundrect_rratio 0.25)
			(net 649 "VDD")
			(pinfunction "VCC_{A}")
			(pintype "power_in")
		)
		(pad "4" smd roundrect
			(at -0.45 -0.75 180)
			(size 0.6 0.3)
			(layers "B.Cu" "B.Mask" "B.Paste")
			(roundrect_rratio 0.25)
			(net 352 "/FPGA GPIO/WiFi_CLK")
			(pinfunction "A_{2}")
			(pintype "bidirectional")
		)
		(pad "5" smd roundrect
			(at 0.45 -0.75 180)
			(size 0.6 0.3)
			(layers "B.Cu" "B.Mask" "B.Paste")
			(roundrect_rratio 0.25)
			(net 354 "/FPGA GPIO/WiFi_DATA_2")
			(pinfunction "A_{1}")
			(pintype "bidirectional")
		)
		(pad "6" smd roundrect
			(at 0.45 -0.25 180)
			(size 0.6 0.25)
			(layers "B.Cu" "B.Mask" "B.Paste")
			(roundrect_rratio 0.25)
			(net 649 "VDD")
			(pinfunction "OE")
			(pintype "input")
		)
		(pad "7" smd roundrect
			(at 0.45 0.25 180)
			(size 0.6 0.25)
			(layers "B.Cu" "B.Mask" "B.Paste")
			(roundrect_rratio 0.25)
			(net 50 "+3V3")
			(pinfunction "VCC_{B}")
			(pintype "power_in")
		)
		(pad "8" smd roundrect
			(at 0.45 0.75 180)
			(size 0.6 0.3)
			(layers "B.Cu" "B.Mask" "B.Paste")
			(roundrect_rratio 0.25)
			(net 225 "/FPGA GPIO/WiFi.DAT2")
			(pinfunction "B_{1}")
			(pintype "bidirectional")
		)
	)
	(footprint "antmicro-footprints:C_0402_1005Metric"
		(layer "B.Cu")
		(at 219.911 121.754)
		(descr "Capacitor SMD 0402")
		(tags "capacitor SMD 0402")
		(property "Reference" "C213"
			(at 6.539 3.996 0)
			(layer "B.SilkS")
			(effects
				(font
					(size 0.7 0.7)
					(thickness 0.15)
				)
				(justify right bottom mirror)
			)
		)
		(property "Value" "C_100n_0402"
			(at -1.022927 -2.155213 0)
			(layer "B.Fab")
			(hide yes)
			(effects
				(font
					(size 0.7 0.7)
					(thickness 0.15)
				)
				(justify right bottom mirror)
			)
		)
		(property "Datasheet" "https://www.murata.com/products/productdetail?partno=GRM155R61H104KE14%23"
			(at 0 0 0)
			(layer "F.Fab")
			(hide yes)
			(effects
				(font
					(size 1.27 1.27)
					(thickness 0.15)
				)
			)
		)
		(property "Description" "SMD Multilayer Ceramic Capacitor, 0.1 µF, 50 V, 0402 [1005 Metric], ± 10%, X5R, GRM Series"
			(at 0 0 0)
			(layer "F.Fab")
			(hide yes)
			(effects
				(font
					(size 1.27 1.27)
					(thickness 0.15)
				)
			)
		)
		(property "Author" "Antmicro"
			(at 0 0 0)
			(layer "B.Fab")
			(hide yes)
			(effects
				(font
					(size 1 1)
					(thickness 0.15)
				)
				(justify mirror)
			)
		)
		(property "Dielectric" "X5R"
			(at 0 0 0)
			(layer "B.Fab")
			(hide yes)
			(effects
				(font
					(size 1 1)
					(thickness 0.15)
				)
				(justify mirror)
			)
		)
		(property "License" "Apache-2.0"
			(at 0 0 0)
			(layer "B.Fab")
			(hide yes)
			(effects
				(font
					(size 1 1)
					(thickness 0.15)
				)
				(justify mirror)
			)
		)
		(property "MPN" "GRM155R61H104KE14D"
			(at 0 0 0)
			(layer "B.Fab")
			(hide yes)
			(effects
				(font
					(size 1 1)
					(thickness 0.15)
				)
				(justify mirror)
			)
		)
		(property "Manufacturer" "Murata"
			(at 0 0 0)
			(layer "B.Fab")
			(hide yes)
			(effects
				(font
					(size 1 1)
					(thickness 0.15)
				)
				(justify mirror)
			)
		)
		(property "Public" ""
			(at 0 0 0)
			(layer "B.Fab")
			(hide yes)
			(effects
				(font
					(size 1 1)
					(thickness 0.15)
				)
				(justify mirror)
			)
		)
		(property "Val" "100n"
			(at 0 0 0)
			(layer "B.Fab")
			(hide yes)
			(effects
				(font
					(size 1 1)
					(thickness 0.15)
				)
				(justify mirror)
			)
		)
		(property "Voltage" "50V"
			(at 0 0 0)
			(layer "B.Fab")
			(hide yes)
			(effects
				(font
					(size 1 1)
					(thickness 0.15)
				)
				(justify mirror)
			)
		)
		(sheetname "/Ethernet/")
		(sheetfile "ethernet.kicad_sch")
		(attr smd)
		(fp_rect
			(start -0.925 0.47)
			(end 0.925 -0.47)
			(stroke
				(width 0.05)
				(type default)
			)
			(fill no)
			(layer "B.CrtYd")
		)
		(fp_line
			(start -0.494 -0.248)
			(end -0.494 0.25)
			(stroke
				(width 0.15)
				(type solid)
			)
			(layer "B.Fab")
		)
		(fp_line
			(start -0.494 0.25)
			(end 0.504 0.25)
			(stroke
				(width 0.15)
				(type solid)
			)
			(layer "B.Fab")
		)
		(fp_line
			(start 0.504 -0.248)
			(end -0.494 -0.248)
			(stroke
				(width 0.15)
				(type solid)
			)
			(layer "B.Fab")
		)
		(fp_line
			(start 0.504 0.25)
			(end 0.504 -0.248)
			(stroke
				(width 0.15)
				(type solid)
			)
			(layer "B.Fab")
		)
		(fp_text user "${REFERENCE}"
			(at -0.939 -4.599 180)
			(layer "B.Fab")
			(effects
				(font
					(size 0.7 0.7)
					(thickness 0.15)
				)
				(justify left bottom mirror)
			)
		)
		(fp_text user "Author: Antmicro"
			(at -0.939 -3.399 180)
			(layer "B.Fab")
			(effects
				(font
					(size 0.7 0.7)
					(thickness 0.15)
				)
				(justify left bottom mirror)
			)
		)
		(fp_text user "License: Apache-2.0"
			(at -0.939 -5.799 180)
			(layer "B.Fab")
			(effects
				(font
					(size 0.7 0.7)
					(thickness 0.15)
				)
				(justify left bottom mirror)
			)
		)
		(pad "1" smd roundrect
			(at -0.48 0)
			(size 0.59 0.64)
			(layers "B.Cu" "B.Mask" "B.Paste")
			(roundrect_rratio 0.25)
			(net 417 "GND")
			(pintype "passive")
		)
		(pad "2" smd roundrect
			(at 0.48 0)
			(size 0.59 0.64)
			(layers "B.Cu" "B.Mask" "B.Paste")
			(roundrect_rratio 0.25)
			(net 418 "+2V5")
			(pintype "passive")
		)
	)
	(gr_line
		(start 174.517 119.336)
		(end 174.517001 152.336)
		(stroke
			(width 0.1)
			(type default)
		)
		(locked yes)
		(layer "Edge.Cuts")
	)
	(gr_line
		(start 226.017 115.836)
		(end 178.017 115.836)
		(stroke
			(width 0.1)
			(type default)
		)
		(locked yes)
		(layer "Edge.Cuts")
	)
	(gr_arc
		(start 178.017 155.835999)
		(mid 175.546283 154.806717)
		(end 174.517001 152.336)
		(stroke
			(width 0.1)
			(type default)
		)
		(locked yes)
		(layer "Edge.Cuts")
	)
	(gr_line
		(start 229.517 152.336)
		(end 229.517 119.336)
		(stroke
			(width 0.1)
			(type default)
		)
		(locked yes)
		(layer "Edge.Cuts")
	)
	(gr_line
		(start 178.017 155.835999)
		(end 226.017 155.836)
		(stroke
			(width 0.1)
			(type default)
		)
		(locked yes)
		(layer "Edge.Cuts")
	)
	(gr_arc
		(start 226.017 115.836)
		(mid 228.491581 116.861419)
		(end 229.517 119.336)
		(stroke
			(width 0.1)
			(type default)
		)
		(locked yes)
		(layer "Edge.Cuts")
	)
	(gr_arc
		(start 229.517 152.336)
		(mid 228.490929 154.809929)
		(end 226.017 155.836)
		(stroke
			(width 0.1)
			(type default)
		)
		(locked yes)
		(layer "Edge.Cuts")
	)
	(gr_arc
		(start 174.517 119.336)
		(mid 175.539204 116.858204)
		(end 178.017 115.836)
		(stroke
			(width 0.1)
			(type default)
		)
		(locked yes)
		(layer "Edge.Cuts")
	)
	(via
		(at 200.499 137.901)
		(size 0.35)
		(drill 0.15)
		(layers "F.Cu" "B.Cu")
		(remove_unused_layers yes)
		(keep_end_layers yes)
		(zone_layer_connections)
		(net 1)
	)
	(via
		(at 200.499 138.7)
		(size 0.35)
		(drill 0.15)
		(layers "F.Cu" "B.Cu")
		(remove_unused_layers yes)
		(keep_end_layers yes)
		(zone_layer_connections)
		(net 1)
	)
	(segment
		(start 200.52 138.176)
		(end 200.52 137.901)
		(width 0.4)
		(layer "B.Cu")
		(net 1)
	)
	(segment
		(start 200.499 138.7)
		(end 200.52 138.679)
		(width 0.4)
		(layer "B.Cu")
		(net 1)
	)
	(segment
		(start 200.606 138.09)
		(end 200.52 138.176)
		(width 0.4)
		(layer "B.Cu")
		(net 1)
	)
	(segment
		(start 201.224 138.09)
		(end 200.606 138.09)
		(width 0.4)
		(layer "B.Cu")
		(net 1)
	)
	(segment
		(start 200.52 138.679)
		(end 200.52 138.176)
		(width 0.4)
		(layer "B.Cu")
		(net 1)
	)
	(segment
		(start 201.224 137.1)
		(end 201.224 138.09)
		(width 0.4)
		(layer "B.Cu")
		(net 1)
	)
	(segment
		(start 182.805 135.766)
		(end 183.2045 136.0905)
		(width 0.174)
		(layer "F.Cu")
		(net 2)
	)
	(segment
		(start 175.603 130.566)
		(end 175.2035 130.2415)
		(width 0.174)
		(layer "F.Cu")
		(net 2)
	)
	(segment
		(start 182.004 122.766)
		(end 181.6045 122.4415)
		(width 0.174)
		(layer "F.Cu")
		(net 2)
	)
	(segment
		(start 181.205 126.016)
		(end 180.8055 126.3405)
		(width 0.174)
		(layer "F.Cu")
		(net 2)
	)
	(segment
		(start 183.1295 128.9415)
		(end 183.15 128.9415)
		(width 0.174)
		(layer "F.Cu")
		(net 2)
	)
	(segment
		(start 182.805 128.617)
		(end 183.1295 128.9415)
		(width 0.174)
		(layer "F.Cu")
		(net 2)
	)
	(segment
		(start 178.804 127.317)
		(end 179.2035 127.6415)
		(width 0.174)
		(layer "F.Cu")
		(net 2)
	)
	(segment
		(start 181.204 124.717)
		(end 180.8045 124.3925)
		(width 0.174)
		(layer "F.Cu")
		(net 2)
	)
	(segment
		(start 175.604 127.317)
		(end 175.27 127.46)
		(width 0.256)
		(layer "F.Cu")
		(net 2)
	)
	(segment
		(start 181.205 127.317)
		(end 180.8055 127.6415)
		(width 0.174)
		(layer "F.Cu")
		(net 2)
	)
	(segment
		(start 181.205 135.766)
		(end 180.8055 136.0905)
		(width 0.174)
		(layer "F.Cu")
		(net 2)
	)
	(segment
		(start 175.7 148.4)
		(end 175.95 148.15)
		(width 0.1)
		(layer "F.Cu")
		(net 2)
	)
	(segment
		(start 178.004 136.417)
		(end 178.4035 136.7415)
		(width 0.174)
		(layer "F.Cu")
		(net 2)
	)
	(segment
		(start 181.205 131.866)
		(end 180.8055 131.5415)
		(width 0.174)
		(layer "F.Cu")
		(net 2)
	)
	(segment
		(start 175.604 128.617)
		(end 175.27 129.31)
		(width 0.256)
		(layer "F.Cu")
		(net 2)
	)
	(segment
		(start 178.805 134.466)
		(end 179.2045 134.7905)
		(width 0.174)
		(layer "F.Cu")
		(net 2)
	)
	(segment
		(start 181.205 123.417)
		(end 180.8055 123.0925)
		(width 0.174)
		(layer "F.Cu")
		(net 2)
	)
	(segment
		(start 182.004 136.417)
		(end 181.6045 136.7415)
		(width 0.174)
		(layer "F.Cu")
		(net 2)
	)
	(segment
		(start 181.205 133.167)
		(end 180.8055 132.8425)
		(width 0.174)
		(layer "F.Cu")
		(net 2)
	)
	(segment
		(start 184.405 134.466)
		(end 184.8045 134.7905)
		(width 0.174)
		(layer "F.Cu")
		(net 2)
	)
	(segment
		(start 178.804 124.717)
		(end 179.2035 124.3925)
		(width 0.174)
		(layer "F.Cu")
		(net 2)
	)
	(segment
		(start 175.23 132.24)
		(end 175.21 132.24)
		(width 0.174)
		(layer "F.Cu")
		(net 2)
	)
	(segment
		(start 178.804 135.766)
		(end 179.2035 136.0905)
		(width 0.174)
		(layer "F.Cu")
		(net 2)
	)
	(segment
		(start 178.804 126.016)
		(end 179.2035 126.3405)
		(width 0.174)
		(layer "F.Cu")
		(net 2)
	)
	(segment
		(start 175.1 148.4)
		(end 175.7 148.4)
		(width 0.1)
		(layer "F.Cu")
		(net 2)
	)
	(segment
		(start 182.805 130.566)
		(end 183.1295 130.2415)
		(width 0.174)
		(layer "F.Cu")
		(net 2)
	)
	(segment
		(start 181.204 134.466)
		(end 180.8045 134.7905)
		(width 0.174)
		(layer "F.Cu")
		(net 2)
	)
	(segment
		(start 175.26 136.09)
		(end 175.26 134.81)
		(width 0.174)
		(layer "F.Cu")
		(net 2)
	)
	(segment
		(start 178.804 131.866)
		(end 179.2035 131.5415)
		(width 0.174)
		(layer "F.Cu")
		(net 2)
	)
	(segment
		(start 177.205 123.416)
		(end 176.8055 123.0915)
		(width 0.174)
		(layer "F.Cu")
		(net 2)
	)
	(segment
		(start 175.26 134.81)
		(end 175.604 134.466)
		(width 0.174)
		(layer "F.Cu")
		(net 2)
	)
	(segment
		(start 184.405 124.717)
		(end 184.8045 124.3925)
		(width 0.174)
		(layer "F.Cu")
		(net 2)
	)
	(segment
		(start 184.405 131.867)
		(end 184.8045 131.5425)
		(width 0.174)
		(layer "F.Cu")
		(net 2)
	)
	(segment
		(start 184.405 128.617)
		(end 184.8045 128.9415)
		(width 0.174)
		(layer "F.Cu")
		(net 2)
	)
	(segment
		(start 182.805 133.167)
		(end 183.2045 132.8425)
		(width 0.174)
		(layer "F.Cu")
		(net 2)
	)
	(segment
		(start 178.804 123.416)
		(end 179.2035 123.0915)
		(width 0.174)
		(layer "F.Cu")
		(net 2)
	)
	(segment
		(start 178.804 133.167)
		(end 179.2035 132.8425)
		(width 0.174)
		(layer "F.Cu")
		(net 2)
	)
	(segment
		(start 177.205 135.766)
		(end 176.8055 136.0905)
		(width 0.174)
		(layer "F.Cu")
		(net 2)
	)
	(segment
		(start 178.004 122.766)
		(end 178.4035 122.4415)
		(width 0.174)
		(layer "F.Cu")
		(net 2)
	)
	(segment
		(start 183.1295 130.2415)
		(end 183.15 130.2415)
		(width 0.174)
		(layer "F.Cu")
		(net 2)
	)
	(segment
		(start 184.405 127.317)
		(end 184.8045 127.6415)
		(width 0.174)
		(layer "F.Cu")
		(net 2)
	)
	(segment
		(start 175.2 123.67)
		(end 175.2 124.313)
		(width 0.174)
		(layer "F.Cu")
		(net 2)
	)
	(segment
		(start 175.2 124.313)
		(end 175.604 124.717)
		(width 0.174)
		(layer "F.Cu")
		(net 2)
	)
	(segment
		(start 184.405 130.566)
		(end 184.8045 130.2415)
		(width 0.174)
		(layer "F.Cu")
		(net 2)
	)
	(segment
		(start 182.805 123.416)
		(end 183.2045 123.0915)
		(width 0.174)
		(layer "F.Cu")
		(net 2)
	)
	(segment
		(start 182.805 126.016)
		(end 183.2045 126.3405)
		(width 0.174)
		(layer "F.Cu")
		(net 2)
	)
	(segment
		(start 175.603 131.867)
		(end 175.23 132.24)
		(width 0.174)
		(layer "F.Cu")
		(net 2)
	)
	(via
		(at 184.8045 128.9415)
		(size 0.35)
		(drill 0.15)
		(layers "F.Cu" "B.Cu")
		(remove_unused_layers yes)
		(keep_end_layers yes)
		(zone_layer_connections)
		(net 2)
	)
	(via
		(at 190.9 125.101)
		(size 0.35)
		(drill 0.15)
		(layers "F.Cu" "B.Cu")
		(remove_unused_layers yes)
		(keep_end_layers yes)
		(zone_layer_connections)
		(net 2)
	)
	(via
		(at 179.2035 124.3925)
		(size 0.35)
		(drill 0.15)
		(layers "F.Cu" "B.Cu")
		(remove_unused_layers yes)
		(keep_end_layers yes)
		(zone_layer_connections)
		(net 2)
	)
	(via
		(at 184.538999 138.55)
		(size 0.35)
		(drill 0.15)
		(layers "F.Cu" "B.Cu")
		(remove_unused_layers yes)
		(keep_end_layers yes)
		(free yes)
		(zone_layer_connections)
		(net 2)
	)
	(via
		(at 193.299 124.3)
		(size 0.35)
		(drill 0.15)
		(layers "F.Cu" "B.Cu")
		(remove_unused_layers yes)
		(keep_end_layers yes)
		(zone_layer_connections)
		(net 2)
	)
	(via
		(at 179.2035 126.3405)
		(size 0.35)
		(drill 0.15)
		(layers "F.Cu" "B.Cu")
		(remove_unused_layers yes)
		(keep_end_layers yes)
		(zone_layer_connections)
		(net 2)
	)
	(via
		(at 189.299 128.3)
		(size 0.35)
		(drill 0.15)
		(layers "F.Cu" "B.Cu")
		(remove_unused_layers yes)
		(keep_end_layers yes)
		(zone_layer_connections)
		(net 2)
	)
	(via
		(at 178.4035 122.4415)
		(size 0.35)
		(drill 0.15)
		(layers "F.Cu" "B.Cu")
		(remove_unused_layers yes)
		(keep_end_layers yes)
		(zone_layer_connections)
		(net 2)
	)
	(via
		(at 175.27 129.31)
		(size 0.35)
		(drill 0.15)
		(layers "F.Cu" "B.Cu")
		(remove_unused_layers yes)
		(keep_end_layers yes)
		(zone_layer_connections)
		(net 2)
	)
	(via
		(at 183.2045 132.8425)
		(size 0.35)
		(drill 0.15)
		(layers "F.Cu" "B.Cu")
		(remove_unused_layers yes)
		(keep_end_layers yes)
		(zone_layer_connections)
		(net 2)
	)
	(via
		(at 194.099 126.701)
		(size 0.35)
		(drill 0.15)
		(layers "F.Cu" "B.Cu")
		(remove_unused_layers yes)
		(keep_end_layers yes)
		(zone_layer_connections)
		(net 2)
	)
	(via
		(at 184.8045 134.7905)
		(size 0.35)
		(drill 0.15)
		(layers "F.Cu" "B.Cu")
		(remove_unused_layers yes)
		(keep_end_layers yes)
		(zone_layer_connections)
		(net 2)
	)
	(via
		(at 193.25 132.3)
		(size 0.35)
		(drill 0.15)
		(layers "F.Cu" "B.Cu")
		(remove_unused_layers yes)
		(keep_end_layers yes)
		(zone_layer_connections)
		(net 2)
	)
	(via
		(at 178.4035 136.7415)
		(size 0.35)
		(drill 0.15)
		(layers "F.Cu" "B.Cu")
		(remove_unused_layers yes)
		(keep_end_layers yes)
		(zone_layer_connections)
		(net 2)
	)
	(via
		(at 175.2035 130.2415)
		(size 0.35)
		(drill 0.15)
		(layers "F.Cu" "B.Cu")
		(remove_unused_layers yes)
		(keep_end_layers yes)
		(zone_layer_connections)
		(net 2)
	)
	(via
		(at 179.2045 134.7905)
		(size 0.35)
		(drill 0.15)
		(layers "F.Cu" "B.Cu")
		(remove_unused_layers yes)
		(keep_end_layers yes)
		(zone_layer_connections)
		(net 2)
	)
	(via
		(at 175.26 136.09)
		(size 0.35)
		(drill 0.15)
		(layers "F.Cu" "B.Cu")
		(remove_unused_layers yes)
		(keep_end_layers yes)
		(zone_layer_connections)
		(net 2)
	)
	(via
		(at 183.2045 126.3405)
		(size 0.35)
		(drill 0.15)
		(layers "F.Cu" "B.Cu")
		(remove_unused_layers yes)
		(keep_end_layers yes)
		(zone_layer_connections)
		(net 2)
	)
	(via
		(at 180.8055 132.8425)
		(size 0.35)
		(drill 0.15)
		(layers "F.Cu" "B.Cu")
		(remove_unused_layers yes)
		(keep_end_layers yes)
		(zone_layer_connections)
		(net 2)
	)
	(via
		(at 180.8055 136.0905)
		(size 0.35)
		(drill 0.15)
		(layers "F.Cu" "B.Cu")
		(remove_unused_layers yes)
		(keep_end_layers yes)
		(zone_layer_connections)
		(net 2)
	)
	(via
		(at 183.2045 123.0915)
		(size 0.35)
		(drill 0.15)
		(layers "F.Cu" "B.Cu")
		(remove_unused_layers yes)
		(keep_end_layers yes)
		(zone_layer_connections)
		(net 2)
	)
	(via
		(at 175.21 132.24)
		(size 0.35)
		(drill 0.15)
		(layers "F.Cu" "B.Cu")
		(remove_unused_layers yes)
		(keep_end_layers yes)
		(zone_layer_connections)
		(net 2)
	)
	(via
		(at 180.8045 134.7905)
		(size 0.35)
		(drill 0.15)
		(layers "F.Cu" "B.Cu")
		(remove_unused_layers yes)
		(keep_end_layers yes)
		(zone_layer_connections)
		(net 2)
	)
	(via
		(at 184.8045 131.5425)
		(size 0.35)
		(drill 0.15)
		(layers "F.Cu" "B.Cu")
		(remove_unused_layers yes)
		(keep_end_layers yes)
		(zone_layer_connections)
		(net 2)
	)
	(via
		(at 177.205 128.617)
		(size 0.35)
		(drill 0.15)
		(layers "F.Cu" "B.Cu")
		(remove_unused_layers yes)
		(keep_end_layers yes)
		(zone_layer_connections)
		(net 2)
	)
	(via
		(at 194.9 129.1)
		(size 0.35)
		(drill 0.15)
		(layers "F.Cu" "B.Cu")
		(remove_unused_layers yes)
		(keep_end_layers yes)
		(zone_layer_connections)
		(net 2)
	)
	(via
		(at 180.8055 123.0925)
		(size 0.35)
		(drill 0.15)
		(layers "F.Cu" "B.Cu")
		(remove_unused_layers yes)
		(keep_end_layers yes)
		(zone_layer_connections)
		(net 2)
	)
	(via
		(at 177.205 130.566)
		(size 0.35)
		(drill 0.15)
		(layers "F.Cu" "B.Cu")
		(remove_unused_layers yes)
		(keep_end_layers yes)
		(zone_layer_connections)
		(net 2)
	)
	(via
		(at 179.2035 131.5415)
		(size 0.35)
		(drill 0.15)
		(layers "F.Cu" "B.Cu")
		(remove_unused_layers yes)
		(keep_end_layers yes)
		(zone_layer_connections)
		(net 2)
	)
	(via
		(at 179.2035 123.0915)
		(size 0.35)
		(drill 0.15)
		(layers "F.Cu" "B.Cu")
		(remove_unused_layers yes)
		(keep_end_layers yes)
		(zone_layer_connections)
		(net 2)
	)
	(via
		(at 177.205 126.016)
		(size 0.35)
		(drill 0.15)
		(layers "F.Cu" "B.Cu")
		(remove_unused_layers yes)
		(keep_end_layers yes)
		(zone_layer_connections)
		(net 2)
	)
	(via
		(at 184.8045 124.3925)
		(size 0.35)
		(drill 0.15)
		(layers "F.Cu" "B.Cu")
		(remove_unused_layers yes)
		(keep_end_layers yes)
		(zone_layer_connections)
		(net 2)
	)
	(via
		(at 180.8045 124.3925)
		(size 0.35)
		(drill 0.15)
		(layers "F.Cu" "B.Cu")
		(remove_unused_layers yes)
		(keep_end_layers yes)
		(zone_layer_connections)
		(net 2)
	)
	(via
		(at 176.8055 136.0905)
		(size 0.35)
		(drill 0.15)
		(layers "F.Cu" "B.Cu")
		(remove_unused_layers yes)
		(keep_end_layers yes)
		(zone_layer_connections)
		(net 2)
	)
	(via
		(at 177.205 133.167)
		(size 0.35)
		(drill 0.15)
		(layers "F.Cu" "B.Cu")
		(remove_unused_layers yes)
		(keep_end_layers yes)
		(zone_layer_connections)
		(net 2)
	)
	(via
		(at 176.8055 123.0915)
		(size 0.35)
		(drill 0.15)
		(layers "F.Cu" "B.Cu")
		(remove_unused_layers yes)
		(keep_end_layers yes)
		(zone_layer_connections)
		(net 2)
	)
	(via
		(at 180.8055 127.6415)
		(size 0.35)
		(drill 0.15)
		(layers "F.Cu" "B.Cu")
		(remove_unused_layers yes)
		(keep_end_layers yes)
		(zone_layer_connections)
		(net 2)
	)
	(via
		(at 175.1 148.4)
		(size 0.35)
		(drill 0.15)
		(layers "F.Cu" "B.Cu")
		(remove_unused_layers yes)
		(keep_end_layers yes)
		(zone_layer_connections)
		(net 2)
	)
	(via
		(at 196.5 125.901)
		(size 0.35)
		(drill 0.15)
		(layers "F.Cu" "B.Cu")
		(remove_unused_layers yes)
		(keep_end_layers yes)
		(zone_layer_connections)
		(net 2)
	)
	(via
		(at 180.8055 131.5415)
		(size 0.35)
		(drill 0.15)
		(layers "F.Cu" "B.Cu")
		(remove_unused_layers yes)
		(keep_end_layers yes)
		(zone_layer_connections)
		(net 2)
	)
	(via
		(at 180.8055 126.3405)
		(size 0.35)
		(drill 0.15)
		(layers "F.Cu" "B.Cu")
		(remove_unused_layers yes)
		(keep_end_layers yes)
		(zone_layer_connections)
		(net 2)
	)
	(via
		(at 192.5 129.85)
		(size 0.35)
		(drill 0.15)
		(layers "F.Cu" "B.Cu")
		(remove_unused_layers yes)
		(keep_end_layers yes)
		(zone_layer_connections)
		(net 2)
	)
	(via
		(at 179.2035 127.6415)
		(size 0.35)
		(drill 0.15)
		(layers "F.Cu" "B.Cu")
		(remove_unused_layers yes)
		(keep_end_layers yes)
		(zone_layer_connections)
		(net 2)
	)
	(via
		(at 184.8045 130.2415)
		(size 0.35)
		(drill 0.15)
		(layers "F.Cu" "B.Cu")
		(remove_unused_layers yes)
		(keep_end_layers yes)
		(zone_layer_connections)
		(net 2)
	)
	(via
		(at 190.1 130.701)
		(size 0.35)
		(drill 0.15)
		(layers "F.Cu" "B.Cu")
		(remove_unused_layers yes)
		(keep_end_layers yes)
		(zone_layer_connections)
		(net 2)
	)
	(via
		(at 191.7 127.5)
		(size 0.35)
		(drill 0.15)
		(layers "F.Cu" "B.Cu")
		(remove_unused_layers yes)
		(keep_end_layers yes)
		(zone_layer_connections)
		(net 2)
	)
	(via
		(at 175.27 127.46)
		(size 0.35)
		(drill 0.15)
		(layers "F.Cu" "B.Cu")
		(remove_unused_layers yes)
		(keep_end_layers yes)
		(zone_layer_connections)
		(net 2)
	)
	(via
		(at 183.2045 136.0905)
		(size 0.35)
		(drill 0.15)
		(layers "F.Cu" "B.Cu")
		(remove_unused_layers yes)
		(keep_end_layers yes)
		(zone_layer_connections)
		(net 2)
	)
	(via
		(at 179.2035 136.0905)
		(size 0.35)
		(drill 0.15)
		(layers "F.Cu" "B.Cu")
		(remove_unused_layers yes)
		(keep_end_layers yes)
		(zone_layer_connections)
		(net 2)
	)
	(via
		(at 179.2035 132.8425)
		(size 0.35)
		(drill 0.15)
		(layers "F.Cu" "B.Cu")
		(remove_unused_layers yes)
		(keep_end_layers yes)
		(zone_layer_connections)
		(net 2)
	)
	(via
		(at 184.8045 127.6415)
		(size 0.35)
		(drill 0.15)
		(layers "F.Cu" "B.Cu")
		(remove_unused_layers yes)
		(keep_end_layers yes)
		(zone_layer_connections)
		(net 2)
	)
	(via
		(at 175.2 123.67)
		(size 0.35)
		(drill 0.15)
		(layers "F.Cu" "B.Cu")
		(remove_unused_layers yes)
		(keep_end_layers yes)
		(zone_layer_connections)
		(net 2)
	)
	(via
		(at 181.6045 136.7415)
		(size 0.35)
		(drill 0.15)
		(layers "F.Cu" "B.Cu")
		(remove_unused_layers yes)
		(keep_end_layers yes)
		(zone_layer_connections)
		(net 2)
	)
	(via
		(at 181.6045 122.4415)
		(size 0.35)
		(drill 0.15)
		(layers "F.Cu" "B.Cu")
		(remove_unused_layers yes)
		(keep_end_layers yes)
		(zone_layer_connections)
		(net 2)
	)
	(via
		(at 183.15 130.2415)
		(size 0.35)
		(drill 0.15)
		(layers "F.Cu" "B.Cu")
		(remove_unused_layers yes)
		(keep_end_layers yes)
		(zone_layer_connections)
		(net 2)
	)
	(via
		(at 183.15 128.9415)
		(size 0.35)
		(drill 0.15)
		(layers "F.Cu" "B.Cu")
		(remove_unused_layers yes)
		(keep_end_layers yes)
		(zone_layer_connections)
		(net 2)
	)
	(segment
		(start 191.72 127.48)
		(end 191.7 127.5)
		(width 0.4)
		(layer "B.Cu")
		(net 2)
	)
	(segment
		(start 194.717 126.701)
		(end 194.816 126.8)
		(width 0.4)
		(layer "B.Cu")
		(net 2)
	)
	(segment
		(start 180 122.616)
		(end 179.2035 123.0915)
		(width 0.4)
		(layer "B.Cu")
		(net 2)
	)
	(segment
		(start 180.05 134.984)
		(end 179.2045 134.7905)
		(width 0.4)
		(layer "B.Cu")
		(net 2)
	)
	(segment
		(start 180.025 135.966)
		(end 180.8055 136.0905)
		(width 0.4)
		(layer "B.Cu")
		(net 2)
	)
	(segment
		(start 184.55 138.561001)
		(end 184.538999 138.55)
		(width 0.2)
		(layer "B.Cu")
		(net 2)
	)
	(segment
		(start 179.2035 124.3925)
		(end 180 124.566)
		(width 0.4)
		(layer "B.Cu")
		(net 2)
	)
	(segment
		(start 180 124.566)
		(end 180.8045 124.3925)
		(width 0.4)
		(layer "B.Cu")
		(net 2)
	)
	(segment
		(start 194.11 126.69)
		(end 194.099 126.701)
		(width 0.4)
		(layer "B.Cu")
		(net 2)
	)
	(segment
		(start 180.05 134.984)
		(end 180.8045 134.7905)
		(width 0.4)
		(layer "B.Cu")
		(net 2)
	)
	(segment
		(start 194.26 129.1)
		(end 194.9 129.1)
		(width 0.4)
		(layer "B.Cu")
		(net 2)
	)
	(segment
		(start 196.5 125.901)
		(end 195.915 125.901)
		(width 0.4)
		(layer "B.Cu")
		(net 2)
	)
	(segment
		(start 177.7 125.584)
		(end 177.205 126.016)
		(width 0.4)
		(layer "B.Cu")
		(net 2)
	)
	(segment
		(start 184.55 138.875)
		(end 184.55 138.561001)
		(width 0.2)
		(layer "B.Cu")
		(net 2)
	)
	(segment
		(start 194.099 126.701)
		(end 194.717 126.701)
		(width 0.4)
		(layer "B.Cu")
		(net 2)
	)
	(segment
		(start 195.915 125.901)
		(end 195.784 125.77)
		(width 0.4)
		(layer "B.Cu")
		(net 2)
	)
	(segment
		(start 183.368 125.8)
		(end 183.2045 126.3405)
		(width 0.4)
		(layer "B.Cu")
		(net 2)
	)
	(segment
		(start 184.925 139.25)
		(end 184.55 138.875)
		(width 0.2)
		(layer "B.Cu")
		(net 2)
	)
	(segment
		(start 180.025 135.966)
		(end 179.2035 136.0905)
		(width 0.4)
		(layer "B.Cu")
		(net 2)
	)
	(segment
		(start 177.7 133.616)
		(end 177.205 133.167)
		(width 0.4)
		(layer "B.Cu")
		(net 2)
	)
	(segment
		(start 180.8055 123.0925)
		(end 180 122.616)
		(width 0.4)
		(layer "B.Cu")
		(net 2)
	)
	(segment
		(start 183.25 133.616)
		(end 183.2045 132.8425)
		(width 0.4)
		(layer "B.Cu")
		(net 2)
	)
	(segment
		(start 181.126 139.376)
		(end 181.48 139.73)
		(width 0.1)
		(layer "In7.Cu")
		(net 2)
	)
	(segment
		(start 179.626 144.784)
		(end 177.35 147.06)
		(width 0.1)
		(layer "In7.Cu")
		(net 2)
	)
	(segment
		(start 175.1 148.219354)
		(end 175.1 148.4)
		(width 0.1)
		(layer "In7.Cu")
		(net 2)
	)
	(segment
		(start 184.538999 138.55)
		(end 184.188999 138.2)
		(width 0.1)
		(layer "In7.Cu")
		(net 2)
	)
	(segment
		(start 181.8 138.2)
		(end 181.126 138.874)
		(width 0.1)
		(layer "In7.Cu")
		(net 2)
	)
	(segment
		(start 184.188999 138.2)
		(end 181.8 138.2)
		(width 0.1)
		(layer "In7.Cu")
		(net 2)
	)
	(segment
		(start 177.35 147.06)
		(end 176.259354 147.06)
		(width 0.1)
		(layer "In7.Cu")
		(net 2)
	)
	(segment
		(start 176.259354 147.06)
		(end 175.1 148.219354)
		(width 0.1)
		(layer "In7.Cu")
		(net 2)
	)
	(segment
		(start 181.126 138.874)
		(end 181.126 139.376)
		(width 0.1)
		(layer "In7.Cu")
		(net 2)
	)
	(segment
		(start 181.48 139.73)
		(end 181.48 143.13)
		(width 0.1)
		(layer "In7.Cu")
		(net 2)
	)
	(segment
		(start 179.826 144.784)
		(end 179.626 144.784)
		(width 0.1)
		(layer "In7.Cu")
		(net 2)
	)
	(segment
		(start 181.48 143.13)
		(end 179.826 144.784)
		(width 0.1)
		(layer "In7.Cu")
		(net 2)
	)
	(segment
		(start 179.55 138.8025)
		(end 179.45 138.9025)
		(width 0.174)
		(layer "F.Cu")
		(net 3)
	)
	(segment
		(start 179.45 138.9025)
		(end 179.45 139.8375)
		(width 0.174)
		(layer "F.Cu")
		(net 3)
	)
	(segment
		(start 179.549 138.8015)
		(end 179.55 138.8025)
		(width 0.174)
		(layer "F.Cu")
		(net 3)
	)
	(segment
		(start 178.5 138.8015)
		(end 179.549 138.8015)
		(width 0.174)
		(layer "F.Cu")
		(net 3)
	)
	(via
		(at 217.73 154.97)
		(size 0.35)
		(drill 0.15)
		(layers "F.Cu" "B.Cu")
		(remove_unused_layers yes)
		(keep_end_layers yes)
		(zone_layer_connections)
		(net 4)
	)
	(via
		(at 207.267 154.9)
		(size 0.35)
		(drill 0.15)
		(layers "F.Cu" "B.Cu")
		(remove_unused_layers yes)
		(keep_end_layers yes)
		(zone_layer_connections)
		(net 4)
	)
	(segment
		(start 207.317 154.171)
		(end 207.317 154.386)
		(width 0.125)
		(layer "B.Cu")
		(net 4)
	)
	(segment
		(start 207.4095 154.4785)
		(end 207.4095 154.7575)
		(width 0.125)
		(layer "B.Cu")
		(net 4)
	)
	(segment
		(start 207.4095 154.7575)
		(end 207.267 154.9)
		(width 0.125)
		(layer "B.Cu")
		(net 4)
	)
	(segment
		(start 207.317 154.386)
		(end 207.4095 154.4785)
		(width 0.125)
		(layer "B.Cu")
		(net 4)
	)
	(segment
		(start 210.678578 154.46)
		(end 211.438578 155.22)
		(width 0.1)
		(layer "In4.Cu")
		(net 4)
	)
	(segment
		(start 216.671422 155.22)
		(end 217.166422 154.725)
		(width 0.1)
		(layer "In4.Cu")
		(net 4)
	)
	(segment
		(start 208.32 154.691422)
		(end 208.551422 154.46)
		(width 0.1)
		(layer "In4.Cu")
		(net 4)
	)
	(segment
		(start 207.417 155.234098)
		(end 207.612902 155.43)
		(width 0.1)
		(layer "In4.Cu")
		(net 4)
	)
	(segment
		(start 207.612902 155.43)
		(end 207.951422 155.43)
		(width 0.1)
		(layer "In4.Cu")
		(net 4)
	)
	(segment
		(start 207.951422 155.43)
		(end 208.32 155.061422)
		(width 0.1)
		(layer "In4.Cu")
		(net 4)
	)
	(segment
		(start 207.417 155.05)
		(end 207.417 155.234098)
		(width 0.1)
		(layer "In4.Cu")
		(net 4)
	)
	(segment
		(start 208.32 155.061422)
		(end 208.32 154.691422)
		(width 0.1)
		(layer "In4.Cu")
		(net 4)
	)
	(segment
		(start 207.267 154.9)
		(end 207.417 155.05)
		(width 0.1)
		(layer "In4.Cu")
		(net 4)
	)
	(segment
		(start 211.438578 155.22)
		(end 216.671422 155.22)
		(width 0.1)
		(layer "In4.Cu")
		(net 4)
	)
	(segment
		(start 217.485 154.725)
		(end 217.73 154.97)
		(width 0.1)
		(layer "In4.Cu")
		(net 4)
	)
	(segment
		(start 217.166422 154.725)
		(end 217.485 154.725)
		(width 0.1)
		(layer "In4.Cu")
		(net 4)
	)
	(segment
		(start 208.551422 154.46)
		(end 210.678578 154.46)
		(width 0.1)
		(layer "In4.Cu")
		(net 4)
	)
	(via
		(at 207.767 154.9)
		(size 0.35)
		(drill 0.15)
		(layers "F.Cu" "B.Cu")
		(remove_unused_layers yes)
		(keep_end_layers yes)
		(zone_layer_connections)
		(net 5)
	)
	(via
		(at 217.73 154.28)
		(size 0.35)
		(drill 0.15)
		(layers "F.Cu" "B.Cu")
		(remove_unused_layers yes)
		(keep_end_layers yes)
		(zone_layer_connections)
		(net 5)
	)
	(segment
		(start 207.717 154.386)
		(end 207.6245 154.4785)
		(width 0.125)
		(layer "B.Cu")
		(net 5)
	)
	(segment
		(start 207.6245 154.4785)
		(end 207.6245 154.7575)
		(width 0.125)
		(layer "B.Cu")
		(net 5)
	)
	(segment
		(start 207.717 154.171)
		(end 207.717 154.386)
		(width 0.125)
		(layer "B.Cu")
		(net 5)
	)
	(segment
		(start 207.6245 154.7575)
		(end 207.767 154.9)
		(width 0.125)
		(layer "B.Cu")
		(net 5)
	)
	(segment
		(start 208.468578 154.26)
		(end 208.63 154.26)
		(width 0.1)
		(layer "In4.Cu")
		(net 5)
	)
	(segment
		(start 207.868578 155.23)
		(end 208.12 154.978578)
		(width 0.1)
		(layer "In4.Cu")
		(net 5)
	)
	(segment
		(start 208.12 154.978578)
		(end 208.12 154.608578)
		(width 0.1)
		(layer "In4.Cu")
		(net 5)
	)
	(segment
		(start 216.588578 155.02)
		(end 217.083578 154.525)
		(width 0.1)
		(layer "In4.Cu")
		(net 5)
	)
	(segment
		(start 208.12 154.608578)
		(end 208.468578 154.26)
		(width 0.1)
		(layer "In4.Cu")
		(net 5)
	)
	(segment
		(start 207.617 155.05)
		(end 207.617 155.151254)
		(width 0.1)
		(layer "In4.Cu")
		(net 5)
	)
	(segment
		(start 217.083578 154.525)
		(end 217.485 154.525)
		(width 0.1)
		(layer "In4.Cu")
		(net 5)
	)
	(segment
		(start 211.521422 155.02)
		(end 216.588578 155.02)
		(width 0.1)
		(layer "In4.Cu")
		(net 5)
	)
	(segment
		(start 210.761422 154.26)
		(end 211.521422 155.02)
		(width 0.1)
		(layer "In4.Cu")
		(net 5)
	)
	(segment
		(start 207.767 154.9)
		(end 207.617 155.05)
		(width 0.1)
		(layer "In4.Cu")
		(net 5)
	)
	(segment
		(start 217.485 154.525)
		(end 217.73 154.28)
		(width 0.1)
		(layer "In4.Cu")
		(net 5)
	)
	(segment
		(start 209.23 154.26)
		(end 210.761422 154.26)
		(width 0.1)
		(layer "In4.Cu")
		(net 5)
	)
	(segment
		(start 207.617 155.151254)
		(end 207.695746 155.23)
		(width 0.1)
		(layer "In4.Cu")
		(net 5)
	)
	(segment
		(start 207.695746 155.23)
		(end 207.868578 155.23)
		(width 0.1)
		(layer "In4.Cu")
		(net 5)
	)
	(arc
		(start 208.93 153.96)
		(mid 209.036066 154.003934)
		(end 209.08 154.11)
		(width 0.1)
		(layer "In4.Cu")
		(net 5)
	)
	(arc
		(start 208.78 154.11)
		(mid 208.823934 154.003934)
		(end 208.93 153.96)
		(width 0.1)
		(layer "In4.Cu")
		(net 5)
	)
	(arc
		(start 208.63 154.26)
		(mid 208.736066 154.216066)
		(end 208.78 154.11)
		(width 0.1)
		(layer "In4.Cu")
		(net 5)
	)
	(arc
		(start 209.08 154.11)
		(mid 209.123934 154.216066)
		(end 209.23 154.26)
		(width 0.1)
		(layer "In4.Cu")
		(net 5)
	)
	(via
		(at 206.1 137.901)
		(size 0.35)
		(drill 0.15)
		(layers "F.Cu" "B.Cu")
		(remove_unused_layers yes)
		(keep_end_layers yes)
		(zone_layer_connections)
		(net 8)
	)
	(via
		(at 205.323 118.625)
		(size 0.35)
		(drill 0.15)
		(layers "F.Cu" "B.Cu")
		(remove_unused_layers yes)
		(keep_end_layers yes)
		(zone_layer_connections)
		(net 8)
	)
	(segment
		(start 204.919 118.978)
		(end 204.919 120.171)
		(width 0.15)
		(layer "B.Cu")
		(net 8)
	)
	(segment
		(start 205.323 118.625)
		(end 205.272 118.625)
		(width 0.15)
		(layer "B.Cu")
		(net 8)
	)
	(segment
		(start 205.272 118.625)
		(end 204.919 118.978)
		(width 0.15)
		(layer "B.Cu")
		(net 8)
	)
	(segment
		(start 210.2 118.8)
		(end 210.2 121.025051)
		(width 0.09)
		(layer "In7.Cu")
		(net 8)
	)
	(segment
		(start 209.375 136.2)
		(end 208.0755 136.2)
		(width 0.09)
		(layer "In7.Cu")
		(net 8)
	)
	(segment
		(start 208.0755 136.2)
		(end 206.3745 137.901)
		(width 0.09)
		(layer "In7.Cu")
		(net 8)
	)
	(segment
		(start 209 117.6)
		(end 210.2 118.8)
		(width 0.09)
		(layer "In7.Cu")
		(net 8)
	)
	(segment
		(start 210.9 121.725051)
		(end 210.9 134.675)
		(width 0.09)
		(layer "In7.Cu")
		(net 8)
	)
	(segment
		(start 210.2 121.025051)
		(end 210.9 121.725051)
		(width 0.09)
		(layer "In7.Cu")
		(net 8)
	)
	(segment
		(start 205.325 118.625)
		(end 206.35 117.6)
		(width 0.09)
		(layer "In7.Cu")
		(net 8)
	)
	(segment
		(start 210.9 134.675)
		(end 209.375 136.2)
		(width 0.09)
		(layer "In7.Cu")
		(net 8)
	)
	(segment
		(start 206.35 117.6)
		(end 209 117.6)
		(width 0.09)
		(layer "In7.Cu")
		(net 8)
	)
	(segment
		(start 206.3745 137.901)
		(end 206.1 137.901)
		(width 0.09)
		(layer "In7.Cu")
		(net 8)
	)
	(segment
		(start 198.1 129.901)
		(end 197.8245 129.6255)
		(width 0.35)
		(layer "F.Cu")
		(net 9)
	)
	(via
		(at 197.8245 129.6255)
		(size 0.35)
		(drill 0.15)
		(layers "F.Cu" "B.Cu")
		(remove_unused_layers yes)
		(keep_end_layers yes)
		(zone_layer_connections)
		(net 9)
	)
	(via
		(at 210.15 122.16)
		(size 0.35)
		(drill 0.15)
		(layers "F.Cu" "B.Cu")
		(remove_unused_layers yes)
		(keep_end_layers yes)
		(zone_layer_connections)
		(net 9)
	)
	(segment
		(start 210.28 122.03)
		(end 210.15 122.16)
		(width 0.09)
		(layer "In9.Cu")
		(net 9)
	)
	(segment
		(start 210.08 118.700294)
		(end 210.800294 117.98)
		(width 0.09)
		(layer "In9.Cu")
		(net 9)
	)
	(segment
		(start 211.474706 117.98)
		(end 211.910221 118.415515)
		(width 0.09)
		(layer "In9.Cu")
		(net 9)
	)
	(segment
		(start 210.08 119.600294)
		(end 210.08 118.700294)
		(width 0.09)
		(layer "In9.Cu")
		(net 9)
	)
	(segment
		(start 197.550294 129.12)
		(end 197.8245 129.394206)
		(width 0.09)
		(layer "In9.Cu")
		(net 9)
	)
	(segment
		(start 211.910221 118.415515)
		(end 211.910221 119.265515)
		(width 0.09)
		(layer "In9.Cu")
		(net 9)
	)
	(segment
		(start 210.800294 117.98)
		(end 211.474706 117.98)
		(width 0.09)
		(layer "In9.Cu")
		(net 9)
	)
	(segment
		(start 195.255 123.000294)
		(end 195.950294 122.305)
		(width 0.09)
		(layer "In9.Cu")
		(net 9)
	)
	(segment
		(start 197.362544 129.12)
		(end 196.762544 129.72)
		(width 0.09)
		(layer "In9.Cu")
		(net 9)
	)
	(segment
		(start 196.762544 129.72)
		(end 196.125294 129.72)
		(width 0.09)
		(layer "In9.Cu")
		(net 9)
	)
	(segment
		(start 195.255 128.849706)
		(end 195.255 123.000294)
		(width 0.09)
		(layer "In9.Cu")
		(net 9)
	)
	(segment
		(start 195.950294 122.305)
		(end 201.575294 122.305)
		(width 0.09)
		(layer "In9.Cu")
		(net 9)
	)
	(segment
		(start 203.800294 120.08)
		(end 209.600294 120.08)
		(width 0.09)
		(layer "In9.Cu")
		(net 9)
	)
	(segment
		(start 197.550294 129.12)
		(end 197.362544 129.12)
		(width 0.09)
		(layer "In9.Cu")
		(net 9)
	)
	(segment
		(start 210.515523 122.03)
		(end 210.28 122.03)
		(width 0.09)
		(layer "In9.Cu")
		(net 9)
	)
	(segment
		(start 212.295 119.650294)
		(end 212.295 120.250523)
		(width 0.09)
		(layer "In9.Cu")
		(net 9)
	)
	(segment
		(start 201.575294 122.305)
		(end 203.800294 120.08)
		(width 0.09)
		(layer "In9.Cu")
		(net 9)
	)
	(segment
		(start 209.600294 120.08)
		(end 210.08 119.600294)
		(width 0.09)
		(layer "In9.Cu")
		(net 9)
	)
	(segment
		(start 211.910221 119.265515)
		(end 212.295 119.650294)
		(width 0.09)
		(layer "In9.Cu")
		(net 9)
	)
	(segment
		(start 196.125294 129.72)
		(end 195.255 128.849706)
		(width 0.09)
		(layer "In9.Cu")
		(net 9)
	)
	(segment
		(start 212.295 120.250523)
		(end 210.515523 122.03)
		(width 0.09)
		(layer "In9.Cu")
		(net 9)
	)
	(segment
		(start 197.8245 129.394206)
		(end 197.8245 129.6255)
		(width 0.09)
		(layer "In9.Cu")
		(net 9)
	)
	(via
		(at 198.1 129.1)
		(size 0.35)
		(drill 0.15)
		(layers "F.Cu" "B.Cu")
		(remove_unused_layers yes)
		(keep_end_layers yes)
		(zone_layer_connections)
		(net 10)
	)
	(via
		(at 210.15 121.66)
		(size 0.35)
		(drill 0.15)
		(layers "F.Cu" "B.Cu")
		(remove_unused_layers yes)
		(keep_end_layers yes)
		(zone_layer_connections)
		(net 10)
	)
	(segment
		(start 196.224706 129.48)
		(end 196.663132 129.48)
		(width 0.09)
		(layer "In9.Cu")
		(net 10)
	)
	(segment
		(start 212.055 120.151111)
		(end 212.055 119.749706)
		(width 0.09)
		(layer "In9.Cu")
		(net 10)
	)
	(segment
		(start 209.699706 120.32)
		(end 203.899706 120.32)
		(width 0.09)
		(layer "In9.Cu")
		(net 10)
	)
	(segment
		(start 195.495 128.325)
		(end 195.495 128.750294)
		(width 0.09)
		(layer "In9.Cu")
		(net 10)
	)
	(segment
		(start 195.707133 128.750293)
		(end 195.707132 128.750294)
		(width 0.09)
		(layer "In9.Cu")
		(net 10)
	)
	(segment
		(start 195.495 127.025)
		(end 195.495 127.725)
		(width 0.09)
		(layer "In9.Cu")
		(net 10)
	)
	(segment
		(start 195.645 127.875)
		(end 195.83289 127.875)
		(width 0.09)
		(layer "In9.Cu")
		(net 10)
	)
	(segment
		(start 195.83289 128.175)
		(end 195.645 128.175)
		(width 0.09)
		(layer "In9.Cu")
		(net 10)
	)
	(segment
		(start 210.15 121.66)
		(end 210.28 121.79)
		(width 0.09)
		(layer "In9.Cu")
		(net 10)
	)
	(segment
		(start 201.674706 122.545)
		(end 196.049706 122.545)
		(width 0.09)
		(layer "In9.Cu")
		(net 10)
	)
	(segment
		(start 197.263132 128.88)
		(end 197.649706 128.88)
		(width 0.09)
		(layer "In9.Cu")
		(net 10)
	)
	(segment
		(start 197.869706 129.1)
		(end 198.1 129.1)
		(width 0.09)
		(layer "In9.Cu")
		(net 10)
	)
	(segment
		(start 195.707132 128.750294)
		(end 195.802785 128.654642)
		(width 0.09)
		(layer "In9.Cu")
		(net 10)
	)
	(segment
		(start 195.495 123.099706)
		(end 195.495 126.425)
		(width 0.09)
		(layer "In9.Cu")
		(net 10)
	)
	(segment
		(start 195.919263 129.174557)
		(end 196.224706 129.48)
		(width 0.09)
		(layer "In9.Cu")
		(net 10)
	)
	(segment
		(start 211.670221 119.364927)
		(end 211.670221 118.514927)
		(width 0.09)
		(layer "In9.Cu")
		(net 10)
	)
	(segment
		(start 196.663132 129.48)
		(end 197.263132 128.88)
		(width 0.09)
		(layer "In9.Cu")
		(net 10)
	)
	(segment
		(start 211.375294 118.22)
		(end 210.899706 118.22)
		(width 0.09)
		(layer "In9.Cu")
		(net 10)
	)
	(segment
		(start 210.899706 118.22)
		(end 210.32 118.799706)
		(width 0.09)
		(layer "In9.Cu")
		(net 10)
	)
	(segment
		(start 196.014916 128.866775)
		(end 196.014917 128.866774)
		(width 0.09)
		(layer "In9.Cu")
		(net 10)
	)
	(segment
		(start 195.782865 126.875)
		(end 195.645 126.875)
		(width 0.09)
		(layer "In9.Cu")
		(net 10)
	)
	(segment
		(start 210.416111 121.79)
		(end 212.055 120.151111)
		(width 0.09)
		(layer "In9.Cu")
		(net 10)
	)
	(segment
		(start 196.014917 128.866774)
		(end 195.919263 128.962425)
		(width 0.09)
		(layer "In9.Cu")
		(net 10)
	)
	(segment
		(start 210.32 118.799706)
		(end 210.32 119.699706)
		(width 0.09)
		(layer "In9.Cu")
		(net 10)
	)
	(segment
		(start 195.645 126.575)
		(end 195.782865 126.575)
		(width 0.09)
		(layer "In9.Cu")
		(net 10)
	)
	(segment
		(start 212.055 119.749706)
		(end 211.670221 119.364927)
		(width 0.09)
		(layer "In9.Cu")
		(net 10)
	)
	(segment
		(start 211.670221 118.514927)
		(end 211.375294 118.22)
		(width 0.09)
		(layer "In9.Cu")
		(net 10)
	)
	(segment
		(start 210.28 121.79)
		(end 210.416111 121.79)
		(width 0.09)
		(layer "In9.Cu")
		(net 10)
	)
	(segment
		(start 210.32 119.699706)
		(end 209.699706 120.32)
		(width 0.09)
		(layer "In9.Cu")
		(net 10)
	)
	(segment
		(start 203.899706 120.32)
		(end 201.674706 122.545)
		(width 0.09)
		(layer "In9.Cu")
		(net 10)
	)
	(segment
		(start 196.049706 122.545)
		(end 195.495 123.099706)
		(width 0.09)
		(layer "In9.Cu")
		(net 10)
	)
	(segment
		(start 197.649706 128.88)
		(end 197.869706 129.1)
		(width 0.09)
		(layer "In9.Cu")
		(net 10)
	)
	(arc
		(start 195.495 126.425)
		(mid 195.538934 126.531066)
		(end 195.645 126.575)
		(width 0.09)
		(layer "In9.Cu")
		(net 10)
	)
	(arc
		(start 195.932865 126.725)
		(mid 195.888931 126.831066)
		(end 195.782865 126.875)
		(width 0.09)
		(layer "In9.Cu")
		(net 10)
	)
	(arc
		(start 196.014917 128.654642)
		(mid 196.05885 128.760708)
		(end 196.014916 128.866775)
		(width 0.09)
		(layer "In9.Cu")
		(net 10)
	)
	(arc
		(start 195.782865 126.575)
		(mid 195.888931 126.618934)
		(end 195.932865 126.725)
		(width 0.09)
		(layer "In9.Cu")
		(net 10)
	)
	(arc
		(start 195.83289 127.875)
		(mid 195.938956 127.918934)
		(end 195.98289 128.025)
		(width 0.09)
		(layer "In9.Cu")
		(net 10)
	)
	(arc
		(start 195.645 126.875)
		(mid 195.538934 126.918934)
		(end 195.495 127.025)
		(width 0.09)
		(layer "In9.Cu")
		(net 10)
	)
	(arc
		(start 195.645 128.175)
		(mid 195.538934 128.218934)
		(end 195.495 128.325)
		(width 0.09)
		(layer "In9.Cu")
		(net 10)
	)
	(arc
		(start 195.495 127.725)
		(mid 195.538934 127.831066)
		(end 195.645 127.875)
		(width 0.09)
		(layer "In9.Cu")
		(net 10)
	)
	(arc
		(start 195.802785 128.654642)
		(mid 195.908851 128.610708)
		(end 196.014917 128.654642)
		(width 0.09)
		(layer "In9.Cu")
		(net 10)
	)
	(arc
		(start 195.98289 128.025)
		(mid 195.938956 128.131066)
		(end 195.83289 128.175)
		(width 0.09)
		(layer "In9.Cu")
		(net 10)
	)
	(arc
		(start 195.919263 128.962425)
		(mid 195.875329 129.068491)
		(end 195.919263 129.174557)
		(width 0.09)
		(layer "In9.Cu")
		(net 10)
	)
	(arc
		(start 195.495 128.750294)
		(mid 195.601068 128.794229)
		(end 195.707133 128.750293)
		(width 0.09)
		(layer "In9.Cu")
		(net 10)
	)
	(via
		(at 204.095839 116.600701)
		(size 0.35)
		(drill 0.15)
		(layers "F.Cu" "B.Cu")
		(remove_unused_layers yes)
		(keep_end_layers yes)
		(zone_layer_connections)
		(net 11)
	)
	(via
		(at 204.499 128.3)
		(size 0.35)
		(drill 0.15)
		(layers "F.Cu" "B.Cu")
		(remove_unused_layers yes)
		(keep_end_layers yes)
		(zone_layer_connections)
		(net 11)
	)
	(segment
		(start 203.99654 116.7)
		(end 203.976025 116.7)
		(width 0.15)
		(layer "B.Cu")
		(net 11)
	)
	(segment
		(start 204.095839 116.600701)
		(end 203.99654 116.7)
		(width 0.15)
		(layer "B.Cu")
		(net 11)
	)
	(segment
		(start 203.976025 116.7)
		(end 203.722 116.954025)
		(width 0.15)
		(layer "B.Cu")
		(net 11)
	)
	(segment
		(start 203.722 116.954025)
		(end 203.722 117.461)
		(width 0.15)
		(layer "B.Cu")
		(net 11)
	)
	(segment
		(start 204.499 128.3)
		(end 204.9 127.899)
		(width 0.09)
		(layer "In7.Cu")
		(net 11)
	)
	(segment
		(start 203.724701 116.600701)
		(end 203.6 116.476)
		(width 0.09)
		(layer "In7.Cu")
		(net 11)
	)
	(segment
		(start 203.75 119.8)
		(end 203.85 119.7)
		(width 0.09)
		(layer "In7.Cu")
		(net 11)
	)
	(segment
		(start 203.224772 116.476)
		(end 203.6 116.476)
		(width 0.09)
		(layer "In7.Cu")
		(net 11)
	)
	(segment
		(start 203.85 118.21038)
		(end 203.05 117.41038)
		(width 0.09)
		(layer "In7.Cu")
		(net 11)
	)
	(segment
		(start 204.9 127.899)
		(end 204.9 122.825772)
		(width 0.09)
		(layer "In7.Cu")
		(net 11)
	)
	(segment
		(start 204.9 122.825772)
		(end 203.75 121.675772)
		(width 0.09)
		(layer "In7.Cu")
		(net 11)
	)
	(segment
		(start 203.05 117.41038)
		(end 203.05 116.650772)
		(width 0.09)
		(layer "In7.Cu")
		(net 11)
	)
	(segment
		(start 203.05 116.650772)
		(end 203.224772 116.476)
		(width 0.09)
		(layer "In7.Cu")
		(net 11)
	)
	(segment
		(start 203.85 119.7)
		(end 203.85 118.21038)
		(width 0.09)
		(layer "In7.Cu")
		(net 11)
	)
	(segment
		(start 203.75 121.675772)
		(end 203.75 119.8)
		(width 0.09)
		(layer "In7.Cu")
		(net 11)
	)
	(segment
		(start 204.095839 116.600701)
		(end 203.724701 116.600701)
		(width 0.09)
		(layer "In7.Cu")
		(net 11)
	)
	(via
		(at 203.315 118.71)
		(size 0.35)
		(drill 0.15)
		(layers "F.Cu" "B.Cu")
		(remove_unused_layers yes)
		(keep_end_layers yes)
		(zone_layer_connections)
		(net 12)
	)
	(via
		(at 206.1 137.101)
		(size 0.35)
		(drill 0.15)
		(layers "F.Cu" "B.Cu")
		(remove_unused_layers yes)
		(keep_end_layers yes)
		(zone_layer_connections)
		(net 12)
	)
	(segment
		(start 203.72 118.978)
		(end 203.72 120.17)
		(width 0.15)
		(layer "B.Cu")
		(net 12)
	)
	(segment
		(start 203.315 118.71)
		(end 203.452 118.71)
		(width 0.15)
		(layer "B.Cu")
		(net 12)
	)
	(segment
		(start 203.72 120.17)
		(end 203.721 120.171)
		(width 0.15)
		(layer "B.Cu")
		(net 12)
	)
	(segment
		(start 203.452 118.71)
		(end 203.72 118.978)
		(width 0.15)
		(layer "B.Cu")
		(net 12)
	)
	(segment
		(start 204.72 117.430683)
		(end 204.72 119.22)
		(width 0.09)
		(layer "In7.Cu")
		(net 12)
	)
	(segment
		(start 202.845 118.24)
		(end 202.845 116.58)
		(width 0.09)
		(layer "In7.Cu")
		(net 12)
	)
	(segment
		(start 209.3725 120.575038)
		(end 209.3725 134.4275)
		(width 0.09)
		(layer "In7.Cu")
		(net 12)
	)
	(segment
		(start 204.72 119.22)
		(end 205.75 120.25)
		(width 0.09)
		(layer "In7.Cu")
		(net 12)
	)
	(segment
		(start 203.315 118.71)
		(end 202.845 118.24)
		(width 0.09)
		(layer "In7.Cu")
		(net 12)
	)
	(segment
		(start 209.047462 120.25)
		(end 209.3725 120.575038)
		(width 0.09)
		(layer "In7.Cu")
		(net 12)
	)
	(segment
		(start 204.875 116.73538)
		(end 204.875 117.275683)
		(width 0.09)
		(layer "In7.Cu")
		(net 12)
	)
	(segment
		(start 207.725 135.725)
		(end 206.349 137.101)
		(width 0.09)
		(layer "In7.Cu")
		(net 12)
	)
	(segment
		(start 202.845 116.58)
		(end 203.144 116.281)
		(width 0.09)
		(layer "In7.Cu")
		(net 12)
	)
	(segment
		(start 208.075 135.725)
		(end 207.725 135.725)
		(width 0.09)
		(layer "In7.Cu")
		(net 12)
	)
	(segment
		(start 205.75 120.25)
		(end 209.047462 120.25)
		(width 0.09)
		(layer "In7.Cu")
		(net 12)
	)
	(segment
		(start 209.3725 134.4275)
		(end 208.075 135.725)
		(width 0.09)
		(layer "In7.Cu")
		(net 12)
	)
	(segment
		(start 206.349 137.101)
		(end 206.1 137.101)
		(width 0.09)
		(layer "In7.Cu")
		(net 12)
	)
	(segment
		(start 204.875 117.275683)
		(end 204.72 117.430683)
		(width 0.09)
		(layer "In7.Cu")
		(net 12)
	)
	(segment
		(start 203.144 116.281)
		(end 204.42062 116.281)
		(width 0.09)
		(layer "In7.Cu")
		(net 12)
	)
	(segment
		(start 204.42062 116.281)
		(end 204.875 116.73538)
		(width 0.09)
		(layer "In7.Cu")
		(net 12)
	)
	(segment
		(start 220.9897 116.7097)
		(end 221.7298 116.7097)
		(width 0.1)
		(layer "F.Cu")
		(net 13)
	)
	(segment
		(start 218.55 116.4)
		(end 218.664 116.286)
		(width 0.1)
		(layer "F.Cu")
		(net 13)
	)
	(segment
		(start 218.55 116.925)
		(end 218.55 116.4)
		(width 0.1)
		(layer "F.Cu")
		(net 13)
	)
	(segment
		(start 218.664 116.286)
		(end 220.566 116.286)
		(width 0.1)
		(layer "F.Cu")
		(net 13)
	)
	(segment
		(start 220.566 116.286)
		(end 220.9897 116.7097)
		(width 0.1)
		(layer "F.Cu")
		(net 13)
	)
	(segment
		(start 184.27 152.535)
		(end 184.275 152.53)
		(width 0.4)
		(layer "B.Cu")
		(net 14)
	)
	(segment
		(start 181.45 152.535)
		(end 184.27 152.535)
		(width 0.4)
		(layer "B.Cu")
		(net 14)
	)
	(segment
		(start 210.958578 152.87)
		(end 210.61 152.87)
		(width 0.11)
		(layer "F.Cu")
		(net 15)
	)
	(segment
		(start 209.55 153.130042)
		(end 209.55 153.31)
		(width 0.11)
		(layer "F.Cu")
		(net 15)
	)
	(segment
		(start 211.8885 153.2715)
		(end 211.5935 153.2715)
		(width 0.11)
		(layer "F.Cu")
		(net 15)
	)
	(segment
		(start 209.94 153)
		(end 209.85 152.91)
		(width 0.11)
		(layer "F.Cu")
		(net 15)
	)
	(segment
		(start 211.5935 153.2715)
		(end 211.4935 153.1715)
		(width 0.11)
		(layer "F.Cu")
		(net 15)
	)
	(segment
		(start 211.260078 153.1715)
		(end 210.958578 152.87)
		(width 0.11)
		(layer "F.Cu")
		(net 15)
	)
	(segment
		(start 211.4935 153.1715)
		(end 211.260078 153.1715)
		(width 0.11)
		(layer "F.Cu")
		(net 15)
	)
	(segment
		(start 210.48 153)
		(end 209.94 153)
		(width 0.11)
		(layer "F.Cu")
		(net 15)
	)
	(segment
		(start 209.85 152.91)
		(end 209.770042 152.91)
		(width 0.11)
		(layer "F.Cu")
		(net 15)
	)
	(segment
		(start 209.770042 152.91)
		(end 209.55 153.130042)
		(width 0.11)
		(layer "F.Cu")
		(net 15)
	)
	(segment
		(start 210.61 152.87)
		(end 210.48 153)
		(width 0.11)
		(layer "F.Cu")
		(net 15)
	)
	(via
		(at 209.55 153.31)
		(size 0.35)
		(drill 0.15)
		(layers "F.Cu" "B.Cu")
		(remove_unused_layers yes)
		(keep_end_layers yes)
		(zone_layer_connections)
		(net 15)
	)
	(segment
		(start 208.922 151.676)
		(end 208.922 151.461)
		(width 0.11)
		(layer "B.Cu")
		(net 15)
	)
	(segment
		(start 208.822 151.890578)
		(end 208.822 151.776)
		(width 0.11)
		(layer "B.Cu")
		(net 15)
	)
	(segment
		(start 208.822 151.776)
		(end 208.922 151.676)
		(width 0.11)
		(layer "B.Cu")
		(net 15)
	)
	(segment
		(start 209.55 153.130042)
		(end 209.673236 153.006806)
		(width 0.11)
		(layer "B.Cu")
		(net 15)
	)
	(segment
		(start 209.55 153.31)
		(end 209.55 153.130042)
		(width 0.11)
		(layer "B.Cu")
		(net 15)
	)
	(segment
		(start 209.673236 152.741814)
		(end 208.822 151.890578)
		(width 0.11)
		(layer "B.Cu")
		(net 15)
	)
	(segment
		(start 209.673236 153.006806)
		(end 209.673236 152.741814)
		(width 0.11)
		(layer "B.Cu")
		(net 15)
	)
	(segment
		(start 211.5935 152.8715)
		(end 211.4935 152.9715)
		(width 0.11)
		(layer "F.Cu")
		(net 16)
	)
	(segment
		(start 209.94 152.55)
		(end 209.82 152.67)
		(width 0.11)
		(layer "F.Cu")
		(net 16)
	)
	(segment
		(start 209.408578 152.98862)
		(end 209.22862 152.98862)
		(width 0.11)
		(layer "F.Cu")
		(net 16)
	)
	(segment
		(start 210.5 152.55)
		(end 209.94 152.55)
		(width 0.11)
		(layer "F.Cu")
		(net 16)
	)
	(segment
		(start 211.342922 152.9715)
		(end 211.041422 152.67)
		(width 0.11)
		(layer "F.Cu")
		(net 16)
	)
	(segment
		(start 209.82 152.67)
		(end 209.727198 152.67)
		(width 0.11)
		(layer "F.Cu")
		(net 16)
	)
	(segment
		(start 210.62 152.67)
		(end 210.5 152.55)
		(width 0.11)
		(layer "F.Cu")
		(net 16)
	)
	(segment
		(start 211.8885 152.8715)
		(end 211.5935 152.8715)
		(width 0.11)
		(layer "F.Cu")
		(net 16)
	)
	(segment
		(start 211.041422 152.67)
		(end 210.62 152.67)
		(width 0.11)
		(layer "F.Cu")
		(net 16)
	)
	(segment
		(start 211.4935 152.9715)
		(end 211.342922 152.9715)
		(width 0.11)
		(layer "F.Cu")
		(net 16)
	)
	(segment
		(start 209.727198 152.67)
		(end 209.408578 152.98862)
		(width 0.11)
		(layer "F.Cu")
		(net 16)
	)
	(via
		(at 209.22862 152.98862)
		(size 0.35)
		(drill 0.15)
		(layers "F.Cu" "B.Cu")
		(remove_unused_layers yes)
		(keep_end_layers yes)
		(zone_layer_connections)
		(net 16)
	)
	(segment
		(start 208.622 151.973422)
		(end 208.622 151.776)
		(width 0.11)
		(layer "B.Cu")
		(net 16)
	)
	(segment
		(start 209.473236 152.923962)
		(end 209.473236 152.824658)
		(width 0.11)
		(layer "B.Cu")
		(net 16)
	)
	(segment
		(start 208.622 151.776)
		(end 208.522 151.676)
		(width 0.11)
		(layer "B.Cu")
		(net 16)
	)
	(segment
		(start 209.473236 152.824658)
		(end 208.622 151.973422)
		(width 0.11)
		(layer "B.Cu")
		(net 16)
	)
	(segment
		(start 209.408578 152.98862)
		(end 209.473236 152.923962)
		(width 0.11)
		(layer "B.Cu")
		(net 16)
	)
	(segment
		(start 208.522 151.676)
		(end 208.522 151.461)
		(width 0.11)
		(layer "B.Cu")
		(net 16)
	)
	(segment
		(start 209.22862 152.98862)
		(end 209.408578 152.98862)
		(width 0.11)
		(layer "B.Cu")
		(net 16)
	)
	(via
		(at 202.121 116.84)
		(size 0.35)
		(drill 0.15)
		(layers "F.Cu" "B.Cu")
		(remove_unused_layers yes)
		(keep_end_layers yes)
		(zone_layer_connections)
		(net 17)
	)
	(via
		(at 200.425 133.882135)
		(size 0.35)
		(drill 0.15)
		(layers "F.Cu" "B.Cu")
		(remove_unused_layers yes)
		(keep_end_layers yes)
		(zone_layer_connections)
		(net 17)
	)
	(segment
		(start 202.121 116.84)
		(end 202.121 117.457)
		(width 0.15)
		(layer "B.Cu")
		(net 17)
	)
	(segment
		(start 202.121 117.457)
		(end 202.117 117.461)
		(width 0.15)
		(layer "B.Cu")
		(net 17)
	)
	(segment
		(start 201.45 121.592521)
		(end 201.45 119.631651)
		(width 0.09)
		(layer "In7.Cu")
		(net 17)
	)
	(segment
		(start 201.7 132.5)
		(end 201.7 121.842521)
		(width 0.09)
		(layer "In7.Cu")
		(net 17)
	)
	(segment
		(start 200.9 133.407135)
		(end 200.9 133.048451)
		(width 0.09)
		(layer "In7.Cu")
		(net 17)
	)
	(segment
		(start 201.5 132.7)
		(end 201.7 132.5)
		(width 0.09)
		(layer "In7.Cu")
		(net 17)
	)
	(segment
		(start 202.121 117.66838)
		(end 202.121 116.84)
		(width 0.09)
		(layer "In7.Cu")
		(net 17)
	)
	(segment
		(start 201.706481 119.37517)
		(end 201.706481 118.082899)
		(width 0.09)
		(layer "In7.Cu")
		(net 17)
	)
	(segment
		(start 201.45 119.631651)
		(end 201.706481 119.37517)
		(width 0.09)
		(layer "In7.Cu")
		(net 17)
	)
	(segment
		(start 200.9 133.048451)
		(end 201.248451 132.7)
		(width 0.09)
		(layer "In7.Cu")
		(net 17)
	)
	(segment
		(start 201.248451 132.7)
		(end 201.5 132.7)
		(width 0.09)
		(layer "In7.Cu")
		(net 17)
	)
	(segment
		(start 201.7 121.842521)
		(end 201.45 121.592521)
		(width 0.09)
		(layer "In7.Cu")
		(net 17)
	)
	(segment
		(start 200.425 133.882135)
		(end 200.9 133.407135)
		(width 0.09)
		(layer "In7.Cu")
		(net 17)
	)
	(segment
		(start 201.706481 118.082899)
		(end 202.121 117.66838)
		(width 0.09)
		(layer "In7.Cu")
		(net 17)
	)
	(via
		(at 202.293 119.4)
		(size 0.35)
		(drill 0.15)
		(layers "F.Cu" "B.Cu")
		(remove_unused_layers yes)
		(keep_end_layers yes)
		(zone_layer_connections)
		(net 18)
	)
	(via
		(at 204.499 131.501)
		(size 0.35)
		(drill 0.15)
		(layers "F.Cu" "B.Cu")
		(remove_unused_layers yes)
		(keep_end_layers yes)
		(zone_layer_connections)
		(net 18)
	)
	(segment
		(start 202.117 119.576)
		(end 202.293 119.4)
		(width 0.15)
		(layer "B.Cu")
		(net 18)
	)
	(segment
		(start 202.117 120.171)
		(end 202.117 119.576)
		(width 0.15)
		(layer "B.Cu")
		(net 18)
	)
	(segment
		(start 204.025 129.4)
		(end 203.27384 128.64884)
		(width 0.09)
		(layer "In7.Cu")
		(net 18)
	)
	(segment
		(start 204.025 131.027)
		(end 204.025 129.4)
		(width 0.09)
		(layer "In7.Cu")
		(net 18)
	)
	(segment
		(start 203.27384 120.37884)
		(end 202.295 119.4)
		(width 0.09)
		(layer "In7.Cu")
		(net 18)
	)
	(segment
		(start 203.27384 128.64884)
		(end 203.27384 120.37884)
		(width 0.09)
		(layer "In7.Cu")
		(net 18)
	)
	(segment
		(start 204.499 131.501)
		(end 204.025 131.027)
		(width 0.09)
		(layer "In7.Cu")
		(net 18)
	)
	(via
		(at 205.372 154.9)
		(size 0.35)
		(drill 0.15)
		(layers "F.Cu" "B.Cu")
		(remove_unused_layers yes)
		(keep_end_layers yes)
		(zone_layer_connections)
		(net 19)
	)
	(via
		(at 199.46 143.59)
		(size 0.35)
		(drill 0.15)
		(layers "F.Cu" "B.Cu")
		(remove_unused_layers yes)
		(keep_end_layers yes)
		(zone_layer_connections)
		(net 19)
	)
	(segment
		(start 205.2295 154.4785)
		(end 205.2295 154.7575)
		(width 0.125)
		(layer "B.Cu")
		(net 19)
	)
	(segment
		(start 205.2295 154.7575)
		(end 205.372 154.9)
		(width 0.125)
		(layer "B.Cu")
		(net 19)
	)
	(segment
		(start 205.322 154.171)
		(end 205.322 154.386)
		(width 0.125)
		(layer "B.Cu")
		(net 19)
	)
	(segment
		(start 205.322 154.386)
		(end 205.2295 154.4785)
		(width 0.125)
		(layer "B.Cu")
		(net 19)
	)
	(segment
		(start 199.14 144.95)
		(end 199.14 143.518165)
		(width 0.1)
		(layer "In2.Cu")
		(net 19)
	)
	(segment
		(start 199.49 148.788578)
		(end 199.14 148.438578)
		(width 0.1)
		(layer "In2.Cu")
		(net 19)
	)
	(segment
		(start 205.222 154.75)
		(end 205.222 154.575236)
		(width 0.1)
		(layer "In2.Cu")
		(net 19)
	)
	(segment
		(start 204.866764 154.22)
		(end 200.881422 154.22)
		(width 0.1)
		(layer "In2.Cu")
		(net 19)
	)
	(segment
		(start 200.881422 154.22)
		(end 199.49 152.828578)
		(width 0.1)
		(layer "In2.Cu")
		(net 19)
	)
	(segment
		(start 199.14 143.518165)
		(end 199.223165 143.435)
		(width 0.1)
		(layer "In2.Cu")
		(net 19)
	)
	(segment
		(start 199.223165 143.435)
		(end 199.305 143.435)
		(width 0.1)
		(layer "In2.Cu")
		(net 19)
	)
	(segment
		(start 199.49 152.828578)
		(end 199.49 148.788578)
		(width 0.1)
		(layer "In2.Cu")
		(net 19)
	)
	(segment
		(start 205.222 154.575236)
		(end 204.866764 154.22)
		(width 0.1)
		(layer "In2.Cu")
		(net 19)
	)
	(segment
		(start 199.14 148.438578)
		(end 199.14 145.815148)
		(width 0.1)
		(layer "In2.Cu")
		(net 19)
	)
	(segment
		(start 199.212575 145.502574)
		(end 199.212574 145.502574)
		(width 0.1)
		(layer "In2.Cu")
		(net 19)
	)
	(segment
		(start 199.285149 145.67)
		(end 199.285149 145.575148)
		(width 0.1)
		(layer "In2.Cu")
		(net 19)
	)
	(segment
		(start 205.372 154.9)
		(end 205.222 154.75)
		(width 0.1)
		(layer "In2.Cu")
		(net 19)
	)
	(segment
		(start 199.305 143.435)
		(end 199.46 143.59)
		(width 0.1)
		(layer "In2.Cu")
		(net 19)
	)
	(segment
		(start 199.212574 145.262574)
		(end 199.212575 145.262574)
		(width 0.1)
		(layer "In2.Cu")
		(net 19)
	)
	(segment
		(start 199.285149 145.19)
		(end 199.285149 145.095148)
		(width 0.1)
		(layer "In2.Cu")
		(net 19)
	)
	(segment
		(start 199.212575 145.022574)
		(end 199.212574 145.022574)
		(width 0.1)
		(layer "In2.Cu")
		(net 19)
	)
	(segment
		(start 199.14 145.43)
		(end 199.14 145.335148)
		(width 0.1)
		(layer "In2.Cu")
		(net 19)
	)
	(segment
		(start 199.212574 145.742574)
		(end 199.212575 145.742574)
		(width 0.1)
		(layer "In2.Cu")
		(net 19)
	)
	(arc
		(start 199.212575 145.262574)
		(mid 199.263893 145.241318)
		(end 199.285149 145.19)
		(width 0.1)
		(layer "In2.Cu")
		(net 19)
	)
	(arc
		(start 199.14 145.335148)
		(mid 199.161256 145.28383)
		(end 199.212574 145.262574)
		(width 0.1)
		(layer "In2.Cu")
		(net 19)
	)
	(arc
		(start 199.14 145.815148)
		(mid 199.161256 145.76383)
		(end 199.212574 145.742574)
		(width 0.1)
		(layer "In2.Cu")
		(net 19)
	)
	(arc
		(start 199.212575 145.742574)
		(mid 199.263893 145.721318)
		(end 199.285149 145.67)
		(width 0.1)
		(layer "In2.Cu")
		(net 19)
	)
	(arc
		(start 199.285149 145.575148)
		(mid 199.263893 145.52383)
		(end 199.212575 145.502574)
		(width 0.1)
		(layer "In2.Cu")
		(net 19)
	)
	(arc
		(start 199.212574 145.022574)
		(mid 199.161256 145.001318)
		(end 199.14 144.95)
		(width 0.1)
		(layer "In2.Cu")
		(net 19)
	)
	(arc
		(start 199.212574 145.502574)
		(mid 199.161256 145.481318)
		(end 199.14 145.43)
		(width 0.1)
		(layer "In2.Cu")
		(net 19)
	)
	(arc
		(start 199.285149 145.095148)
		(mid 199.263893 145.04383)
		(end 199.212575 145.022574)
		(width 0.1)
		(layer "In2.Cu")
		(net 19)
	)
	(via
		(at 204.52 116.84)
		(size 0.35)
		(drill 0.15)
		(layers "F.Cu" "B.Cu")
		(remove_unused_layers yes)
		(keep_end_layers yes)
		(zone_layer_connections)
		(net 20)
	)
	(via
		(at 203.699 137.901)
		(size 0.35)
		(drill 0.15)
		(layers "F.Cu" "B.Cu")
		(remove_unused_layers yes)
		(keep_end_layers yes)
		(zone_layer_connections)
		(net 20)
	)
	(segment
		(start 204.52 117.459)
		(end 204.522 117.461)
		(width 0.15)
		(layer "B.Cu")
		(net 20)
	)
	(segment
		(start 204.52 116.84)
		(end 204.52 117.459)
		(width 0.15)
		(layer "B.Cu")
		(net 20)
	)
	(segment
		(start 204.1 137.5)
		(end 203.699 137.901)
		(width 0.09)
		(layer "In7.Cu")
		(net 20)
	)
	(segment
		(start 204.52 119.745)
		(end 205.226002 120.451002)
		(width 0.09)
		(layer "In7.Cu")
		(net 20)
	)
	(segment
		(start 208.62 121.087451)
		(end 208.62 134.48)
		(width 0.09)
		(layer "In7.Cu")
		(net 20)
	)
	(segment
		(start 204.925 137.25)
		(end 204.675 137.5)
		(width 0.09)
		(layer "In7.Cu")
		(net 20)
	)
	(segment
		(start 208.432549 120.9)
		(end 208.62 121.087451)
		(width 0.09)
		(layer "In7.Cu")
		(net 20)
	)
	(segment
		(start 205.16438 136.776)
		(end 204.925 137.01538)
		(width 0.09)
		(layer "In7.Cu")
		(net 20)
	)
	(segment
		(start 208.425 120.9)
		(end 208.432549 120.9)
		(width 0.09)
		(layer "In7.Cu")
		(net 20)
	)
	(segment
		(start 207.976002 120.451002)
		(end 208.425 120.9)
		(width 0.09)
		(layer "In7.Cu")
		(net 20)
	)
	(segment
		(start 208.62 134.48)
		(end 206.324 136.776)
		(width 0.09)
		(layer "In7.Cu")
		(net 20)
	)
	(segment
		(start 204.675 137.5)
		(end 204.1 137.5)
		(width 0.09)
		(layer "In7.Cu")
		(net 20)
	)
	(segment
		(start 204.925 137.01538)
		(end 204.925 137.25)
		(width 0.09)
		(layer "In7.Cu")
		(net 20)
	)
	(segment
		(start 206.324 136.776)
		(end 205.16438 136.776)
		(width 0.09)
		(layer "In7.Cu")
		(net 20)
	)
	(segment
		(start 204.52 116.84)
		(end 204.52 119.745)
		(width 0.09)
		(layer "In7.Cu")
		(net 20)
	)
	(segment
		(start 205.226002 120.451002)
		(end 207.976002 120.451002)
		(width 0.09)
		(layer "In7.Cu")
		(net 20)
	)
	(via
		(at 202.9 134.7)
		(size 0.35)
		(drill 0.15)
		(layers "F.Cu" "B.Cu")
		(remove_unused_layers yes)
		(keep_end_layers yes)
		(zone_layer_connections)
		(net 21)
	)
	(via
		(at 201.322 116.84)
		(size 0.35)
		(drill 0.15)
		(layers "F.Cu" "B.Cu")
		(remove_unused_layers yes)
		(keep_end_layers yes)
		(zone_layer_connections)
		(net 21)
	)
	(segment
		(start 201.322 116.84)
		(end 201.322 117.461)
		(width 0.15)
		(layer "B.Cu")
		(net 21)
	)
	(segment
		(start 200.715294 118.992463)
		(end 200.775 119.052169)
		(width 0.09)
		(layer "In7.Cu")
		(net 21)
	)
	(segment
		(start 200.775 117.881802)
		(end 200.775 118.497832)
		(width 0.09)
		(layer "In7.Cu")
		(net 21)
	)
	(segment
		(start 200.775 120.25738)
		(end 200.125 120.907379)
		(width 0.09)
		(layer "In7.Cu")
		(net 21)
	)
	(segment
		(start 199.778 133.878)
		(end 200.15 134.25)
		(width 0.09)
		(layer "In7.Cu")
		(net 21)
	)
	(segment
		(start 200.775 118.497832)
		(end 200.715294 118.557538)
		(width 0.09)
		(layer "In7.Cu")
		(net 21)
	)
	(segment
		(start 200.125 123.05)
		(end 200.1 123.075)
		(width 0.09)
		(layer "In7.Cu")
		(net 21)
	)
	(segment
		(start 200.775 119.052169)
		(end 200.775 120.25738)
		(width 0.09)
		(layer "In7.Cu")
		(net 21)
	)
	(segment
		(start 201.322 117.334802)
		(end 200.775 117.881802)
		(width 0.09)
		(layer "In7.Cu")
		(net 21)
	)
	(segment
		(start 200.715294 118.557538)
		(end 200.715294 118.992463)
		(width 0.09)
		(layer "In7.Cu")
		(net 21)
	)
	(segment
		(start 200.15 134.25)
		(end 202.45 134.25)
		(width 0.09)
		(layer "In7.Cu")
		(net 21)
	)
	(segment
		(start 202.45 134.25)
		(end 202.9 134.7)
		(width 0.09)
		(layer "In7.Cu")
		(net 21)
	)
	(segment
		(start 200.125 120.907379)
		(end 200.125 123.05)
		(width 0.09)
		(layer "In7.Cu")
		(net 21)
	)
	(segment
		(start 200.1 123.075)
		(end 200.1 132.244451)
		(width 0.09)
		(layer "In7.Cu")
		(net 21)
	)
	(segment
		(start 201.322 116.84)
		(end 201.322 117.334802)
		(width 0.09)
		(layer "In7.Cu")
		(net 21)
	)
	(segment
		(start 200.1 132.244451)
		(end 199.778 132.566451)
		(width 0.09)
		(layer "In7.Cu")
		(net 21)
	)
	(segment
		(start 199.778 132.566451)
		(end 199.778 133.878)
		(width 0.09)
		(layer "In7.Cu")
		(net 21)
	)
	(via
		(at 202.9 138.7)
		(size 0.35)
		(drill 0.15)
		(layers "F.Cu" "B.Cu")
		(remove_unused_layers yes)
		(keep_end_layers yes)
		(zone_layer_connections)
		(net 22)
	)
	(via
		(at 201.373 118.825)
		(size 0.35)
		(drill 0.15)
		(layers "F.Cu" "B.Cu")
		(remove_unused_layers yes)
		(keep_end_layers yes)
		(zone_layer_connections)
		(net 22)
	)
	(segment
		(start 200.915 119.210056)
		(end 200.915 120.171)
		(width 0.15)
		(layer "B.Cu")
		(net 22)
	)
	(segment
		(start 201.373 118.825)
		(end 201.300056 118.825)
		(width 0.15)
		(layer "B.Cu")
		(net 22)
	)
	(segment
		(start 201.300056 118.825)
		(end 200.915 119.210056)
		(width 0.15)
		(layer "B.Cu")
		(net 22)
	)
	(segment
		(start 198.76438 136.626)
		(end 199.226 136.626)
		(width 0.1)
		(layer "In9.Cu")
		(net 22)
	)
	(segment
		(start 192.1875 133.4775)
		(end 194.5775 133.4775)
		(width 0.1)
		(layer "In9.Cu")
		(net 22)
	)
	(segment
		(start 199.775 117.951593)
		(end 199.423407 117.6)
		(width 0.1)
		(layer "In9.Cu")
		(net 22)
	)
	(segment
		(start 202.45 138.25)
		(end 202.9 138.7)
		(width 0.1)
		(layer "In9.Cu")
		(net 22)
	)
	(segment
		(start 200.175 118.825)
		(end 199.775 118.425)
		(width 0.1)
		(layer "In9.Cu")
		(net 22)
	)
	(segment
		(start 198.3 136.16162)
		(end 198.76438 136.626)
		(width 0.1)
		(layer "In9.Cu")
		(net 22)
	)
	(segment
		(start 199.226 136.626)
		(end 199.65 137.05)
		(width 0.1)
		(layer "In9.Cu")
		(net 22)
	)
	(segment
		(start 196.7 117.6)
		(end 195.675 118.625)
		(width 0.1)
		(layer "In9.Cu")
		(net 22)
	)
	(segment
		(start 195.53 119.82)
		(end 194.71 119.82)
		(width 0.1)
		(layer "In9.Cu")
		(net 22)
	)
	(segment
		(start 199.69038 138.25)
		(end 202.45 138.25)
		(width 0.1)
		(layer "In9.Cu")
		(net 22)
	)
	(segment
		(start 199.65 137.49038)
		(end 199.425 137.71538)
		(width 0.1)
		(layer "In9.Cu")
		(net 22)
	)
	(segment
		(start 199.65 137.05)
		(end 199.65 137.49038)
		(width 0.1)
		(layer "In9.Cu")
		(net 22)
	)
	(segment
		(start 194.5775 133.4775)
		(end 195.825 134.725)
		(width 0.1)
		(layer "In9.Cu")
		(net 22)
	)
	(segment
		(start 191.325 123.205)
		(end 191.325 132.615)
		(width 0.1)
		(layer "In9.Cu")
		(net 22)
	)
	(segment
		(start 198.3 135.125)
		(end 198.3 136.16162)
		(width 0.1)
		(layer "In9.Cu")
		(net 22)
	)
	(segment
		(start 199.423407 117.6)
		(end 196.7 117.6)
		(width 0.1)
		(layer "In9.Cu")
		(net 22)
	)
	(segment
		(start 195.675 119.675)
		(end 195.53 119.82)
		(width 0.1)
		(layer "In9.Cu")
		(net 22)
	)
	(segment
		(start 201.375 118.825)
		(end 200.175 118.825)
		(width 0.1)
		(layer "In9.Cu")
		(net 22)
	)
	(segment
		(start 199.425 137.98462)
		(end 199.69038 138.25)
		(width 0.1)
		(layer "In9.Cu")
		(net 22)
	)
	(segment
		(start 195.825 134.725)
		(end 197.9 134.725)
		(width 0.1)
		(layer "In9.Cu")
		(net 22)
	)
	(segment
		(start 191.325 132.615)
		(end 192.1875 133.4775)
		(width 0.1)
		(layer "In9.Cu")
		(net 22)
	)
	(segment
		(start 195.675 118.625)
		(end 195.675 119.675)
		(width 0.1)
		(layer "In9.Cu")
		(net 22)
	)
	(segment
		(start 197.9 134.725)
		(end 198.3 135.125)
		(width 0.1)
		(layer "In9.Cu")
		(net 22)
	)
	(segment
		(start 199.775 118.425)
		(end 199.775 117.951593)
		(width 0.1)
		(layer "In9.Cu")
		(net 22)
	)
	(segment
		(start 194.71 119.82)
		(end 191.325 123.205)
		(width 0.1)
		(layer "In9.Cu")
		(net 22)
	)
	(segment
		(start 199.425 137.71538)
		(end 199.425 137.98462)
		(width 0.1)
		(layer "In9.Cu")
		(net 22)
	)
	(via
		(at 200.51908 116.84)
		(size 0.35)
		(drill 0.15)
		(layers "F.Cu" "B.Cu")
		(remove_unused_layers yes)
		(keep_end_layers yes)
		(zone_layer_connections)
		(net 23)
	)
	(via
		(at 202.9 137.901)
		(size 0.35)
		(drill 0.15)
		(layers "F.Cu" "B.Cu")
		(remove_unused_layers yes)
		(keep_end_layers yes)
		(zone_layer_connections)
		(net 23)
	)
	(segment
		(start 200.51908 117.45808)
		(end 200.522 117.461)
		(width 0.15)
		(layer "B.Cu")
		(net 23)
	)
	(segment
		(start 200.51908 116.84)
		(end 200.51908 117.45808)
		(width 0.15)
		(layer "B.Cu")
		(net 23)
	)
	(segment
		(start 200.575 120.075)
		(end 199.925 120.725)
		(width 0.09)
		(layer "In7.Cu")
		(net 23)
	)
	(segment
		(start 199.925 122.275)
		(end 199.3 122.9)
		(width 0.09)
		(layer "In7.Cu")
		(net 23)
	)
	(segment
		(start 200.375 135.075)
		(end 202.475 135.075)
		(width 0.09)
		(layer "In7.Cu")
		(net 23)
	)
	(segment
		(start 200.515294 119.075306)
		(end 200.575 119.135012)
		(width 0.09)
		(layer "In7.Cu")
		(net 23)
	)
	(segment
		(start 203.22 135.82)
		(end 203.22 136.432549)
		(width 0.09)
		(layer "In7.Cu")
		(net 23)
	)
	(segment
		(start 199.3 122.9)
		(end 199.3 132.2)
		(width 0.09)
		(layer "In7.Cu")
		(net 23)
	)
	(segment
		(start 202.575 136.96638)
		(end 202.575 137.576)
		(width 0.09)
		(layer "In7.Cu")
		(net 23)
	)
	(segment
		(start 199.925 120.725)
		(end 199.925 122.275)
		(width 0.09)
		(layer "In7.Cu")
		(net 23)
	)
	(segment
		(start 202.92138 136.62)
		(end 202.575 136.96638)
		(width 0.09)
		(layer "In7.Cu")
		(net 23)
	)
	(segment
		(start 202.475 135.075)
		(end 203.22 135.82)
		(width 0.09)
		(layer "In7.Cu")
		(net 23)
	)
	(segment
		(start 199.3 132.2)
		(end 198.975 132.525)
		(width 0.09)
		(layer "In7.Cu")
		(net 23)
	)
	(segment
		(start 200.575 119.135012)
		(end 200.575 120.075)
		(width 0.09)
		(layer "In7.Cu")
		(net 23)
	)
	(segment
		(start 203.032549 136.62)
		(end 202.92138 136.62)
		(width 0.09)
		(layer "In7.Cu")
		(net 23)
	)
	(segment
		(start 198.975 132.525)
		(end 198.975 133.675)
		(width 0.09)
		(layer "In7.Cu")
		(net 23)
	)
	(segment
		(start 202.575 137.576)
		(end 202.9 137.901)
		(width 0.09)
		(layer "In7.Cu")
		(net 23)
	)
	(segment
		(start 203.22 136.432549)
		(end 203.032549 136.62)
		(width 0.09)
		(layer "In7.Cu")
		(net 23)
	)
	(segment
		(start 200.515294 116.843786)
		(end 200.515294 119.075306)
		(width 0.09)
		(layer "In7.Cu")
		(net 23)
	)
	(segment
		(start 198.975 133.675)
		(end 200.375 135.075)
		(width 0.09)
		(layer "In7.Cu")
		(net 23)
	)
	(segment
		(start 200.51908 116.84)
		(end 200.515294 116.843786)
		(width 0.09)
		(layer "In7.Cu")
		(net 23)
	)
	(via
		(at 205.299 137.101)
		(size 0.35)
		(drill 0.15)
		(layers "F.Cu" "B.Cu")
		(remove_unused_layers yes)
		(keep_end_layers yes)
		(zone_layer_connections)
		(net 24)
	)
	(via
		(at 205.326 118.135)
		(size 0.35)
		(drill 0.15)
		(layers "F.Cu" "B.Cu")
		(remove_unused_layers yes)
		(keep_end_layers yes)
		(zone_layer_connections)
		(net 24)
	)
	(segment
		(start 204.521 118.616)
		(end 204.521 120.17)
		(width 0.15)
		(layer "B.Cu")
		(net 24)
	)
	(segment
		(start 205.002 118.135)
		(end 204.521 118.616)
		(width 0.15)
		(layer "B.Cu")
		(net 24)
	)
	(segment
		(start 204.521 120.17)
		(end 204.52 120.171)
		(width 0.15)
		(layer "B.Cu")
		(net 24)
	)
	(segment
		(start 205.326 118.135)
		(end 205.002 118.135)
		(width 0.15)
		(layer "B.Cu")
		(net 24)
	)
	(segment
		(start 209.8 124.9)
		(end 210.125 125.225)
		(width 0.09)
		(layer "In7.Cu")
		(net 24)
	)
	(segment
		(start 204.989926 118.945)
		(end 205.72602 118.945)
		(width 0.09)
		(layer "In7.Cu")
		(net 24)
	)
	(segment
		(start 210.125 125.225)
		(end 210.125 134.4)
		(width 0.09)
		(layer "In7.Cu")
		(net 24)
	)
	(segment
		(start 209.8 120.55)
		(end 209.8 124.9)
		(width 0.09)
		(layer "In7.Cu")
		(net 24)
	)
	(segment
		(start 209.3 120.05)
		(end 209.8 120.55)
		(width 0.09)
		(layer "In7.Cu")
		(net 24)
	)
	(segment
		(start 206.83102 120.05)
		(end 209.3 120.05)
		(width 0.09)
		(layer "In7.Cu")
		(net 24)
	)
	(segment
		(start 205.326 118.135)
		(end 204.919926 118.541074)
		(width 0.09)
		(layer "In7.Cu")
		(net 24)
	)
	(segment
		(start 204.919926 118.875)
		(end 204.989926 118.945)
		(width 0.09)
		(layer "In7.Cu")
		(net 24)
	)
	(segment
		(start 205.624 137.426)
		(end 205.299 137.101)
		(width 0.09)
		(layer "In7.Cu")
		(net 24)
	)
	(segment
		(start 206.470329 137.426)
		(end 205.624 137.426)
		(width 0.09)
		(layer "In7.Cu")
		(net 24)
	)
	(segment
		(start 208.525 136)
		(end 207.896329 136)
		(width 0.09)
		(layer "In7.Cu")
		(net 24)
	)
	(segment
		(start 205.72602 118.945)
		(end 206.83102 120.05)
		(width 0.09)
		(layer "In7.Cu")
		(net 24)
	)
	(segment
		(start 204.919926 118.541074)
		(end 204.919926 118.875)
		(width 0.09)
		(layer "In7.Cu")
		(net 24)
	)
	(segment
		(start 207.896329 136)
		(end 206.470329 137.426)
		(width 0.09)
		(layer "In7.Cu")
		(net 24)
	)
	(segment
		(start 210.125 134.4)
		(end 208.525 136)
		(width 0.09)
		(layer "In7.Cu")
		(net 24)
	)
	(via
		(at 204.499 137.101)
		(size 0.35)
		(drill 0.15)
		(layers "F.Cu" "B.Cu")
		(remove_unused_layers yes)
		(keep_end_layers yes)
		(zone_layer_connections)
		(net 25)
	)
	(via
		(at 204.121 117.05)
		(size 0.35)
		(drill 0.15)
		(layers "F.Cu" "B.Cu")
		(remove_unused_layers yes)
		(keep_end_layers yes)
		(zone_layer_connections)
		(net 25)
	)
	(segment
		(start 206.32 136.055)
		(end 205.16538 136.055)
		(width 0.09)
		(layer "In7.Cu")
		(net 25)
	)
	(segment
		(start 206.5 122.5)
		(end 207.35 123.35)
		(width 0.09)
		(layer "In7.Cu")
		(net 25)
	)
	(segment
		(start 204.3 117.229)
		(end 204.3 121.38262)
		(width 0.09)
		(layer "In7.Cu")
		(net 25)
	)
	(segment
		(start 207.35 135.025)
		(end 206.32 136.055)
		(width 0.09)
		(layer "In7.Cu")
		(net 25)
	)
	(segment
		(start 204.95 136.27038)
		(end 204.95 136.65)
		(width 0.09)
		(layer "In7.Cu")
		(net 25)
	)
	(segment
		(start 204.121 117.05)
		(end 204.3 117.229)
		(width 0.09)
		(layer "In7.Cu")
		(net 25)
	)
	(segment
		(start 205.41738 122.5)
		(end 206.5 122.5)
		(width 0.09)
		(layer "In7.Cu")
		(net 25)
	)
	(segment
		(start 207.35 123.35)
		(end 207.35 135.025)
		(width 0.09)
		(layer "In7.Cu")
		(net 25)
	)
	(segment
		(start 204.95 136.65)
		(end 204.499 137.101)
		(width 0.09)
		(layer "In7.Cu")
		(net 25)
	)
	(segment
		(start 204.3 121.38262)
		(end 205.41738 122.5)
		(width 0.09)
		(layer "In7.Cu")
		(net 25)
	)
	(segment
		(start 205.16538 136.055)
		(end 204.95 136.27038)
		(width 0.09)
		(layer "In7.Cu")
		(net 25)
	)
	(via
		(at 205.299 137.901)
		(size 0.35)
		(drill 0.15)
		(layers "F.Cu" "B.Cu")
		(remove_unused_layers yes)
		(keep_end_layers yes)
		(zone_layer_connections)
		(net 26)
	)
	(via
		(at 199 118.7)
		(size 0.35)
		(drill 0.15)
		(layers "F.Cu" "B.Cu")
		(remove_unused_layers yes)
		(keep_end_layers yes)
		(zone_layer_connections)
		(net 26)
	)
	(segment
		(start 200.117 118.817)
		(end 200.117 120.171)
		(width 0.15)
		(layer "B.Cu")
		(net 26)
	)
	(segment
		(start 199.7 118.4)
		(end 200.117 118.817)
		(width 0.15)
		(layer "B.Cu")
		(net 26)
	)
	(segment
		(start 199.3 118.4)
		(end 199.7 118.4)
		(width 0.15)
		(layer "B.Cu")
		(net 26)
	)
	(segment
		(start 199 118.7)
		(end 199.3 118.4)
		(width 0.15)
		(layer "B.Cu")
		(net 26)
	)
	(segment
		(start 204.48962 138.37)
		(end 204.95862 137.901)
		(width 0.09)
		(layer "In7.Cu")
		(net 26)
	)
	(segment
		(start 198.5 138.4)
		(end 198.5 138.78)
		(width 0.09)
		(layer "In7.Cu")
		(net 26)
	)
	(segment
		(start 196.18 128.67)
		(end 195.368 129.482)
		(width 0.09)
		(layer "In7.Cu")
		(net 26)
	)
	(segment
		(start 197.867276 135.5)
		(end 198.1 135.732724)
		(width 0.09)
		(layer "In7.Cu")
		(net 26)
	)
	(segment
		(start 195.368 133.268)
		(end 196 133.9)
		(width 0.09)
		(layer "In7.Cu")
		(net 26)
	)
	(segment
		(start 199.921 139.842)
		(end 200.778519 139.842)
		(width 0.09)
		(layer "In7.Cu")
		(net 26)
	)
	(segment
		(start 195.368 129.482)
		(end 195.368 133.268)
		(width 0.09)
		(layer "In7.Cu")
		(net 26)
	)
	(segment
		(start 204.024 138.56538)
		(end 204.21938 138.37)
		(width 0.09)
		(layer "In7.Cu")
		(net 26)
	)
	(segment
		(start 198.1 136.9)
		(end 198.0235 136.9765)
		(width 0.09)
		(layer "In7.Cu")
		(net 26)
	)
	(segment
		(start 198.24 121.51)
		(end 196.18 123.57)
		(width 0.09)
		(layer "In7.Cu")
		(net 26)
	)
	(segment
		(start 199 118.7)
		(end 198.65 119.05)
		(width 0.09)
		(layer "In7.Cu")
		(net 26)
	)
	(segment
		(start 198.65 120.3)
		(end 198.24 120.71)
		(width 0.09)
		(layer "In7.Cu")
		(net 26)
	)
	(segment
		(start 198.1 135.732724)
		(end 198.1 136.9)
		(width 0.09)
		(layer "In7.Cu")
		(net 26)
	)
	(segment
		(start 200.973 139.647519)
		(end 200.973 139.372481)
		(width 0.09)
		(layer "In7.Cu")
		(net 26)
	)
	(segment
		(start 200.973 139.372481)
		(end 201.220481 139.125)
		(width 0.09)
		(layer "In7.Cu")
		(net 26)
	)
	(segment
		(start 204.024 138.892157)
		(end 204.024 138.56538)
		(width 0.09)
		(layer "In7.Cu")
		(net 26)
	)
	(segment
		(start 196.271274 133.9)
		(end 196.5 134.128726)
		(width 0.09)
		(layer "In7.Cu")
		(net 26)
	)
	(segment
		(start 203.791157 139.125)
		(end 204.024 138.892157)
		(width 0.09)
		(layer "In7.Cu")
		(net 26)
	)
	(segment
		(start 198.0235 137.9235)
		(end 198.5 138.4)
		(width 0.09)
		(layer "In7.Cu")
		(net 26)
	)
	(segment
		(start 198.65 119.05)
		(end 198.65 120.3)
		(width 0.09)
		(layer "In7.Cu")
		(net 26)
	)
	(segment
		(start 204.21938 138.37)
		(end 204.48962 138.37)
		(width 0.09)
		(layer "In7.Cu")
		(net 26)
	)
	(segment
		(start 196.5 134.5)
		(end 197.5 135.5)
		(width 0.09)
		(layer "In7.Cu")
		(net 26)
	)
	(segment
		(start 198.5 138.78)
		(end 198.9 139.18)
		(width 0.09)
		(layer "In7.Cu")
		(net 26)
	)
	(segment
		(start 199.259 139.18)
		(end 199.921 139.842)
		(width 0.09)
		(layer "In7.Cu")
		(net 26)
	)
	(segment
		(start 204.95862 137.901)
		(end 205.299 137.901)
		(width 0.09)
		(layer "In7.Cu")
		(net 26)
	)
	(segment
		(start 196 133.9)
		(end 196.271274 133.9)
		(width 0.09)
		(layer "In7.Cu")
		(net 26)
	)
	(segment
		(start 198.24 120.71)
		(end 198.24 121.51)
		(width 0.09)
		(layer "In7.Cu")
		(net 26)
	)
	(segment
		(start 196.5 134.128726)
		(end 196.5 134.5)
		(width 0.09)
		(layer "In7.Cu")
		(net 26)
	)
	(segment
		(start 198.0235 136.9765)
		(end 198.0235 137.9235)
		(width 0.09)
		(layer "In7.Cu")
		(net 26)
	)
	(segment
		(start 197.5 135.5)
		(end 197.867276 135.5)
		(width 0.09)
		(layer "In7.Cu")
		(net 26)
	)
	(segment
		(start 200.778519 139.842)
		(end 200.973 139.647519)
		(width 0.09)
		(layer "In7.Cu")
		(net 26)
	)
	(segment
		(start 196.18 123.57)
		(end 196.18 128.67)
		(width 0.09)
		(layer "In7.Cu")
		(net 26)
	)
	(segment
		(start 201.220481 139.125)
		(end 203.791157 139.125)
		(width 0.09)
		(layer "In7.Cu")
		(net 26)
	)
	(segment
		(start 198.9 139.18)
		(end 199.259 139.18)
		(width 0.09)
		(layer "In7.Cu")
		(net 26)
	)
	(via
		(at 203.315 118.135)
		(size 0.35)
		(drill 0.15)
		(layers "F.Cu" "B.Cu")
		(remove_unused_layers yes)
		(keep_end_layers yes)
		(zone_layer_connections)
		(net 27)
	)
	(via
		(at 203.699 128.3)
		(size 0.35)
		(drill 0.15)
		(layers "F.Cu" "B.Cu")
		(remove_unused_layers yes)
		(keep_end_layers yes)
		(zone_layer_connections)
		(net 27)
	)
	(segment
		(start 203.315 118.135)
		(end 203.639 118.135)
		(width 0.15)
		(layer "B.Cu")
		(net 27)
	)
	(segment
		(start 203.639 118.135)
		(end 204.12 118.616)
		(width 0.15)
		(layer "B.Cu")
		(net 27)
	)
	(segment
		(start 204.12 118.616)
		(end 204.12 120.171)
		(width 0.15)
		(layer "B.Cu")
		(net 27)
	)
	(segment
		(start 204.1 122.9)
		(end 203.525 122.325)
		(width 0.09)
		(layer "In7.Cu")
		(net 27)
	)
	(segment
		(start 204.1 127.899)
		(end 204.1 122.9)
		(width 0.09)
		(layer "In7.Cu")
		(net 27)
	)
	(segment
		(start 203.642 119.437832)
		(end 203.642 118.462)
		(width 0.09)
		(layer "In7.Cu")
		(net 27)
	)
	(segment
		(start 203.642 118.462)
		(end 203.315 118.135)
		(width 0.09)
		(layer "In7.Cu")
		(net 27)
	)
	(segment
		(start 203.525 119.554832)
		(end 203.642 119.437832)
		(width 0.09)
		(layer "In7.Cu")
		(net 27)
	)
	(segment
		(start 203.525 122.325)
		(end 203.525 119.554832)
		(width 0.09)
		(layer "In7.Cu")
		(net 27)
	)
	(segment
		(start 203.699 128.3)
		(end 204.1 127.899)
		(width 0.09)
		(layer "In7.Cu")
		(net 27)
	)
	(segment
		(start 200.190294 118.176507)
		(end 200.190294 118.010294)
		(width 0.1)
		(layer "F.Cu")
		(net 28)
	)
	(segment
		(start 199.867335 117.687335)
		(end 199.242486 117.687335)
		(width 0.1)
		(layer "F.Cu")
		(net 28)
	)
	(segment
		(start 200.190294 118.010294)
		(end 199.867335 117.687335)
		(width 0.1)
		(layer "F.Cu")
		(net 28)
	)
	(via
		(at 200.504999 137.197501)
		(size 0.35)
		(drill 0.15)
		(layers "F.Cu" "B.Cu")
		(remove_unused_layers yes)
		(keep_end_layers yes)
		(zone_layer_connections)
		(net 28)
	)
	(via
		(at 200.190294 118.176507)
		(size 0.35)
		(drill 0.15)
		(layers "F.Cu" "B.Cu")
		(remove_unused_layers yes)
		(keep_end_layers yes)
		(zone_layer_connections)
		(net 28)
	)
	(segment
		(start 199.725 120.642158)
		(end 200.375 119.992158)
		(width 0.09)
		(layer "In7.Cu")
		(net 28)
	)
	(segment
		(start 200.504999 137.197501)
		(end 199.77 136.462502)
		(width 0.09)
		(layer "In7.Cu")
		(net 28)
	)
	(segment
		(start 200.315294 118.5)
		(end 200.190294 118.375)
		(width 0.09)
		(layer "In7.Cu")
		(net 28)
	)
	(segment
		(start 198.5 123.25)
		(end 199.725 122.025)
		(width 0.09)
		(layer "In7.Cu")
		(net 28)
	)
	(segment
		(start 198.78 133.98)
		(end 198.527451 133.98)
		(width 0.09)
		(layer "In7.Cu")
		(net 28)
	)
	(segment
		(start 200.375 119.992158)
		(end 200.375 119.217855)
		(width 0.09)
		(layer "In7.Cu")
		(net 28)
	)
	(segment
		(start 200.375 119.217855)
		(end 200.315294 119.158149)
		(width 0.09)
		(layer "In7.Cu")
		(net 28)
	)
	(segment
		(start 198.82 128.032549)
		(end 198.5 127.712549)
		(width 0.09)
		(layer "In7.Cu")
		(net 28)
	)
	(segment
		(start 200.190294 118.375)
		(end 200.190294 118.176507)
		(width 0.09)
		(layer "In7.Cu")
		(net 28)
	)
	(segment
		(start 200.315294 119.158149)
		(end 200.315294 118.5)
		(width 0.09)
		(layer "In7.Cu")
		(net 28)
	)
	(segment
		(start 198.175 132.5125)
		(end 198.82 131.8675)
		(width 0.09)
		(layer "In7.Cu")
		(net 28)
	)
	(segment
		(start 198.527451 133.98)
		(end 198.175 133.627549)
		(width 0.09)
		(layer "In7.Cu")
		(net 28)
	)
	(segment
		(start 199.77 136.462502)
		(end 199.77 134.97)
		(width 0.09)
		(layer "In7.Cu")
		(net 28)
	)
	(segment
		(start 199.77 134.97)
		(end 198.78 133.98)
		(width 0.09)
		(layer "In7.Cu")
		(net 28)
	)
	(segment
		(start 198.175 133.627549)
		(end 198.175 132.5125)
		(width 0.09)
		(layer "In7.Cu")
		(net 28)
	)
	(segment
		(start 198.82 131.8675)
		(end 198.82 128.032549)
		(width 0.09)
		(layer "In7.Cu")
		(net 28)
	)
	(segment
		(start 199.725 122.025)
		(end 199.725 120.642158)
		(width 0.09)
		(layer "In7.Cu")
		(net 28)
	)
	(segment
		(start 198.5 127.712549)
		(end 198.5 123.25)
		(width 0.09)
		(layer "In7.Cu")
		(net 28)
	)
	(via
		(at 203.375 116.85)
		(size 0.35)
		(drill 0.15)
		(layers "F.Cu" "B.Cu")
		(remove_unused_layers yes)
		(keep_end_layers yes)
		(zone_layer_connections)
		(net 29)
	)
	(via
		(at 203.699 138.7)
		(size 0.35)
		(drill 0.15)
		(layers "F.Cu" "B.Cu")
		(remove_unused_layers yes)
		(keep_end_layers yes)
		(zone_layer_connections)
		(net 29)
	)
	(segment
		(start 203.322 117.461)
		(end 203.322 116.903)
		(width 0.15)
		(layer "B.Cu")
		(net 29)
	)
	(segment
		(start 203.322 116.903)
		(end 203.375 116.85)
		(width 0.15)
		(layer "B.Cu")
		(net 29)
	)
	(segment
		(start 203.699 138.353549)
		(end 203.699 138.7)
		(width 0.09)
		(layer "In7.Cu")
		(net 29)
	)
	(segment
		(start 204.075 117.456549)
		(end 204.075 119.825)
		(width 0.09)
		(layer "In7.Cu")
		(net 29)
	)
	(segment
		(start 203.379 138.033549)
		(end 203.699 138.353549)
		(width 0.09)
		(layer "In7.Cu")
		(net 29)
	)
	(segment
		(start 204 121.65)
		(end 205.2 122.85)
		(width 0.09)
		(layer "In7.Cu")
		(net 29)
	)
	(segment
		(start 206.225 135.85)
		(end 204.35 135.85)
		(width 0.09)
		(layer "In7.Cu")
		(net 29)
	)
	(segment
		(start 203.375 116.85)
		(end 203.707549 117.182549)
		(width 0.09)
		(layer "In7.Cu")
		(net 29)
	)
	(segment
		(start 204.075 119.825)
		(end 204 119.9)
		(width 0.09)
		(layer "In7.Cu")
		(net 29)
	)
	(segment
		(start 203.379 137.746)
		(end 203.379 138.033549)
		(width 0.09)
		(layer "In7.Cu")
		(net 29)
	)
	(segment
		(start 203.801 117.182549)
		(end 204.075 117.456549)
		(width 0.09)
		(layer "In7.Cu")
		(net 29)
	)
	(segment
		(start 204.05 136.15)
		(end 204.05 137.25)
		(width 0.09)
		(layer "In7.Cu")
		(net 29)
	)
	(segment
		(start 204 119.9)
		(end 204 121.65)
		(width 0.09)
		(layer "In7.Cu")
		(net 29)
	)
	(segment
		(start 206.7 135.375)
		(end 206.225 135.85)
		(width 0.09)
		(layer "In7.Cu")
		(net 29)
	)
	(segment
		(start 206 122.85)
		(end 206.7 123.55)
		(width 0.09)
		(layer "In7.Cu")
		(net 29)
	)
	(segment
		(start 204.05 137.25)
		(end 203.874 137.426)
		(width 0.09)
		(layer "In7.Cu")
		(net 29)
	)
	(segment
		(start 203.699 137.426)
		(end 203.379 137.746)
		(width 0.09)
		(layer "In7.Cu")
		(net 29)
	)
	(segment
		(start 204.35 135.85)
		(end 204.05 136.15)
		(width 0.09)
		(layer "In7.Cu")
		(net 29)
	)
	(segment
		(start 203.874 137.426)
		(end 203.699 137.426)
		(width 0.09)
		(layer "In7.Cu")
		(net 29)
	)
	(segment
		(start 205.2 122.85)
		(end 206 122.85)
		(width 0.09)
		(layer "In7.Cu")
		(net 29)
	)
	(segment
		(start 206.7 123.55)
		(end 206.7 135.375)
		(width 0.09)
		(layer "In7.Cu")
		(net 29)
	)
	(segment
		(start 203.707549 117.182549)
		(end 203.801 117.182549)
		(width 0.09)
		(layer "In7.Cu")
		(net 29)
	)
	(via
		(at 208.3 121.22)
		(size 0.35)
		(drill 0.15)
		(layers "F.Cu" "B.Cu")
		(remove_unused_layers yes)
		(keep_end_layers yes)
		(zone_layer_connections)
		(net 30)
	)
	(via
		(at 202.112 118.135)
		(size 0.35)
		(drill 0.15)
		(layers "F.Cu" "B.Cu")
		(remove_unused_layers yes)
		(keep_end_layers yes)
		(zone_layer_connections)
		(net 30)
	)
	(via
		(at 206.1 136.38)
		(size 0.35)
		(drill 0.15)
		(layers "F.Cu" "B.Cu")
		(remove_unused_layers yes)
		(keep_end_layers yes)
		(zone_layer_connections)
		(net 30)
	)
	(segment
		(start 202.917 118.616)
		(end 202.917 120.171)
		(width 0.15)
		(layer "B.Cu")
		(net 30)
	)
	(segment
		(start 202.436 118.135)
		(end 202.917 118.616)
		(width 0.15)
		(layer "B.Cu")
		(net 30)
	)
	(segment
		(start 202.112 118.135)
		(end 202.436 118.135)
		(width 0.15)
		(layer "B.Cu")
		(net 30)
	)
	(segment
		(start 202.464 117.785)
		(end 205.470975 117.785)
		(width 0.09)
		(layer "In4.Cu")
		(net 30)
	)
	(segment
		(start 206.601926 119.820906)
		(end 206.85102 120.07)
		(width 0.09)
		(layer "In4.Cu")
		(net 30)
	)
	(segment
		(start 205.470975 117.785)
		(end 206.601926 118.915951)
		(width 0.09)
		(layer "In4.Cu")
		(net 30)
	)
	(segment
		(start 206.85102 120.07)
		(end 207.15 120.07)
		(width 0.09)
		(layer "In4.Cu")
		(net 30)
	)
	(segment
		(start 206.601926 118.915951)
		(end 206.601926 119.820906)
		(width 0.09)
		(layer "In4.Cu")
		(net 30)
	)
	(segment
		(start 202.114 118.135)
		(end 202.464 117.785)
		(width 0.09)
		(layer "In4.Cu")
		(net 30)
	)
	(segment
		(start 207.15 120.07)
		(end 208.3 121.22)
		(width 0.09)
		(layer "In4.Cu")
		(net 30)
	)
	(segment
		(start 206.1 136.38)
		(end 206.395 136.38)
		(width 0.09)
		(layer "In7.Cu")
		(net 30)
	)
	(segment
		(start 207.95 121.57)
		(end 208.3 121.22)
		(width 0.09)
		(layer "In7.Cu")
		(net 30)
	)
	(segment
		(start 207.95 134.825)
		(end 207.95 121.57)
		(width 0.09)
		(layer "In7.Cu")
		(net 30)
	)
	(segment
		(start 206.395 136.38)
		(end 207.95 134.825)
		(width 0.09)
		(layer "In7.Cu")
		(net 30)
	)
	(via
		(at 201.722 117.05)
		(size 0.35)
		(drill 0.15)
		(layers "F.Cu" "B.Cu")
		(remove_unused_layers yes)
		(keep_end_layers yes)
		(zone_layer_connections)
		(net 31)
	)
	(via
		(at 200.499 133.101)
		(size 0.35)
		(drill 0.15)
		(layers "F.Cu" "B.Cu")
		(remove_unused_layers yes)
		(keep_end_layers yes)
		(zone_layer_connections)
		(net 31)
	)
	(segment
		(start 200.499 133.101)
		(end 200.9 132.7)
		(width 0.09)
		(layer "In7.Cu")
		(net 31)
	)
	(segment
		(start 201.725 117.45)
		(end 201.725 117.053)
		(width 0.09)
		(layer "In7.Cu")
		(net 31)
	)
	(segment
		(start 200.975 118.580674)
		(end 200.975 118)
		(width 0.09)
		(layer "In7.Cu")
		(net 31)
	)
	(segment
		(start 201.375 117.6)
		(end 201.575 117.6)
		(width 0.09)
		(layer "In7.Cu")
		(net 31)
	)
	(segment
		(start 200.9 122.7)
		(end 200.325 122.125)
		(width 0.09)
		(layer "In7.Cu")
		(net 31)
	)
	(segment
		(start 200.975 118)
		(end 201.375 117.6)
		(width 0.09)
		(layer "In7.Cu")
		(net 31)
	)
	(segment
		(start 200.975 120.340222)
		(end 200.975 118.969326)
		(width 0.09)
		(layer "In7.Cu")
		(net 31)
	)
	(segment
		(start 201.725 117.053)
		(end 201.722 117.05)
		(width 0.09)
		(layer "In7.Cu")
		(net 31)
	)
	(segment
		(start 200.325 122.125)
		(end 200.325 120.990222)
		(width 0.09)
		(layer "In7.Cu")
		(net 31)
	)
	(segment
		(start 201.575 117.6)
		(end 201.725 117.45)
		(width 0.09)
		(layer "In7.Cu")
		(net 31)
	)
	(segment
		(start 200.915294 118.90962)
		(end 200.915294 118.64038)
		(width 0.09)
		(layer "In7.Cu")
		(net 31)
	)
	(segment
		(start 200.915294 118.64038)
		(end 200.975 118.580674)
		(width 0.09)
		(layer "In7.Cu")
		(net 31)
	)
	(segment
		(start 200.325 120.990222)
		(end 200.975 120.340222)
		(width 0.09)
		(layer "In7.Cu")
		(net 31)
	)
	(segment
		(start 200.975 118.969326)
		(end 200.915294 118.90962)
		(width 0.09)
		(layer "In7.Cu")
		(net 31)
	)
	(segment
		(start 200.9 132.7)
		(end 200.9 122.7)
		(width 0.09)
		(layer "In7.Cu")
		(net 31)
	)
	(via
		(at 201.3 133.101)
		(size 0.35)
		(drill 0.15)
		(layers "F.Cu" "B.Cu")
		(remove_unused_layers yes)
		(keep_end_layers yes)
		(zone_layer_connections)
		(net 32)
	)
	(via
		(at 202.026481 118.580897)
		(size 0.35)
		(drill 0.15)
		(layers "F.Cu" "B.Cu")
		(remove_unused_layers yes)
		(keep_end_layers yes)
		(zone_layer_connections)
		(net 32)
	)
	(segment
		(start 201.733534 118.873844)
		(end 201.733534 120.156466)
		(width 0.15)
		(layer "B.Cu")
		(net 32)
	)
	(segment
		(start 202.026481 118.580897)
		(end 201.733534 118.873844)
		(width 0.15)
		(layer "B.Cu")
		(net 32)
	)
	(segment
		(start 202.028481 119.206899)
		(end 201.97 119.26538)
		(width 0.09)
		(layer "In7.Cu")
		(net 32)
	)
	(segment
		(start 202.5 124.05)
		(end 202.5 132.5)
		(width 0.09)
		(layer "In7.Cu")
		(net 32)
	)
	(segment
		(start 202.5 132.5)
		(end 202.3 132.7)
		(width 0.09)
		(layer "In7.Cu")
		(net 32)
	)
	(segment
		(start 202 132.7)
		(end 201.599 133.101)
		(width 0.09)
		(layer "In7.Cu")
		(net 32)
	)
	(segment
		(start 202.028481 118.580897)
		(end 202.028481 119.206899)
		(width 0.09)
		(layer "In7.Cu")
		(net 32)
	)
	(segment
		(start 201.675 121.225)
		(end 202.025 121.575)
		(width 0.09)
		(layer "In7.Cu")
		(net 32)
	)
	(segment
		(start 202.3 132.7)
		(end 202 132.7)
		(width 0.09)
		(layer "In7.Cu")
		(net 32)
	)
	(segment
		(start 201.599 133.101)
		(end 201.3 133.101)
		(width 0.09)
		(layer "In7.Cu")
		(net 32)
	)
	(segment
		(start 201.675 119.689493)
		(end 201.675 121.225)
		(width 0.09)
		(layer "In7.Cu")
		(net 32)
	)
	(segment
		(start 201.97 119.394493)
		(end 201.675 119.689493)
		(width 0.09)
		(layer "In7.Cu")
		(net 32)
	)
	(segment
		(start 202.025 121.575)
		(end 202.025 123.575)
		(width 0.09)
		(layer "In7.Cu")
		(net 32)
	)
	(segment
		(start 202.025 123.575)
		(end 202.5 124.05)
		(width 0.09)
		(layer "In7.Cu")
		(net 32)
	)
	(segment
		(start 201.97 119.26538)
		(end 201.97 119.394493)
		(width 0.09)
		(layer "In7.Cu")
		(net 32)
	)
	(via
		(at 199.46 143.08)
		(size 0.35)
		(drill 0.15)
		(layers "F.Cu" "B.Cu")
		(remove_unused_layers yes)
		(keep_end_layers yes)
		(zone_layer_connections)
		(net 33)
	)
	(via
		(at 204.872 154.9)
		(size 0.35)
		(drill 0.15)
		(layers "F.Cu" "B.Cu")
		(remove_unused_layers yes)
		(keep_end_layers yes)
		(zone_layer_connections)
		(net 33)
	)
	(segment
		(start 205.0145 154.7575)
		(end 204.872 154.9)
		(width 0.125)
		(layer "B.Cu")
		(net 33)
	)
	(segment
		(start 205.0145 154.4785)
		(end 205.0145 154.7575)
		(width 0.125)
		(layer "B.Cu")
		(net 33)
	)
	(segment
		(start 204.922 154.171)
		(end 204.922 154.386)
		(width 0.125)
		(layer "B.Cu")
		(net 33)
	)
	(segment
		(start 204.922 154.386)
		(end 205.0145 154.4785)
		(width 0.125)
		(layer "B.Cu")
		(net 33)
	)
	(segment
		(start 205.022 154.75)
		(end 205.022 154.65808)
		(width 0.1)
		(layer "In2.Cu")
		(net 33)
	)
	(segment
		(start 199.305 143.235)
		(end 199.46 143.08)
		(width 0.1)
		(layer "In2.Cu")
		(net 33)
	)
	(segment
		(start 199.140321 143.235)
		(end 199.305 143.235)
		(width 0.1)
		(layer "In2.Cu")
		(net 33)
	)
	(segment
		(start 199.29 152.911422)
		(end 199.29 148.871422)
		(width 0.1)
		(layer "In2.Cu")
		(net 33)
	)
	(segment
		(start 200.798578 154.42)
		(end 199.29 152.911422)
		(width 0.1)
		(layer "In2.Cu")
		(net 33)
	)
	(segment
		(start 199.29 148.871422)
		(end 198.94 148.521422)
		(width 0.1)
		(layer "In2.Cu")
		(net 33)
	)
	(segment
		(start 198.94 143.435321)
		(end 199.140321 143.235)
		(width 0.1)
		(layer "In2.Cu")
		(net 33)
	)
	(segment
		(start 198.94 148.521422)
		(end 198.94 143.435321)
		(width 0.1)
		(layer "In2.Cu")
		(net 33)
	)
	(segment
		(start 204.78392 154.42)
		(end 200.798578 154.42)
		(width 0.1)
		(layer "In2.Cu")
		(net 33)
	)
	(segment
		(start 205.022 154.65808)
		(end 204.78392 154.42)
		(width 0.1)
		(layer "In2.Cu")
		(net 33)
	)
	(segment
		(start 204.872 154.9)
		(end 205.022 154.75)
		(width 0.1)
		(layer "In2.Cu")
		(net 33)
	)
	(segment
		(start 200.919 118.241)
		(end 200.919 117.05)
		(width 0.1)
		(layer "F.Cu")
		(net 34)
	)
	(segment
		(start 199.85 120.05)
		(end 199.85 120.47)
		(width 0.1)
		(layer "F.Cu")
		(net 34)
	)
	(segment
		(start 200.55 119.35)
		(end 200.55 118.61)
		(width 0.1)
		(layer "F.Cu")
		(net 34)
	)
	(segment
		(start 199.85 120.05)
		(end 200.55 119.35)
		(width 0.1)
		(layer "F.Cu")
		(net 34)
	)
	(segment
		(start 200.55 118.61)
		(end 200.919 118.241)
		(width 0.1)
		(layer "F.Cu")
		(net 34)
	)
	(via
		(at 200.919 117.05)
		(size 0.35)
		(drill 0.15)
		(layers "F.Cu" "B.Cu")
		(remove_unused_layers yes)
		(keep_end_layers yes)
		(zone_layer_connections)
		(net 34)
	)
	(via
		(at 199.46 142.59)
		(size 0.35)
		(drill 0.15)
		(layers "F.Cu" "B.Cu")
		(remove_unused_layers yes)
		(keep_end_layers yes)
		(zone_layer_connections)
		(net 35)
	)
	(via
		(at 200.572 154.9)
		(size 0.35)
		(drill 0.15)
		(layers "F.Cu" "B.Cu")
		(remove_unused_layers yes)
		(keep_end_layers yes)
		(zone_layer_connections)
		(net 35)
	)
	(segment
		(start 200.522 154.386)
		(end 200.4295 154.4785)
		(width 0.125)
		(layer "B.Cu")
		(net 35)
	)
	(segment
		(start 200.4295 154.7575)
		(end 200.572 154.9)
		(width 0.125)
		(layer "B.Cu")
		(net 35)
	)
	(segment
		(start 200.4295 154.4785)
		(end 200.4295 154.7575)
		(width 0.125)
		(layer "B.Cu")
		(net 35)
	)
	(segment
		(start 200.522 154.171)
		(end 200.522 154.386)
		(width 0.125)
		(layer "B.Cu")
		(net 35)
	)
	(segment
		(start 198.63 142.831422)
		(end 198.667868 142.793557)
		(width 0.1)
		(layer "In2.Cu")
		(net 35)
	)
	(segment
		(start 198.63 148.938578)
		(end 198.16 148.468578)
		(width 0.1)
		(layer "In2.Cu")
		(net 35)
	)
	(segment
		(start 200.572 154.9)
		(end 200.422 154.75)
		(width 0.1)
		(layer "In2.Cu")
		(net 35)
	)
	(segment
		(start 199.021421 142.616778)
		(end 199.021422 142.616778)
		(width 0.1)
		(layer "In2.Cu")
		(net 35)
	)
	(segment
		(start 198.63 152.768578)
		(end 198.63 148.938578)
		(width 0.1)
		(layer "In2.Cu")
		(net 35)
	)
	(segment
		(start 199.31 142.44)
		(end 199.46 142.59)
		(width 0.1)
		(layer "In2.Cu")
		(net 35)
	)
	(segment
		(start 200.422 154.560578)
		(end 198.63 152.768578)
		(width 0.1)
		(layer "In2.Cu")
		(net 35)
	)
	(segment
		(start 199.041706 142.637063)
		(end 199.021421 142.616778)
		(width 0.1)
		(layer "In2.Cu")
		(net 35)
	)
	(segment
		(start 198.844645 142.793556)
		(end 198.86493 142.81384)
		(width 0.1)
		(layer "In2.Cu")
		(net 35)
	)
	(segment
		(start 199.021422 142.44)
		(end 199.31 142.44)
		(width 0.1)
		(layer "In2.Cu")
		(net 35)
	)
	(segment
		(start 199.041705 142.81384)
		(end 199.041707 142.813839)
		(width 0.1)
		(layer "In2.Cu")
		(net 35)
	)
	(segment
		(start 198.63 145.641422)
		(end 198.63 142.831422)
		(width 0.1)
		(layer "In2.Cu")
		(net 35)
	)
	(segment
		(start 200.422 154.75)
		(end 200.422 154.560578)
		(width 0.1)
		(layer "In2.Cu")
		(net 35)
	)
	(segment
		(start 198.16 148.468578)
		(end 198.16 146.111422)
		(width 0.1)
		(layer "In2.Cu")
		(net 35)
	)
	(segment
		(start 198.16 146.111422)
		(end 198.63 145.641422)
		(width 0.1)
		(layer "In2.Cu")
		(net 35)
	)
	(arc
		(start 199.041705 142.81384)
		(mid 199.078317 142.725452)
		(end 199.041706 142.637063)
		(width 0.1)
		(layer "In2.Cu")
		(net 35)
	)
	(arc
		(start 198.86493 142.81384)
		(mid 198.953319 142.850451)
		(end 199.041707 142.813839)
		(width 0.1)
		(layer "In2.Cu")
		(net 35)
	)
	(arc
		(start 199.021422 142.616778)
		(mid 198.984809 142.52839)
		(end 199.021422 142.44)
		(width 0.1)
		(layer "In2.Cu")
		(net 35)
	)
	(arc
		(start 198.667868 142.793557)
		(mid 198.756256 142.756945)
		(end 198.844645 142.793556)
		(width 0.1)
		(layer "In2.Cu")
		(net 35)
	)
	(via
		(at 200.072 154.9)
		(size 0.35)
		(drill 0.15)
		(layers "F.Cu" "B.Cu")
		(remove_unused_layers yes)
		(keep_end_layers yes)
		(zone_layer_connections)
		(net 36)
	)
	(via
		(at 199.45 142.1)
		(size 0.35)
		(drill 0.15)
		(layers "F.Cu" "B.Cu")
		(remove_unused_layers yes)
		(keep_end_layers yes)
		(zone_layer_connections)
		(net 36)
	)
	(segment
		(start 200.122 154.386)
		(end 200.2145 154.4785)
		(width 0.125)
		(layer "B.Cu")
		(net 36)
	)
	(segment
		(start 200.2145 154.7575)
		(end 200.072 154.9)
		(width 0.125)
		(layer "B.Cu")
		(net 36)
	)
	(segment
		(start 200.2145 154.4785)
		(end 200.2145 154.7575)
		(width 0.125)
		(layer "B.Cu")
		(net 36)
	)
	(segment
		(start 200.122 154.171)
		(end 200.122 154.386)
		(width 0.125)
		(layer "B.Cu")
		(net 36)
	)
	(segment
		(start 200.072 154.9)
		(end 200.222 154.75)
		(width 0.1)
		(layer "In2.Cu")
		(net 36)
	)
	(segment
		(start 198.43 149.021422)
		(end 197.96 148.551422)
		(width 0.1)
		(layer "In2.Cu")
		(net 36)
	)
	(segment
		(start 199.31 142.24)
		(end 199.45 142.1)
		(width 0.1)
		(layer "In2.Cu")
		(net 36)
	)
	(segment
		(start 198.938578 142.24)
		(end 199.31 142.24)
		(width 0.1)
		(layer "In2.Cu")
		(net 36)
	)
	(segment
		(start 197.96 146.028578)
		(end 198.43 145.558578)
		(width 0.1)
		(layer "In2.Cu")
		(net 36)
	)
	(segment
		(start 197.96 148.551422)
		(end 197.96 146.028578)
		(width 0.1)
		(layer "In2.Cu")
		(net 36)
	)
	(segment
		(start 198.43 145.558578)
		(end 198.43 142.748578)
		(width 0.1)
		(layer "In2.Cu")
		(net 36)
	)
	(segment
		(start 198.43 142.748578)
		(end 198.938578 142.24)
		(width 0.1)
		(layer "In2.Cu")
		(net 36)
	)
	(segment
		(start 200.222 154.643422)
		(end 198.43 152.851422)
		(width 0.1)
		(layer "In2.Cu")
		(net 36)
	)
	(segment
		(start 200.222 154.75)
		(end 200.222 154.643422)
		(width 0.1)
		(layer "In2.Cu")
		(net 36)
	)
	(segment
		(start 198.43 152.851422)
		(end 198.43 149.021422)
		(width 0.1)
		(layer "In2.Cu")
		(net 36)
	)
	(via
		(at 198.172 154.9)
		(size 0.35)
		(drill 0.15)
		(layers "F.Cu" "B.Cu")
		(remove_unused_layers yes)
		(keep_end_layers yes)
		(zone_layer_connections)
		(net 37)
	)
	(via
		(at 197.61 142.11)
		(size 0.35)
		(drill 0.15)
		(layers "F.Cu" "B.Cu")
		(remove_unused_layers yes)
		(keep_end_layers yes)
		(zone_layer_connections)
		(net 37)
	)
	(segment
		(start 198.122 154.171)
		(end 198.122 154.386)
		(width 0.125)
		(layer "B.Cu")
		(net 37)
	)
	(segment
		(start 198.0295 154.7575)
		(end 198.172 154.9)
		(width 0.125)
		(layer "B.Cu")
		(net 37)
	)
	(segment
		(start 197.13 142.1)
		(end 197.2725 142.2425)
		(width 0.125)
		(layer "B.Cu")
		(net 37)
	)
	(segment
		(start 198.0295 154.4785)
		(end 198.0295 154.7575)
		(width 0.125)
		(layer "B.Cu")
		(net 37)
	)
	(segment
		(start 197 142.1)
		(end 197.13 142.1)
		(width 0.125)
		(layer "B.Cu")
		(net 37)
	)
	(segment
		(start 198.122 154.386)
		(end 198.0295 154.4785)
		(width 0.125)
		(layer "B.Cu")
		(net 37)
	)
	(segment
		(start 197.4775 142.2425)
		(end 197.61 142.11)
		(width 0.125)
		(layer "B.Cu")
		(net 37)
	)
	(segment
		(start 197.2725 142.2425)
		(end 197.4775 142.2425)
		(width 0.125)
		(layer "B.Cu")
		(net 37)
	)
	(segment
		(start 197.96 142.26)
		(end 197.76 142.26)
		(width 0.1)
		(layer "In2.Cu")
		(net 37)
	)
	(segment
		(start 198.172 154.9)
		(end 198.022 154.75)
		(width 0.1)
		(layer "In2.Cu")
		(net 37)
	)
	(segment
		(start 198.022 152.080578)
		(end 197.625 151.683578)
		(width 0.1)
		(layer "In2.Cu")
		(net 37)
	)
	(segment
		(start 197.391422 145.7)
		(end 198.15 144.941422)
		(width 0.1)
		(layer "In2.Cu")
		(net 37)
	)
	(segment
		(start 198.022 154.75)
		(end 198.022 152.080578)
		(width 0.1)
		(layer "In2.Cu")
		(net 37)
	)
	(segment
		(start 198.15 142.45)
		(end 197.96 142.26)
		(width 0.1)
		(layer "In2.Cu")
		(net 37)
	)
	(segment
		(start 196.27 147.978578)
		(end 196.27 146.171422)
		(width 0.1)
		(layer "In2.Cu")
		(net 37)
	)
	(segment
		(start 197.76 142.26)
		(end 197.61 142.11)
		(width 0.1)
		(layer "In2.Cu")
		(net 37)
	)
	(segment
		(start 198.15 144.941422)
		(end 198.15 142.45)
		(width 0.1)
		(layer "In2.Cu")
		(net 37)
	)
	(segment
		(start 196.27 146.171422)
		(end 196.741422 145.7)
		(width 0.1)
		(layer "In2.Cu")
		(net 37)
	)
	(segment
		(start 197.625 151.683578)
		(end 197.625 149.333578)
		(width 0.1)
		(layer "In2.Cu")
		(net 37)
	)
	(segment
		(start 196.741422 145.7)
		(end 197.391422 145.7)
		(width 0.1)
		(layer "In2.Cu")
		(net 37)
	)
	(segment
		(start 197.625 149.333578)
		(end 196.27 147.978578)
		(width 0.1)
		(layer "In2.Cu")
		(net 37)
	)
	(via
		(at 197.672 154.9)
		(size 0.35)
		(drill 0.15)
		(layers "F.Cu" "B.Cu")
		(remove_unused_layers yes)
		(keep_end_layers yes)
		(zone_layer_connections)
		(net 38)
	)
	(via
		(at 197.6 142.62)
		(size 0.35)
		(drill 0.15)
		(layers "F.Cu" "B.Cu")
		(remove_unused_layers yes)
		(keep_end_layers yes)
		(zone_layer_connections)
		(net 38)
	)
	(segment
		(start 197.722 154.386)
		(end 197.8145 154.4785)
		(width 0.125)
		(layer "B.Cu")
		(net 38)
	)
	(segment
		(start 197.722 154.171)
		(end 197.722 154.386)
		(width 0.125)
		(layer "B.Cu")
		(net 38)
	)
	(segment
		(start 197.8145 154.4785)
		(end 197.8145 154.7575)
		(width 0.125)
		(layer "B.Cu")
		(net 38)
	)
	(segment
		(start 197.4375 142.4575)
		(end 197.6 142.62)
		(width 0.125)
		(layer "B.Cu")
		(net 38)
	)
	(segment
		(start 197 142.6)
		(end 197.13 142.6)
		(width 0.125)
		(layer "B.Cu")
		(net 38)
	)
	(segment
		(start 197.8145 154.7575)
		(end 197.672 154.9)
		(width 0.125)
		(layer "B.Cu")
		(net 38)
	)
	(segment
		(start 197.13 142.6)
		(end 197.2725 142.4575)
		(width 0.125)
		(layer "B.Cu")
		(net 38)
	)
	(segment
		(start 197.2725 142.4575)
		(end 197.4375 142.4575)
		(width 0.125)
		(layer "B.Cu")
		(net 38)
	)
	(segment
		(start 196.07 146.088578)
		(end 196.658578 145.5)
		(width 0.1)
		(layer "In2.Cu")
		(net 38)
	)
	(segment
		(start 197.425 149.416422)
		(end 196.07 148.061422)
		(width 0.1)
		(layer "In2.Cu")
		(net 38)
	)
	(segment
		(start 197.425 151.766422)
		(end 197.425 149.416422)
		(width 0.1)
		(layer "In2.Cu")
		(net 38)
	)
	(segment
		(start 197.807725 143.367725)
		(end 197.807724 143.367725)
		(width 0.1)
		(layer "In2.Cu")
		(net 38)
	)
	(segment
		(start 196.07 148.061422)
		(end 196.07 146.088578)
		(width 0.1)
		(layer "In2.Cu")
		(net 38)
	)
	(segment
		(start 197.95 142.92545)
		(end 197.95 142.55)
		(width 0.1)
		(layer "In2.Cu")
		(net 38)
	)
	(segment
		(start 197.86 142.46)
		(end 197.76 142.46)
		(width 0.1)
		(layer "In2.Cu")
		(net 38)
	)
	(segment
		(start 197.308578 145.5)
		(end 197.95 144.858578)
		(width 0.1)
		(layer "In2.Cu")
		(net 38)
	)
	(segment
		(start 196.658578 145.5)
		(end 197.308578 145.5)
		(width 0.1)
		(layer "In2.Cu")
		(net 38)
	)
	(segment
		(start 197.672 154.9)
		(end 197.822 154.75)
		(width 0.1)
		(layer "In2.Cu")
		(net 38)
	)
	(segment
		(start 197.95 142.55)
		(end 197.86 142.46)
		(width 0.1)
		(layer "In2.Cu")
		(net 38)
	)
	(segment
		(start 197.807724 143.067725)
		(end 197.807725 143.067725)
		(width 0.1)
		(layer "In2.Cu")
		(net 38)
	)
	(segment
		(start 197.95 144.858578)
		(end 197.95 143.51)
		(width 0.1)
		(layer "In2.Cu")
		(net 38)
	)
	(segment
		(start 197.76 142.46)
		(end 197.6 142.62)
		(width 0.1)
		(layer "In2.Cu")
		(net 38)
	)
	(segment
		(start 197.822 154.75)
		(end 197.822 152.163422)
		(width 0.1)
		(layer "In2.Cu")
		(net 38)
	)
	(segment
		(start 197.822 152.163422)
		(end 197.425 151.766422)
		(width 0.1)
		(layer "In2.Cu")
		(net 38)
	)
	(segment
		(start 197.665449 143.22545)
		(end 197.665449 143.21)
		(width 0.1)
		(layer "In2.Cu")
		(net 38)
	)
	(arc
		(start 197.95 143.51)
		(mid 197.908329 143.409396)
		(end 197.807725 143.367725)
		(width 0.1)
		(layer "In2.Cu")
		(net 38)
	)
	(arc
		(start 197.807724 143.367725)
		(mid 197.70712 143.326054)
		(end 197.665449 143.22545)
		(width 0.1)
		(layer "In2.Cu")
		(net 38)
	)
	(arc
		(start 197.665449 143.21)
		(mid 197.70712 143.109396)
		(end 197.807724 143.067725)
		(width 0.1)
		(layer "In2.Cu")
		(net 38)
	)
	(arc
		(start 197.807725 143.067725)
		(mid 197.908329 143.026054)
		(end 197.95 142.92545)
		(width 0.1)
		(layer "In2.Cu")
		(net 38)
	)
	(via
		(at 196.748677 143.147401)
		(size 0.35)
		(drill 0.15)
		(layers "F.Cu" "B.Cu")
		(remove_unused_layers yes)
		(keep_end_layers yes)
		(zone_layer_connections)
		(net 39)
	)
	(via
		(at 196.1245 152.801)
		(size 0.35)
		(drill 0.15)
		(layers "F.Cu" "B.Cu")
		(remove_unused_layers yes)
		(keep_end_layers yes)
		(zone_layer_connections)
		(net 39)
	)
	(segment
		(start 196.1245 152.801)
		(end 196.24425 152.92075)
		(width 0.125)
		(layer "B.Cu")
		(net 39)
	)
	(segment
		(start 196.427222 152.92075)
		(end 196.6145 152.733472)
		(width 0.125)
		(layer "B.Cu")
		(net 39)
	)
	(segment
		(start 196.522 151.676)
		(end 196.522 151.461)
		(width 0.125)
		(layer "B.Cu")
		(net 39)
	)
	(segment
		(start 196.24425 152.92075)
		(end 196.427222 152.92075)
		(width 0.125)
		(layer "B.Cu")
		(net 39)
	)
	(segment
		(start 196.6145 152.733472)
		(end 196.6145 151.7685)
		(width 0.125)
		(layer "B.Cu")
		(net 39)
	)
	(segment
		(start 196.6145 151.7685)
		(end 196.522 151.676)
		(width 0.125)
		(layer "B.Cu")
		(net 39)
	)
	(segment
		(start 197.243673 143.275)
		(end 196.924465 143.275)
		(width 0.1)
		(layer "In2.Cu")
		(net 39)
	)
	(segment
		(start 196.88 150.957844)
		(end 196.518921 151.318921)
		(width 0.1)
		(layer "In2.Cu")
		(net 39)
	)
	(segment
		(start 196.518922 151.696892)
		(end 196.495776 151.720039)
		(width 0.1)
		(layer "In2.Cu")
		(net 39)
	)
	(segment
		(start 195.69 152.738578)
		(end 195.879672 152.92825)
		(width 0.1)
		(layer "In2.Cu")
		(net 39)
	)
	(segment
		(start 196.88 149.618578)
		(end 195.43 148.168578)
		(width 0.1)
		(layer "In2.Cu")
		(net 39)
	)
	(segment
		(start 196.306791 151.720039)
		(end 196.30679 151.720039)
		(width 0.1)
		(layer "In2.Cu")
		(net 39)
	)
	(segment
		(start 196.495776 151.720039)
		(end 196.495776 151.720038)
		(width 0.1)
		(layer "In2.Cu")
		(net 39)
	)
	(segment
		(start 196.911422 145.12)
		(end 197.65 144.381422)
		(width 0.1)
		(layer "In2.Cu")
		(net 39)
	)
	(segment
		(start 195.69 152.147844)
		(end 196.117806 151.720039)
		(width 0.1)
		(layer "In2.Cu")
		(net 39)
	)
	(segment
		(start 197.65 144.381422)
		(end 197.65 143.681327)
		(width 0.1)
		(layer "In2.Cu")
		(net 39)
	)
	(segment
		(start 196.88 150.957844)
		(end 196.88 149.618578)
		(width 0.1)
		(layer "In2.Cu")
		(net 39)
	)
	(segment
		(start 195.881422 145.12)
		(end 196.911422 145.12)
		(width 0.1)
		(layer "In2.Cu")
		(net 39)
	)
	(segment
		(start 195.99725 152.92825)
		(end 196.1245 152.801)
		(width 0.1)
		(layer "In2.Cu")
		(net 39)
	)
	(segment
		(start 195.69 152.147844)
		(end 195.69 152.738578)
		(width 0.1)
		(layer "In2.Cu")
		(net 39)
	)
	(segment
		(start 195.43 145.571422)
		(end 195.881422 145.12)
		(width 0.1)
		(layer "In2.Cu")
		(net 39)
	)
	(segment
		(start 195.43 148.168578)
		(end 195.43 145.571422)
		(width 0.1)
		(layer "In2.Cu")
		(net 39)
	)
	(segment
		(start 197.65 143.681327)
		(end 197.243673 143.275)
		(width 0.1)
		(layer "In2.Cu")
		(net 39)
	)
	(segment
		(start 195.879672 152.92825)
		(end 195.99725 152.92825)
		(width 0.1)
		(layer "In2.Cu")
		(net 39)
	)
	(segment
		(start 196.796866 143.147401)
		(end 196.748677 143.147401)
		(width 0.1)
		(layer "In2.Cu")
		(net 39)
	)
	(segment
		(start 196.924465 143.275)
		(end 196.796866 143.147401)
		(width 0.1)
		(layer "In2.Cu")
		(net 39)
	)
	(arc
		(start 196.518922 151.507906)
		(mid 196.558062 151.602399)
		(end 196.518922 151.696892)
		(width 0.1)
		(layer "In2.Cu")
		(net 39)
	)
	(arc
		(start 196.495776 151.720038)
		(mid 196.401284 151.759179)
		(end 196.306791 151.720039)
		(width 0.1)
		(layer "In2.Cu")
		(net 39)
	)
	(arc
		(start 196.30679 151.720039)
		(mid 196.212298 151.680899)
		(end 196.117806 151.720039)
		(width 0.1)
		(layer "In2.Cu")
		(net 39)
	)
	(arc
		(start 196.518921 151.318921)
		(mid 196.479781 151.413414)
		(end 196.518922 151.507906)
		(width 0.1)
		(layer "In2.Cu")
		(net 39)
	)
	(via
		(at 196.1245 153.2555)
		(size 0.35)
		(drill 0.15)
		(layers "F.Cu" "B.Cu")
		(remove_unused_layers yes)
		(keep_end_layers yes)
		(zone_layer_connections)
		(net 40)
	)
	(via
		(at 196.93 143.6)
		(size 0.35)
		(drill 0.15)
		(layers "F.Cu" "B.Cu")
		(remove_unused_layers yes)
		(keep_end_layers yes)
		(zone_layer_connections)
		(net 40)
	)
	(segment
		(start 196.8295 152.822528)
		(end 196.8295 151.7685)
		(width 0.125)
		(layer "B.Cu")
		(net 40)
	)
	(segment
		(start 196.1245 153.2555)
		(end 196.24425 153.13575)
		(width 0.125)
		(layer "B.Cu")
		(net 40)
	)
	(segment
		(start 196.922 151.676)
		(end 196.922 151.461)
		(width 0.125)
		(layer "B.Cu")
		(net 40)
	)
	(segment
		(start 196.516278 153.13575)
		(end 196.8295 152.822528)
		(width 0.125)
		(layer "B.Cu")
		(net 40)
	)
	(segment
		(start 196.24425 153.13575)
		(end 196.516278 153.13575)
		(width 0.125)
		(layer "B.Cu")
		(net 40)
	)
	(segment
		(start 196.8295 151.7685)
		(end 196.922 151.676)
		(width 0.125)
		(layer "B.Cu")
		(net 40)
	)
	(segment
		(start 196.93 143.518567)
		(end 196.983567 143.465)
		(width 0.1)
		(layer "In2.Cu")
		(net 40)
	)
	(segment
		(start 195.796828 153.12825)
		(end 195.99725 153.12825)
		(width 0.1)
		(layer "In2.Cu")
		(net 40)
	)
	(segment
		(start 195.23 145.488578)
		(end 195.23 148.251422)
		(width 0.1)
		(layer "In2.Cu")
		(net 40)
	)
	(segment
		(start 197.45 143.764171)
		(end 197.45 144.298578)
		(width 0.1)
		(layer "In2.Cu")
		(net 40)
	)
	(segment
		(start 195.49 152.065)
		(end 195.49 152.821422)
		(width 0.1)
		(layer "In2.Cu")
		(net 40)
	)
	(segment
		(start 196.68 150.875)
		(end 195.49 152.065)
		(width 0.1)
		(layer "In2.Cu")
		(net 40)
	)
	(segment
		(start 196.828578 144.92)
		(end 195.798578 144.92)
		(width 0.1)
		(layer "In2.Cu")
		(net 40)
	)
	(segment
		(start 196.983567 143.465)
		(end 197.150829 143.465)
		(width 0.1)
		(layer "In2.Cu")
		(net 40)
	)
	(segment
		(start 196.68 149.701422)
		(end 196.68 150.875)
		(width 0.1)
		(layer "In2.Cu")
		(net 40)
	)
	(segment
		(start 195.798578 144.92)
		(end 195.23 145.488578)
		(width 0.1)
		(layer "In2.Cu")
		(net 40)
	)
	(segment
		(start 195.49 152.821422)
		(end 195.796828 153.12825)
		(width 0.1)
		(layer "In2.Cu")
		(net 40)
	)
	(segment
		(start 197.150829 143.465)
		(end 197.45 143.764171)
		(width 0.1)
		(layer "In2.Cu")
		(net 40)
	)
	(segment
		(start 197.45 144.298578)
		(end 196.828578 144.92)
		(width 0.1)
		(layer "In2.Cu")
		(net 40)
	)
	(segment
		(start 195.23 148.251422)
		(end 196.68 149.701422)
		(width 0.1)
		(layer "In2.Cu")
		(net 40)
	)
	(segment
		(start 196.93 143.6)
		(end 196.93 143.518567)
		(width 0.1)
		(layer "In2.Cu")
		(net 40)
	)
	(segment
		(start 195.99725 153.12825)
		(end 196.1245 153.2555)
		(width 0.1)
		(layer "In2.Cu")
		(net 40)
	)
	(via
		(at 198.1 128.3)
		(size 0.35)
		(drill 0.15)
		(layers "F.Cu" "B.Cu")
		(remove_unused_layers yes)
		(keep_end_layers yes)
		(zone_layer_connections)
		(net 41)
	)
	(via
		(at 210.195802 124.142497)
		(size 0.35)
		(drill 0.15)
		(layers "F.Cu" "B.Cu")
		(remove_unused_layers yes)
		(keep_end_layers yes)
		(zone_layer_connections)
		(net 41)
	)
	(segment
		(start 205.474706 124.92)
		(end 205.180058 125.214648)
		(width 0.09)
		(layer "In9.Cu")
		(net 41)
	)
	(segment
		(start 206.67 124.674706)
		(end 206.424706 124.92)
		(width 0.09)
		(layer "In9.Cu")
		(net 41)
	)
	(segment
		(start 212.23 125.100294)
		(end 212.23 124.324706)
		(width 0.09)
		(layer "In9.Cu")
		(net 41)
	)
	(segment
		(start 210.325802 124.012497)
		(end 210.195802 124.142497)
		(width 0.09)
		(layer "In9.Cu")
		(net 41)
	)
	(segment
		(start 208.855 125.575294)
		(end 208.855 123.51)
		(width 0.09)
		(layer "In9.Cu")
		(net 41)
	)
	(segment
		(start 205.180058 125.785352)
		(end 205.414927 126.020221)
		(width 0.09)
		(layer "In9.Cu")
		(net 41)
	)
	(segment
		(start 196.49 124.140294)
		(end 197.000294 123.63)
		(width 0.09)
		(layer "In9.Cu")
		(net 41)
	)
	(segment
		(start 196.49 125.079706)
		(end 196.49 124.140294)
		(width 0.09)
		(layer "In9.Cu")
		(net 41)
	)
	(segment
		(start 209.695 123.51)
		(end 209.695 125.28)
		(width 0.09)
		(layer "In9.Cu")
		(net 41)
	)
	(segment
		(start 211.595 124.217497)
		(end 211.595 124.360102)
		(width 0.09)
		(layer "In9.Cu")
		(net 41)
	)
	(segment
		(start 208.410073 126.020221)
		(end 208.855 125.575294)
		(width 0.09)
		(layer "In9.Cu")
		(net 41)
	)
	(segment
		(start 206.424706 124.92)
		(end 205.474706 124.92)
		(width 0.09)
		(layer "In9.Cu")
		(net 41)
	)
	(segment
		(start 206.349706 123.63)
		(end 206.67 123.950294)
		(width 0.09)
		(layer "In9.Cu")
		(net 41)
	)
	(segment
		(start 197.18 127.559706)
		(end 197.18 125.769706)
		(width 0.09)
		(layer "In9.Cu")
		(net 41)
	)
	(segment
		(start 205.414927 126.020221)
		(end 208.410073 126.020221)
		(width 0.09)
		(layer "In9.Cu")
		(net 41)
	)
	(segment
		(start 210.5 124.012497)
		(end 210.325802 124.012497)
		(width 0.09)
		(layer "In9.Cu")
		(net 41)
	)
	(segment
		(start 197.000294 123.63)
		(end 206.349706 123.63)
		(width 0.09)
		(layer "In9.Cu")
		(net 41)
	)
	(segment
		(start 197.640294 128.02)
		(end 197.18 127.559706)
		(width 0.09)
		(layer "In9.Cu")
		(net 41)
	)
	(segment
		(start 209.875 125.46)
		(end 211.870294 125.46)
		(width 0.09)
		(layer "In9.Cu")
		(net 41)
	)
	(segment
		(start 212.23 124.324706)
		(end 211.917791 124.012497)
		(width 0.09)
		(layer "In9.Cu")
		(net 41)
	)
	(segment
		(start 206.67 123.950294)
		(end 206.67 124.674706)
		(width 0.09)
		(layer "In9.Cu")
		(net 41)
	)
	(segment
		(start 210.705 124.360102)
		(end 210.705 124.217497)
		(width 0.09)
		(layer "In9.Cu")
		(net 41)
	)
	(segment
		(start 211.870294 125.46)
		(end 212.23 125.100294)
		(width 0.09)
		(layer "In9.Cu")
		(net 41)
	)
	(segment
		(start 211.917791 124.012497)
		(end 211.8 124.012497)
		(width 0.09)
		(layer "In9.Cu")
		(net 41)
	)
	(segment
		(start 198.1 128.3)
		(end 197.82 128.02)
		(width 0.09)
		(layer "In9.Cu")
		(net 41)
	)
	(segment
		(start 205.180058 125.214648)
		(end 205.180058 125.785352)
		(width 0.09)
		(layer "In9.Cu")
		(net 41)
	)
	(segment
		(start 197.18 125.769706)
		(end 196.49 125.079706)
		(width 0.09)
		(layer "In9.Cu")
		(net 41)
	)
	(segment
		(start 197.82 128.02)
		(end 197.640294 128.02)
		(width 0.09)
		(layer "In9.Cu")
		(net 41)
	)
	(arc
		(start 211.595 124.360102)
		(mid 211.464663 124.674765)
		(end 211.15 124.805102)
		(width 0.09)
		(layer "In9.Cu")
		(net 41)
	)
	(arc
		(start 210.705 124.217497)
		(mid 210.644957 124.07254)
		(end 210.5 124.012497)
		(width 0.09)
		(layer "In9.Cu")
		(net 41)
	)
	(arc
		(start 211.8 124.012497)
		(mid 211.655043 124.07254)
		(end 211.595 124.217497)
		(width 0.09)
		(layer "In9.Cu")
		(net 41)
	)
	(arc
		(start 209.695 125.28)
		(mid 209.747721 125.407279)
		(end 209.875 125.46)
		(width 0.09)
		(layer "In9.Cu")
		(net 41)
	)
	(arc
		(start 211.15 124.805102)
		(mid 210.835337 124.674765)
		(end 210.705 124.360102)
		(width 0.09)
		(layer "In9.Cu")
		(net 41)
	)
	(arc
		(start 209.275 123.09)
		(mid 209.571985 123.213015)
		(end 209.695 123.51)
		(width 0.09)
		(layer "In9.Cu")
		(net 41)
	)
	(arc
		(start 208.855 123.51)
		(mid 208.978015 123.213015)
		(end 209.275 123.09)
		(width 0.09)
		(layer "In9.Cu")
		(net 41)
	)
	(via
		(at 198.1 127.5)
		(size 0.35)
		(drill 0.15)
		(layers "F.Cu" "B.Cu")
		(remove_unused_layers yes)
		(keep_end_layers yes)
		(zone_layer_connections)
		(net 42)
	)
	(via
		(at 210.195802 123.642497)
		(size 0.35)
		(drill 0.15)
		(layers "F.Cu" "B.Cu")
		(remove_unused_layers yes)
		(keep_end_layers yes)
		(zone_layer_connections)
		(net 42)
	)
	(segment
		(start 206.43 124.049706)
		(end 206.43 124.575294)
		(width 0.09)
		(layer "In9.Cu")
		(net 42)
	)
	(segment
		(start 209.095 125.674706)
		(end 209.095 123.51)
		(width 0.09)
		(layer "In9.Cu")
		(net 42)
	)
	(segment
		(start 196.73 124.239706)
		(end 197.099706 123.87)
		(width 0.09)
		(layer "In9.Cu")
		(net 42)
	)
	(segment
		(start 206.250294 123.87)
		(end 206.43 124.049706)
		(width 0.09)
		(layer "In9.Cu")
		(net 42)
	)
	(segment
		(start 198.1 127.5)
		(end 197.82 127.78)
		(width 0.09)
		(layer "In9.Cu")
		(net 42)
	)
	(segment
		(start 210.945 124.360102)
		(end 210.945 124.217497)
		(width 0.09)
		(layer "In9.Cu")
		(net 42)
	)
	(segment
		(start 209.455 123.51)
		(end 209.455 125.28)
		(width 0.09)
		(layer "In9.Cu")
		(net 42)
	)
	(segment
		(start 196.73 124.980294)
		(end 196.73 124.239706)
		(width 0.09)
		(layer "In9.Cu")
		(net 42)
	)
	(segment
		(start 210.325802 123.772497)
		(end 210.195802 123.642497)
		(width 0.09)
		(layer "In9.Cu")
		(net 42)
	)
	(segment
		(start 208.509485 126.260221)
		(end 209.095 125.674706)
		(width 0.09)
		(layer "In9.Cu")
		(net 42)
	)
	(segment
		(start 212.017203 123.772497)
		(end 211.8 123.772497)
		(width 0.09)
		(layer "In9.Cu")
		(net 42)
	)
	(segment
		(start 197.099706 123.87)
		(end 206.250294 123.87)
		(width 0.09)
		(layer "In9.Cu")
		(net 42)
	)
	(segment
		(start 197.82 127.78)
		(end 197.739706 127.78)
		(width 0.09)
		(layer "In9.Cu")
		(net 42)
	)
	(segment
		(start 205.375294 124.68)
		(end 204.940058 125.115236)
		(width 0.09)
		(layer "In9.Cu")
		(net 42)
	)
	(segment
		(start 212.47 124.225294)
		(end 212.017203 123.772497)
		(width 0.09)
		(layer "In9.Cu")
		(net 42)
	)
	(segment
		(start 204.940058 125.884764)
		(end 205.315515 126.260221)
		(width 0.09)
		(layer "In9.Cu")
		(net 42)
	)
	(segment
		(start 211.355 124.217497)
		(end 211.355 124.360102)
		(width 0.09)
		(layer "In9.Cu")
		(net 42)
	)
	(segment
		(start 210.5 123.772497)
		(end 210.325802 123.772497)
		(width 0.09)
		(layer "In9.Cu")
		(net 42)
	)
	(segment
		(start 197.42 125.670294)
		(end 196.73 124.980294)
		(width 0.09)
		(layer "In9.Cu")
		(net 42)
	)
	(segment
		(start 209.875 125.7)
		(end 211.969706 125.7)
		(width 0.09)
		(layer "In9.Cu")
		(net 42)
	)
	(segment
		(start 204.940058 125.115236)
		(end 204.940058 125.884764)
		(width 0.09)
		(layer "In9.Cu")
		(net 42)
	)
	(segment
		(start 197.42 127.460294)
		(end 197.42 125.670294)
		(width 0.09)
		(layer "In9.Cu")
		(net 42)
	)
	(segment
		(start 205.315515 126.260221)
		(end 208.509485 126.260221)
		(width 0.09)
		(layer "In9.Cu")
		(net 42)
	)
	(segment
		(start 212.47 125.199706)
		(end 212.47 124.225294)
		(width 0.09)
		(layer "In9.Cu")
		(net 42)
	)
	(segment
		(start 206.43 124.575294)
		(end 206.325294 124.68)
		(width 0.09)
		(layer "In9.Cu")
		(net 42)
	)
	(segment
		(start 197.739706 127.78)
		(end 197.42 127.460294)
		(width 0.09)
		(layer "In9.Cu")
		(net 42)
	)
	(segment
		(start 206.325294 124.68)
		(end 205.375294 124.68)
		(width 0.09)
		(layer "In9.Cu")
		(net 42)
	)
	(segment
		(start 211.969706 125.7)
		(end 212.47 125.199706)
		(width 0.09)
		(layer "In9.Cu")
		(net 42)
	)
	(arc
		(start 211.8 123.772497)
		(mid 211.485337 123.902834)
		(end 211.355 124.217497)
		(width 0.09)
		(layer "In9.Cu")
		(net 42)
	)
	(arc
		(start 211.355 124.360102)
		(mid 211.294957 124.505059)
		(end 211.15 124.565102)
		(width 0.09)
		(layer "In9.Cu")
		(net 42)
	)
	(arc
		(start 209.095 123.51)
		(mid 209.147721 123.382721)
		(end 209.275 123.33)
		(width 0.09)
		(layer "In9.Cu")
		(net 42)
	)
	(arc
		(start 209.275 123.33)
		(mid 209.402279 123.382721)
		(end 209.455 123.51)
		(width 0.09)
		(layer "In9.Cu")
		(net 42)
	)
	(arc
		(start 209.455 125.28)
		(mid 209.578015 125.576985)
		(end 209.875 125.7)
		(width 0.09)
		(layer "In9.Cu")
		(net 42)
	)
	(arc
		(start 210.945 124.217497)
		(mid 210.814663 123.902834)
		(end 210.5 123.772497)
		(width 0.09)
		(layer "In9.Cu")
		(net 42)
	)
	(arc
		(start 211.15 124.565102)
		(mid 211.005043 124.505059)
		(end 210.945 124.360102)
		(width 0.09)
		(layer "In9.Cu")
		(net 42)
	)
	(via
		(at 211.31 118.63)
		(size 0.35)
		(drill 0.15)
		(layers "F.Cu" "B.Cu")
		(remove_unused_layers yes)
		(keep_end_layers yes)
		(zone_layer_connections)
		(net 43)
	)
	(via
		(at 196.5 128.3)
		(size 0.35)
		(drill 0.15)
		(layers "F.Cu" "B.Cu")
		(remove_unused_layers yes)
		(keep_end_layers yes)
		(zone_layer_connections)
		(net 43)
	)
	(segment
		(start 203.125 122.955)
		(end 196.315294 122.955)
		(width 0.09)
		(layer "In9.Cu")
		(net 43)
	)
	(segment
		(start 195.9 126.349706)
		(end 196.46 126.909706)
		(width 0.09)
		(layer "In9.Cu")
		(net 43)
	)
	(segment
		(start 208.675294 122.255)
		(end 207.892597 123.037697)
		(width 0.09)
		(layer "In9.Cu")
		(net 43)
	)
	(segment
		(start 210.99417 118.76)
		(end 210.65 119.10417)
		(width 0.09)
		(layer "In9.Cu")
		(net 43)
	)
	(segment
		(start 207.82 122.349706)
		(end 207.82 121.43)
		(width 0.09)
		(layer "In9.Cu")
		(net 43)
	)
	(segment
		(start 210.65 119.10417)
		(end 210.65 119.930294)
		(width 0.09)
		(layer "In9.Cu")
		(net 43)
	)
	(segment
		(start 196.209851 127.250148)
		(end 196.209851 127.3)
		(width 0.09)
		(layer "In9.Cu")
		(net 43)
	)
	(segment
		(start 196.46 128.26)
		(end 196.5 128.3)
		(width 0.09)
		(layer "In9.Cu")
		(net 43)
	)
	(segment
		(start 207.892597 123.037697)
		(end 207.892597 125.04)
		(width 0.09)
		(layer "In9.Cu")
		(net 43)
	)
	(segment
		(start 196.334926 127.125074)
		(end 196.334925 127.125074)
		(width 0.09)
		(layer "In9.Cu")
		(net 43)
	)
	(segment
		(start 196.46 128.150194)
		(end 196.46 128.26)
		(width 0.09)
		(layer "In9.Cu")
		(net 43)
	)
	(segment
		(start 207.282597 125.04)
		(end 207.282597 122.887109)
		(width 0.09)
		(layer "In9.Cu")
		(net 43)
	)
	(segment
		(start 210.65 119.930294)
		(end 209.53 121.050294)
		(width 0.09)
		(layer "In9.Cu")
		(net 43)
	)
	(segment
		(start 196.46 127.550148)
		(end 196.46 127.6)
		(width 0.09)
		(layer "In9.Cu")
		(net 43)
	)
	(segment
		(start 207.282597 122.887109)
		(end 207.82 122.349706)
		(width 0.09)
		(layer "In9.Cu")
		(net 43)
	)
	(segment
		(start 211.31 118.63)
		(end 211.18 118.76)
		(width 0.09)
		(layer "In9.Cu")
		(net 43)
	)
	(segment
		(start 196.46 126.909706)
		(end 196.46 127)
		(width 0.09)
		(layer "In9.Cu")
		(net 43)
	)
	(segment
		(start 211.18 118.76)
		(end 210.99417 118.76)
		(width 0.09)
		(layer "In9.Cu")
		(net 43)
	)
	(segment
		(start 205.275294 122.955)
		(end 204.825 122.955)
		(width 0.09)
		(layer "In9.Cu")
		(net 43)
	)
	(segment
		(start 209.114757 122.255)
		(end 208.675294 122.255)
		(width 0.09)
		(layer "In9.Cu")
		(net 43)
	)
	(segment
		(start 196.334902 128.025097)
		(end 196.334903 128.025097)
		(width 0.09)
		(layer "In9.Cu")
		(net 43)
	)
	(segment
		(start 209.53 121.839757)
		(end 209.114757 122.255)
		(width 0.09)
		(layer "In9.Cu")
		(net 43)
	)
	(segment
		(start 196.334925 127.425074)
		(end 196.334926 127.425074)
		(width 0.09)
		(layer "In9.Cu")
		(net 43)
	)
	(segment
		(start 203.43 121.53)
		(end 203.43 122.65)
		(width 0.09)
		(layer "In9.Cu")
		(net 43)
	)
	(segment
		(start 196.334903 127.725097)
		(end 196.334902 127.725097)
		(width 0.09)
		(layer "In9.Cu")
		(net 43)
	)
	(segment
		(start 209.53 121.050294)
		(end 209.53 121.839757)
		(width 0.09)
		(layer "In9.Cu")
		(net 43)
	)
	(segment
		(start 196.209805 127.850194)
		(end 196.209805 127.9)
		(width 0.09)
		(layer "In9.Cu")
		(net 43)
	)
	(segment
		(start 196.315294 122.955)
		(end 195.9 123.370294)
		(width 0.09)
		(layer "In9.Cu")
		(net 43)
	)
	(segment
		(start 207.495 121.105)
		(end 206.425294 121.105)
		(width 0.09)
		(layer "In9.Cu")
		(net 43)
	)
	(segment
		(start 206.425294 121.105)
		(end 205.655 121.875294)
		(width 0.09)
		(layer "In9.Cu")
		(net 43)
	)
	(segment
		(start 207.82 121.43)
		(end 207.495 121.105)
		(width 0.09)
		(layer "In9.Cu")
		(net 43)
	)
	(segment
		(start 204.52 122.65)
		(end 204.52 121.53)
		(width 0.09)
		(layer "In9.Cu")
		(net 43)
	)
	(segment
		(start 205.655 121.875294)
		(end 205.655 122.575294)
		(width 0.09)
		(layer "In9.Cu")
		(net 43)
	)
	(segment
		(start 205.655 122.575294)
		(end 205.275294 122.955)
		(width 0.09)
		(layer "In9.Cu")
		(net 43)
	)
	(segment
		(start 195.9 123.370294)
		(end 195.9 126.349706)
		(width 0.09)
		(layer "In9.Cu")
		(net 43)
	)
	(arc
		(start 196.46 127.6)
		(mid 196.42336 127.688457)
		(end 196.334903 127.725097)
		(width 0.09)
		(layer "In9.Cu")
		(net 43)
	)
	(arc
		(start 196.46 127)
		(mid 196.423367 127.088441)
		(end 196.334926 127.125074)
		(width 0.09)
		(layer "In9.Cu")
		(net 43)
	)
	(arc
		(start 196.334926 127.425074)
		(mid 196.423367 127.461707)
		(end 196.46 127.550148)
		(width 0.09)
		(layer "In9.Cu")
		(net 43)
	)
	(arc
		(start 196.334903 128.025097)
		(mid 196.42336 128.061737)
		(end 196.46 128.150194)
		(width 0.09)
		(layer "In9.Cu")
		(net 43)
	)
	(arc
		(start 196.334902 127.725097)
		(mid 196.246445 127.761737)
		(end 196.209805 127.850194)
		(width 0.09)
		(layer "In9.Cu")
		(net 43)
	)
	(arc
		(start 207.892597 125.04)
		(mid 207.803265 125.255667)
		(end 207.587597 125.345)
		(width 0.09)
		(layer "In9.Cu")
		(net 43)
	)
	(arc
		(start 204.52 121.53)
		(mid 204.360373 121.144627)
		(end 203.975 120.985)
		(width 0.09)
		(layer "In9.Cu")
		(net 43)
	)
	(arc
		(start 196.209851 127.3)
		(mid 196.246484 127.388441)
		(end 196.334925 127.425074)
		(width 0.09)
		(layer "In9.Cu")
		(net 43)
	)
	(arc
		(start 204.825 122.955)
		(mid 204.609332 122.865668)
		(end 204.52 122.65)
		(width 0.09)
		(layer "In9.Cu")
		(net 43)
	)
	(arc
		(start 196.209805 127.9)
		(mid 196.246445 127.988457)
		(end 196.334902 128.025097)
		(width 0.09)
		(layer "In9.Cu")
		(net 43)
	)
	(arc
		(start 203.975 120.985)
		(mid 203.589627 121.144627)
		(end 203.43 121.53)
		(width 0.09)
		(layer "In9.Cu")
		(net 43)
	)
	(arc
		(start 207.587597 125.345)
		(mid 207.371929 125.255668)
		(end 207.282597 125.04)
		(width 0.09)
		(layer "In9.Cu")
		(net 43)
	)
	(arc
		(start 203.43 122.65)
		(mid 203.340668 122.865668)
		(end 203.125 122.955)
		(width 0.09)
		(layer "In9.Cu")
		(net 43)
	)
	(arc
		(start 196.334925 127.125074)
		(mid 196.246484 127.161707)
		(end 196.209851 127.250148)
		(width 0.09)
		(layer "In9.Cu")
		(net 43)
	)
	(segment
		(start 197.85 120.05)
		(end 196.4 120.05)
		(width 0.1)
		(layer "F.Cu")
		(net 44)
	)
	(segment
		(start 195.727 121.848)
		(end 195.45 121.571)
		(width 0.11)
		(layer "F.Cu")
		(net 44)
	)
	(segment
		(start 195.45 121.571)
		(end 195.45 120)
		(width 0.11)
		(layer "F.Cu")
		(net 44)
	)
	(segment
		(start 196.4 120.05)
		(end 195.9 119.55)
		(width 0.1)
		(layer "F.Cu")
		(net 44)
	)
	(segment
		(start 195.45 120)
		(end 195.9 119.55)
		(width 0.11)
		(layer "F.Cu")
		(net 44)
	)
	(segment
		(start 195.927 121.848)
		(end 195.727 121.848)
		(width 0.11)
		(layer "F.Cu")
		(net 44)
	)
	(segment
		(start 195.9 117.8)
		(end 195.7 117.6)
		(width 0.1)
		(layer "F.Cu")
		(net 44)
	)
	(segment
		(start 195.9 119.55)
		(end 195.9 117.8)
		(width 0.1)
		(layer "F.Cu")
		(net 44)
	)
	(segment
		(start 195.072 117.6)
		(end 194.522 117.05)
		(width 0.1)
		(layer "F.Cu")
		(net 44)
	)
	(segment
		(start 198.65 120.85)
		(end 197.85 120.05)
		(width 0.1)
		(layer "F.Cu")
		(net 44)
	)
	(segment
		(start 195.7 117.6)
		(end 195.072 117.6)
		(width 0.1)
		(layer "F.Cu")
		(net 44)
	)
	(via
		(at 198.65 120.85)
		(size 0.35)
		(drill 0.15)
		(layers "F.Cu" "B.Cu")
		(remove_unused_layers yes)
		(keep_end_layers yes)
		(zone_layer_connections)
		(net 44)
	)
	(via
		(at 194.522 117.05)
		(size 0.35)
		(drill 0.15)
		(layers "F.Cu" "B.Cu")
		(remove_unused_layers yes)
		(keep_end_layers yes)
		(zone_layer_connections)
		(net 44)
	)
	(segment
		(start 199.02 121.22)
		(end 198.65 120.85)
		(width 0.256)
		(layer "B.Cu")
		(net 44)
	)
	(segment
		(start 199.475 121.22)
		(end 198.975 121.22)
		(width 0.256)
		(layer "B.Cu")
		(net 44)
	)
	(segment
		(start 199.95 121.22)
		(end 199.475 121.22)
		(width 0.256)
		(layer "B.Cu")
		(net 44)
	)
	(segment
		(start 199.475 121.22)
		(end 199.02 121.22)
		(width 0.256)
		(layer "B.Cu")
		(net 44)
	)
	(via
		(at 200.499 140.3)
		(size 0.35)
		(drill 0.15)
		(layers "F.Cu" "B.Cu")
		(remove_unused_layers yes)
		(keep_end_layers yes)
		(zone_layer_connections)
		(net 46)
	)
	(segment
		(start 200.5 141.868693)
		(end 200.498197 141.819324)
		(width 0.125)
		(layer "B.Cu")
		(net 46)
	)
	(segment
		(start 200.42217 140.7645)
		(end 200.449997 140.7645)
		(width 0.125)
		(layer "B.Cu")
		(net 46)
	)
	(segment
		(start 200.5 142.090001)
		(end 200.5 141.868693)
		(width 0.125)
		(layer "B.Cu")
		(net 46)
	)
	(segment
		(start 200.65 140.5645)
		(end 200.65 140.533843)
		(width 0.125)
		(layer "B.Cu")
		(net 46)
	)
	(segment
		(start 200.1615 141.323087)
		(end 200.1615 141.025184)
		(width 0.125)
		(layer "B.Cu")
		(net 46)
	)
	(segment
		(start 200.498197 141.819324)
		(end 200.460409 141.728102)
		(width 0.125)
		(layer "B.Cu")
		(net 46)
	)
	(segment
		(start 200.591421 140.392421)
		(end 200.499 140.3)
		(width 0.125)
		(layer "B.Cu")
		(net 46)
	)
	(segment
		(start 200.426776 141.691916)
		(end 200.234723 141.499863)
		(width 0.125)
		(layer "B.Cu")
		(net 46)
	)
	(segment
		(start 200.460409 141.728102)
		(end 200.426776 141.691916)
		(width 0.125)
		(layer "B.Cu")
		(net 46)
	)
	(arc
		(start 200.234723 141.499863)
		(mid 200.18053 141.418757)
		(end 200.1615 141.323087)
		(width 0.125)
		(layer "B.Cu")
		(net 46)
	)
	(arc
		(start 200.449997 140.7645)
		(mid 200.59142 140.70592)
		(end 200.65 140.5645)
		(width 0.125)
		(layer "B.Cu")
		(net 46)
	)
	(arc
		(start 200.65 140.533843)
		(mid 200.634776 140.457306)
		(end 200.591421 140.392421)
		(width 0.125)
		(layer "B.Cu")
		(net 46)
	)
	(arc
		(start 200.1615 141.025184)
		(mid 200.237842 140.840863)
		(end 200.42217 140.7645)
		(width 0.125)
		(layer "B.Cu")
		(net 46)
	)
	(segment
		(start 195.370993 139.029007)
		(end 195.7 138.7)
		(width 0.4)
		(layer "F.Cu")
		(net 47)
	)
	(segment
		(start 198.1 137.1)
		(end 198.899 136.301)
		(width 0.4)
		(layer "F.Cu")
		(net 47)
	)
	(segment
		(start 196.5 132.3)
		(end 196.5 132.302)
		(width 0.4)
		(layer "F.Cu")
		(net 47)
	)
	(segment
		(start 198.1 132.3)
		(end 198.1 132.302)
		(width 0.4)
		(layer "F.Cu")
		(net 47)
	)
	(segment
		(start 197.299 133.101)
		(end 198.1 132.3)
		(width 0.4)
		(layer "F.Cu")
		(net 47)
	)
	(segment
		(start 197.299 136.301)
		(end 197.3 136.301)
		(width 0.4)
		(layer "F.Cu")
		(net 47)
	)
	(segment
		(start 212.925 116.925)
		(end 214.05 116.925)
		(width 0.174)
		(layer "F.Cu")
		(net 47)
	)
	(segment
		(start 197.299 134.7)
		(end 197.3 134.7)
		(width 0.4)
		(layer "F.Cu")
		(net 47)
	)
	(segment
		(start 195.370993 139.090993)
		(end 195.370993 139.029007)
		(width 0.4)
		(layer "F.Cu")
		(net 47)
	)
	(segment
		(start 196.5 137.101)
		(end 196.5 137.1)
		(width 0.4)
		(layer "F.Cu")
		(net 47)
	)
	(segment
		(start 196.5 135.499)
		(end 197.299 134.7)
		(width 0.4)
		(layer "F.Cu")
		(net 47)
	)
	(segment
		(start 198.1 133.901)
		(end 198.899 134.7)
		(width 0.4)
		(layer "F.Cu")
		(net 47)
	)
	(segment
		(start 197.3 134.7)
		(end 198.1 133.9)
		(width 0.4)
		(layer "F.Cu")
		(net 47)
	)
	(segment
		(start 196.5 135.5)
		(end 196.5 135.499)
		(width 0.4)
		(layer "F.Cu")
		(net 47)
	)
	(segment
		(start 196.5 133.901)
		(end 197.299 134.7)
		(width 0.4)
		(layer "F.Cu")
		(net 47)
	)
	(segment
		(start 216.55 124.275)
		(end 216.55 123.875)
		(width 0.174)
		(layer "F.Cu")
		(net 47)
	)
	(segment
		(start 198.899 136.301)
		(end 198.899 136.3)
		(width 0.4)
		(layer "F.Cu")
		(net 47)
	)
	(segment
		(start 196.5 135.5)
		(end 196.5 135.502)
		(width 0.4)
		(layer "F.Cu")
		(net 47)
	)
	(segment
		(start 196.5 133.9)
		(end 196.5 133.901)
		(width 0.4)
		(layer "F.Cu")
		(net 47)
	)
	(segment
		(start 196.5 132.302)
		(end 197.299 133.101)
		(width 0.4)
		(layer "F.Cu")
		(net 47)
	)
	(segment
		(start 197.3 136.301)
		(end 198.1 137.101)
		(width 0.4)
		(layer "F.Cu")
		(net 47)
	)
	(segment
		(start 196.5 137.1)
		(end 197.299 136.301)
		(width 0.4)
		(layer "F.Cu")
		(net 47)
	)
	(segment
		(start 198.1 133.9)
		(end 198.1 133.901)
		(width 0.4)
		(layer "F.Cu")
		(net 47)
	)
	(segment
		(start 198.1 132.302)
		(end 198.899 133.101)
		(width 0.4)
		(layer "F.Cu")
		(net 47)
	)
	(segment
		(start 216.865999 124.590999)
		(end 216.55 124.275)
		(width 0.174)
		(layer "F.Cu")
		(net 47)
	)
	(segment
		(start 212.7 117.15)
		(end 212.925 116.925)
		(width 0.174)
		(layer "F.Cu")
		(net 47)
	)
	(segment
		(start 196.5 135.502)
		(end 197.299 136.301)
		(width 0.4)
		(layer "F.Cu")
		(net 47)
	)
	(segment
		(start 198.1 137.101)
		(end 198.1 137.1)
		(width 0.4)
		(layer "F.Cu")
		(net 47)
	)
	(segment
		(start 216.865999 124.62194)
		(end 216.865999 124.590999)
		(width 0.174)
		(layer "F.Cu")
		(net 47)
	)
	(segment
		(start 198.899 136.3)
		(end 199.699 135.5)
		(width 0.4)
		(layer "F.Cu")
		(net 47)
	)
	(via
		(at 209.6 140.15)
		(size 0.35)
		(drill 0.15)
		(layers "F.Cu" "B.Cu")
		(remove_unused_layers yes)
		(keep_end_layers yes)
		(free yes)
		(zone_layer_connections "In6.Cu" "In7.Cu")
		(net 47)
	)
	(via
		(at 186.3 145.6)
		(size 0.35)
		(drill 0.15)
		(layers "F.Cu" "B.Cu")
		(remove_unused_layers yes)
		(keep_end_layers yes)
		(free yes)
		(zone_layer_connections "In4.Cu" "In6.Cu")
		(net 47)
	)
	(via
		(at 186.75 145.3)
		(size 0.35)
		(drill 0.15)
		(layers "F.Cu" "B.Cu")
		(remove_unused_layers yes)
		(keep_end_layers yes)
		(free yes)
		(zone_layer_connections "In4.Cu" "In6.Cu")
		(net 47)
	)
	(via
		(at 185.825 146.55)
		(size 0.35)
		(drill 0.15)
		(layers "F.Cu" "B.Cu")
		(remove_unused_layers yes)
		(keep_end_layers yes)
		(free yes)
		(zone_layer_connections "In4.Cu" "In6.Cu")
		(net 47)
	)
	(via
		(at 210.2 139.250001)
		(size 0.35)
		(drill 0.15)
		(layers "F.Cu" "B.Cu")
		(remove_unused_layers yes)
		(keep_end_layers yes)
		(free yes)
		(zone_layer_connections "In6.Cu")
		(net 47)
	)
	(via
		(at 210.75 139.250001)
		(size 0.35)
		(drill 0.15)
		(layers "F.Cu" "B.Cu")
		(remove_unused_layers yes)
		(keep_end_layers yes)
		(free yes)
		(zone_layer_connections "In6.Cu")
		(net 47)
	)
	(via
		(at 216.5 124.9)
		(size 0.35)
		(drill 0.15)
		(layers "F.Cu" "B.Cu")
		(remove_unused_layers yes)
		(keep_end_layers yes)
		(zone_layer_connections "In4.Cu" "In7.Cu")
		(net 47)
	)
	(via
		(at 211.1 140.600001)
		(size 0.35)
		(drill 0.15)
		(layers "F.Cu" "B.Cu")
		(remove_unused_layers yes)
		(keep_end_layers yes)
		(free yes)
		(zone_layer_connections "In6.Cu" "In7.Cu")
		(net 47)
	)
	(via
		(at 220.85 120.65)
		(size 0.35)
		(drill 0.15)
		(layers "F.Cu" "B.Cu")
		(remove_unused_layers yes)
		(keep_end_layers yes)
		(zone_layer_connections "In4.Cu")
		(net 47)
	)
	(via
		(at 210.2 140.15)
		(size 0.35)
		(drill 0.15)
		(layers "F.Cu" "B.Cu")
		(remove_unused_layers yes)
		(keep_end_layers yes)
		(free yes)
		(zone_layer_connections "In6.Cu" "In7.Cu")
		(net 47)
	)
	(via
		(at 196.5 140.3)
		(size 0.35)
		(drill 0.15)
		(layers "F.Cu" "B.Cu")
		(remove_unused_layers yes)
		(keep_end_layers yes)
		(zone_layer_connections "In4.Cu" "In6.Cu")
		(net 47)
	)
	(via
		(at 187.45 145.05)
		(size 0.35)
		(drill 0.15)
		(layers "F.Cu" "B.Cu")
		(remove_unused_layers yes)
		(keep_end_layers yes)
		(free yes)
		(zone_layer_connections "In4.Cu" "In6.Cu")
		(net 47)
	)
	(via
		(at 209.35 140.600001)
		(size 0.35)
		(drill 0.15)
		(layers "F.Cu" "B.Cu")
		(remove_unused_layers yes)
		(keep_end_layers yes)
		(free yes)
		(zone_layer_connections "In6.Cu" "In7.Cu")
		(net 47)
	)
	(via
		(at 209.3 139.700001)
		(size 0.35)
		(drill 0.15)
		(layers "F.Cu" "B.Cu")
		(remove_unused_layers yes)
		(keep_end_layers yes)
		(free yes)
		(zone_layer_connections "In6.Cu" "In7.Cu")
		(net 47)
	)
	(via
		(at 197.299 136.301)
		(size 0.35)
		(drill 0.15)
		(layers "F.Cu" "B.Cu")
		(remove_unused_layers yes)
		(keep_end_layers yes)
		(zone_layer_connections "In4.Cu" "In6.Cu")
		(net 47)
	)
	(via
		(at 196.9 134.3)
		(size 0.35)
		(drill 0.15)
		(layers "F.Cu" "B.Cu")
		(remove_unused_layers yes)
		(keep_end_layers yes)
		(zone_layer_connections "In4.Cu" "In6.Cu")
		(net 47)
	)
	(via
		(at 209.9 139.7)
		(size 0.35)
		(drill 0.15)
		(layers "F.Cu" "B.Cu")
		(remove_unused_layers yes)
		(keep_end_layers yes)
		(free yes)
		(zone_layer_connections "In6.Cu" "In7.Cu")
		(net 47)
	)
	(via
		(at 199.699 140.3)
		(size 0.35)
		(drill 0.15)
		(layers "F.Cu" "B.Cu")
		(remove_unused_layers yes)
		(keep_end_layers yes)
		(zone_layer_connections "In4.Cu" "In6.Cu")
		(net 47)
	)
	(via
		(at 186.125 146.1)
		(size 0.35)
		(drill 0.15)
		(layers "F.Cu" "B.Cu")
		(remove_unused_layers yes)
		(keep_end_layers yes)
		(free yes)
		(zone_layer_connections "In4.Cu" "In6.Cu")
		(net 47)
	)
	(via
		(at 197.7 134.3)
		(size 0.35)
		(drill 0.15)
		(layers "F.Cu" "B.Cu")
		(remove_unused_layers yes)
		(keep_end_layers yes)
		(zone_layer_connections "In4.Cu" "In6.Cu")
		(net 47)
	)
	(via
		(at 210.505048 140.602492)
		(size 0.35)
		(drill 0.15)
		(layers "F.Cu" "B.Cu")
		(remove_unused_layers yes)
		(keep_end_layers yes)
		(free yes)
		(zone_layer_connections "In6.Cu" "In7.Cu")
		(net 47)
	)
	(via
		(at 186.975 145.650001)
		(size 0.35)
		(drill 0.15)
		(layers "F.Cu" "B.Cu")
		(remove_unused_layers yes)
		(keep_end_layers yes)
		(free yes)
		(zone_layer_connections "In4.Cu" "In6.Cu")
		(net 47)
	)
	(via
		(at 201.3 140.3)
		(size 0.35)
		(drill 0.15)
		(layers "F.Cu" "B.Cu")
		(remove_unused_layers yes)
		(keep_end_layers yes)
		(zone_layer_connections "In6.Cu")
		(net 47)
	)
	(via
		(at 198.899 136.301)
		(size 0.35)
		(drill 0.15)
		(layers "F.Cu" "B.Cu")
		(remove_unused_layers yes)
		(keep_end_layers yes)
		(zone_layer_connections "In4.Cu" "In6.Cu")
		(net 47)
	)
	(via
		(at 187.9 145.9)
		(size 0.35)
		(drill 0.15)
		(layers "F.Cu" "B.Cu")
		(remove_unused_layers yes)
		(keep_end_layers yes)
		(free yes)
		(zone_layer_connections "In4.Cu" "In6.Cu")
		(net 47)
	)
	(via
		(at 187.9 144.2)
		(size 0.35)
		(drill 0.15)
		(layers "F.Cu" "B.Cu")
		(remove_unused_layers yes)
		(keep_end_layers yes)
		(free yes)
		(zone_layer_connections "In4.Cu" "In6.Cu")
		(net 47)
	)
	(via
		(at 187.899999 145.35)
		(size 0.35)
		(drill 0.15)
		(layers "F.Cu" "B.Cu")
		(remove_unused_layers yes)
		(keep_end_layers yes)
		(free yes)
		(zone_layer_connections "In4.Cu" "In6.Cu")
		(net 47)
	)
	(via
		(at 210.505048 139.702493)
		(size 0.35)
		(drill 0.15)
		(layers "F.Cu" "B.Cu")
		(remove_unused_layers yes)
		(keep_end_layers yes)
		(free yes)
		(zone_layer_connections "In6.Cu" "In7.Cu")
		(net 47)
	)
	(via
		(at 197.69 132.71)
		(size 0.35)
		(drill 0.15)
		(layers "F.Cu" "B.Cu")
		(remove_unused_layers yes)
		(keep_end_layers yes)
		(zone_layer_connections "In4.Cu" "In6.Cu")
		(net 47)
	)
	(via
		(at 198.5 132.72)
		(size 0.35)
		(drill 0.15)
		(layers "F.Cu" "B.Cu")
		(remove_unused_layers yes)
		(keep_end_layers yes)
		(zone_layer_connections "In4.Cu" "In6.Cu")
		(net 47)
	)
	(via
		(at 198.5 134.3)
		(size 0.35)
		(drill 0.15)
		(layers "F.Cu" "B.Cu")
		(remove_unused_layers yes)
		(keep_end_layers yes)
		(zone_layer_connections "In4.Cu" "In6.Cu")
		(net 47)
	)
	(via
		(at 187.45 144.5)
		(size 0.35)
		(drill 0.15)
		(layers "F.Cu" "B.Cu")
		(remove_unused_layers yes)
		(keep_end_layers yes)
		(free yes)
		(zone_layer_connections "In4.Cu" "In6.Cu")
		(net 47)
	)
	(via
		(at 209.9 140.599999)
		(size 0.35)
		(drill 0.15)
		(layers "F.Cu" "B.Cu")
		(remove_unused_layers yes)
		(keep_end_layers yes)
		(free yes)
		(zone_layer_connections "In6.Cu" "In7.Cu")
		(net 47)
	)
	(via
		(at 198.1 140.3)
		(size 0.35)
		(drill 0.15)
		(layers "F.Cu" "B.Cu")
		(remove_unused_layers yes)
		(keep_end_layers yes)
		(zone_layer_connections "In4.Cu" "In6.Cu")
		(net 47)
	)
	(via
		(at 216.865999 124.62194)
		(size 0.35)
		(drill 0.15)
		(layers "F.Cu" "B.Cu")
		(remove_unused_layers yes)
		(keep_end_layers yes)
		(zone_layer_connections "In4.Cu" "In7.Cu")
		(net 47)
	)
	(via
		(at 187.902492 144.744952)
		(size 0.35)
		(drill 0.15)
		(layers "F.Cu" "B.Cu")
		(remove_unused_layers yes)
		(keep_end_layers yes)
		(free yes)
		(zone_layer_connections "In4.Cu" "In6.Cu")
		(net 47)
	)
	(via
		(at 198.899 138.7)
		(size 0.35)
		(drill 0.15)
		(layers "F.Cu" "B.Cu")
		(remove_unused_layers yes)
		(keep_end_layers yes)
		(zone_layer_connections "In4.Cu" "In6.Cu")
		(net 47)
	)
	(via
		(at 209.6 139.250001)
		(size 0.35)
		(drill 0.15)
		(layers "F.Cu" "B.Cu")
		(remove_unused_layers yes)
		(keep_end_layers yes)
		(free yes)
		(zone_layer_connections "In6.Cu")
		(net 47)
	)
	(via
		(at 186.730048 146.102493)
		(size 0.35)
		(drill 0.15)
		(layers "F.Cu" "B.Cu")
		(remove_unused_layers yes)
		(keep_end_layers yes)
		(free yes)
		(zone_layer_connections "In4.Cu" "In6.Cu")
		(net 47)
	)
	(via
		(at 212.85 120.65)
		(size 0.35)
		(drill 0.15)
		(layers "F.Cu" "B.Cu")
		(remove_unused_layers yes)
		(keep_end_layers yes)
		(zone_layer_connections "In4.Cu" "In7.Cu")
		(net 47)
	)
	(via
		(at 211.1 139.700001)
		(size 0.35)
		(drill 0.15)
		(layers "F.Cu" "B.Cu")
		(remove_unused_layers yes)
		(keep_end_layers yes)
		(free yes)
		(zone_layer_connections "In6.Cu" "In7.Cu")
		(net 47)
	)
	(via
		(at 195.370993 139.090993)
		(size 0.35)
		(drill 0.15)
		(layers "F.Cu" "B.Cu")
		(remove_unused_layers yes)
		(keep_end_layers yes)
		(zone_layer_connections "In4.Cu" "In6.Cu")
		(net 47)
	)
	(via
		(at 186.975 146.55)
		(size 0.35)
		(drill 0.15)
		(layers "F.Cu" "B.Cu")
		(remove_unused_layers yes)
		(keep_end_layers yes)
		(free yes)
		(zone_layer_connections "In4.Cu" "In6.Cu")
		(net 47)
	)
	(via
		(at 212.7 117.15)
		(size 0.35)
		(drill 0.15)
		(layers "F.Cu" "B.Cu")
		(remove_unused_layers yes)
		(keep_end_layers yes)
		(zone_layer_connections "In4.Cu" "In7.Cu")
		(net 47)
	)
	(via
		(at 194.9 140.3)
		(size 0.35)
		(drill 0.15)
		(layers "F.Cu" "B.Cu")
		(remove_unused_layers yes)
		(keep_end_layers yes)
		(zone_layer_connections "In4.Cu" "In6.Cu")
		(net 47)
	)
	(via
		(at 186.425 146.55)
		(size 0.35)
		(drill 0.15)
		(layers "F.Cu" "B.Cu")
		(remove_unused_layers yes)
		(keep_end_layers yes)
		(free yes)
		(zone_layer_connections "In4.Cu" "In6.Cu")
		(net 47)
	)
	(via
		(at 196.88 132.69)
		(size 0.35)
		(drill 0.15)
		(layers "F.Cu" "B.Cu")
		(remove_unused_layers yes)
		(keep_end_layers yes)
		(zone_layer_connections "In4.Cu" "In6.Cu")
		(net 47)
	)
	(via
		(at 210.75 140.15)
		(size 0.35)
		(drill 0.15)
		(layers "F.Cu" "B.Cu")
		(remove_unused_layers yes)
		(keep_end_layers yes)
		(free yes)
		(zone_layer_connections "In6.Cu" "In7.Cu")
		(net 47)
	)
	(via
		(at 187.45 145.65)
		(size 0.35)
		(drill 0.15)
		(layers "F.Cu" "B.Cu")
		(remove_unused_layers yes)
		(keep_end_layers yes)
		(free yes)
		(zone_layer_connections "In4.Cu" "In6.Cu")
		(net 47)
	)
	(segment
		(start 217.361 124.126939)
		(end 216.865999 124.62194)
		(width 0.256)
		(layer "B.Cu")
		(net 47)
	)
	(segment
		(start 196.9 134.3)
		(end 198.89 134.3)
		(width 0.4)
		(layer "B.Cu")
		(net 47)
	)
	(segment
		(start 212.7 117.5)
		(end 212.954 117.754)
		(width 0.174)
		(layer "B.Cu")
		(net 47)
	)
	(segment
		(start 216.361 124.116941)
		(end 216.865999 124.62194)
		(width 0.256)
		(layer "B.Cu")
		(net 47)
	)
	(segment
		(start 212.7 117.15)
		(end 212.7 117.5)
		(width 0.174)
		(layer "B.Cu")
		(net 47)
	)
	(segment
		(start 196.88 132.69)
		(end 197.19 132.69)
		(width 0.256)
		(layer "B.Cu")
		(net 47)
	)
	(segment
		(start 217 124.755941)
		(end 216.865999 124.62194)
		(width 0.4)
		(layer "B.Cu")
		(net 47)
	)
	(segment
		(start 213.381 121.754)
		(end 213.381 120.754)
		(width 0.2)
		(layer "B.Cu")
		(net 47)
	)
	(segment
		(start 197.19 132.69)
		(end 197.305 132.575)
		(width 0.256)
		(layer "B.Cu")
		(net 47)
	)
	(segment
		(start 196.88 132.69)
		(end 197.04 132.53)
		(width 0.256)
		(layer "B.Cu")
		(net 47)
	)
	(segment
		(start 198.675 132.575)
		(end 198.94 132.31)
		(width 0.4)
		(layer "B.Cu")
		(net 47)
	)
	(segment
		(start 217.361 123.734)
		(end 217.361 124.126939)
		(width 0.256)
		(layer "B.Cu")
		(net 47)
	)
	(segment
		(start 220.4804 120.65)
		(end 220.391 120.7394)
		(width 0.2)
		(layer "B.Cu")
		(net 47)
	)
	(segment
		(start 216.361 123.734)
		(end 216.361 124.116941)
		(width 0.256)
		(layer "B.Cu")
		(net 47)
	)
	(segment
		(start 212.85 120.65)
		(end 212.954 120.754)
		(width 0.2)
		(layer "B.Cu")
		(net 47)
	)
	(segment
		(start 212.954 120.754)
		(end 213.381 120.754)
		(width 0.2)
		(layer "B.Cu")
		(net 47)
	)
	(segment
		(start 197.305 132.575)
		(end 198.675 132.575)
		(width 0.4)
		(layer "B.Cu")
		(net 47)
	)
	(segment
		(start 198.89 134.3)
		(end 198.94 134.25)
		(width 0.4)
		(layer "B.Cu")
		(net 47)
	)
	(segment
		(start 216.361 123.734)
		(end 217.361 123.734)
		(width 0.256)
		(layer "B.Cu")
		(net 47)
	)
	(segment
		(start 197.04 132.53)
		(end 197.04 132.31)
		(width 0.256)
		(layer "B.Cu")
		(net 47)
	)
	(segment
		(start 220.85 120.65)
		(end 220.4804 120.65)
		(width 0.2)
		(layer "B.Cu")
		(net 47)
	)
	(segment
		(start 217 124.9)
		(end 216.5 124.9)
		(width 0.4)
		(layer "B.Cu")
		(net 47)
	)
	(segment
		(start 197.04 132.31)
		(end 197.305 132.575)
		(width 0.4)
		(layer "B.Cu")
		(net 47)
	)
	(segment
		(start 217 124.755941)
		(end 217 124.9)
		(width 0.4)
		(layer "B.Cu")
		(net 47)
	)
	(segment
		(start 212.954 117.754)
		(end 213.377 117.754)
		(width 0.174)
		(layer "B.Cu")
		(net 47)
	)
	(segment
		(start 216.587939 124.9)
		(end 216.865999 124.62194)
		(width 0.4)
		(layer "B.Cu")
		(net 47)
	)
	(segment
		(start 216.5 124.9)
		(end 216.587939 124.9)
		(width 0.4)
		(layer "B.Cu")
		(net 47)
	)
	(segment
		(start 175.699999 147.4)
		(end 175.95 147.650001)
		(width 0.1)
		(layer "F.Cu")
		(net 48)
	)
	(segment
		(start 178.004 132.517)
		(end 178.4035 132.1925)
		(width 0.174)
		(layer "F.Cu")
		(net 48)
	)
	(segment
		(start 184.405 133.167)
		(end 184.8045 132.8425)
		(width 0.174)
		(layer "F.Cu")
		(net 48)
	)
	(segment
		(start 182.004 132.517)
		(end 181.6045 132.1925)
		(width 0.174)
		(layer "F.Cu")
		(net 48)
	)
	(segment
		(start 196.09 134.31)
		(end 195.7 134.7)
		(width 0.4)
		(layer "F.Cu")
		(net 48)
	)
	(segment
		(start 197.365234 146.606582)
		(end 197.82 146.151816)
		(width 0.2)
		(layer "F.Cu")
		(net 48)
	)
	(segment
		(start 197.82 146.151816)
		(end 197.82 145.43)
		(width 0.2)
		(layer "F.Cu")
		(net 48)
	)
	(segment
		(start 194.9 133.9)
		(end 194.901 133.9)
		(width 0.4)
		(layer "F.Cu")
		(net 48)
	)
	(segment
		(start 196.081 132.72)
		(end 195.7 133.101)
		(width 0.4)
		(layer "F.Cu")
		(net 48)
	)
	(segment
		(start 175.604 126.016)
		(end 175.254 125.666)
		(width 0.256)
		(layer "F.Cu")
		(net 48)
	)
	(segment
		(start 196.09 134.3)
		(end 196.09 134.31)
		(width 0.4)
		(layer "F.Cu")
		(net 48)
	)
	(segment
		(start 194.9 133.9)
		(end 195.7 134.7)
		(width 0.4)
		(layer "F.Cu")
		(net 48)
	)
	(segment
		(start 175.2 133.571)
		(end 175.604 133.167)
		(width 0.174)
		(layer "F.Cu")
		(net 48)
	)
	(segment
		(start 182.004 126.666)
		(end 181.6045 126.9905)
		(width 0.174)
		(layer "F.Cu")
		(net 48)
	)
	(segment
		(start 175.2 133.95)
		(end 175.2 133.571)
		(width 0.174)
		(layer "F.Cu")
		(net 48)
	)
	(segment
		(start 194.899 133.9)
		(end 194.099 134.7)
		(width 0.4)
		(layer "F.Cu")
		(net 48)
	)
	(segment
		(start 197.75 144.53)
		(end 197.75 145.36)
		(width 0.2)
		(layer "F.Cu")
		(net 48)
	)
	(segment
		(start 194.901 133.9)
		(end 195.7 133.101)
		(width 0.4)
		(layer "F.Cu")
		(net 48)
	)
	(segment
		(start 184.405 126.016)
		(end 184.8045 126.3405)
		(width 0.174)
		(layer "F.Cu")
		(net 48)
	)
	(segment
		(start 175.104084 147.4)
		(end 175.699999 147.4)
		(width 0.1)
		(layer "F.Cu")
		(net 48)
	)
	(segment
		(start 175.103997 147.399913)
		(end 175.104084 147.4)
		(width 0.1)
		(layer "F.Cu")
		(net 48)
	)
	(segment
		(start 178.004 126.666)
		(end 178.4035 126.9905)
		(width 0.174)
		(layer "F.Cu")
		(net 48)
	)
	(segment
		(start 194.9 133.9)
		(end 194.899 133.9)
		(width 0.4)
		(layer "F.Cu")
		(net 48)
	)
	(segment
		(start 197.75 143.73)
		(end 197.75 144.53)
		(width 0.2)
		(layer "F.Cu")
		(net 48)
	)
	(segment
		(start 197.75 145.36)
		(end 197.82 145.43)
		(width 0.2)
		(layer "F.Cu")
		(net 48)
	)
	(segment
		(start 196.1 132.72)
		(end 196.081 132.72)
		(width 0.4)
		(layer "F.Cu")
		(net 48)
	)
	(via
		(at 190.9 133.12)
		(size 0.35)
		(drill 0.15)
		(layers "F.Cu" "B.Cu")
		(remove_unused_layers yes)
		(keep_end_layers yes)
		(zone_layer_connections "In7.Cu")
		(net 48)
	)
	(via
		(at 190.1 138.7)
		(size 0.35)
		(drill 0.15)
		(layers "F.Cu" "B.Cu")
		(remove_unused_layers yes)
		(keep_end_layers yes)
		(zone_layer_connections "In7.Cu")
		(net 48)
	)
	(via
		(at 220.15 134.85)
		(size 0.35)
		(drill 0.15)
		(layers "F.Cu" "B.Cu")
		(remove_unused_layers yes)
		(keep_end_layers yes)
		(zone_layer_connections "In7.Cu")
		(net 48)
	)
	(via
		(at 178.4035 126.9905)
		(size 0.35)
		(drill 0.15)
		(layers "F.Cu" "B.Cu")
		(remove_unused_layers yes)
		(keep_end_layers yes)
		(zone_layer_connections "In7.Cu")
		(net 48)
	)
	(via
		(at 194.099 134.7)
		(size 0.35)
		(drill 0.15)
		(layers "F.Cu" "B.Cu")
		(remove_unused_layers yes)
		(keep_end_layers yes)
		(zone_layer_connections "In7.Cu")
		(net 48)
	)
	(via
		(at 196.09 134.3)
		(size 0.35)
		(drill 0.15)
		(layers "F.Cu" "B.Cu")
		(remove_unused_layers yes)
		(keep_end_layers yes)
		(zone_layer_connections)
		(net 48)
	)
	(via
		(at 195.7 131.501)
		(size 0.35)
		(drill 0.15)
		(layers "F.Cu" "B.Cu")
		(remove_unused_layers yes)
		(keep_end_layers yes)
		(zone_layer_connections)
		(net 48)
	)
	(via
		(at 175.254 125.666)
		(size 0.35)
		(drill 0.15)
		(layers "F.Cu" "B.Cu")
		(remove_unused_layers yes)
		(keep_end_layers yes)
		(zone_layer_connections "In7.Cu")
		(net 48)
	)
	(via
		(at 195.7 136.301)
		(size 0.35)
		(drill 0.15)
		(layers "F.Cu" "B.Cu")
		(remove_unused_layers yes)
		(keep_end_layers yes)
		(zone_layer_connections)
		(net 48)
	)
	(via
		(at 175.45 145.1375)
		(size 0.35)
		(drill 0.15)
		(layers "F.Cu" "B.Cu")
		(remove_unused_layers yes)
		(keep_end_layers yes)
		(free yes)
		(zone_layer_connections "In7.Cu")
		(net 48)
	)
	(via
		(at 189.3 136.25)
		(size 0.35)
		(drill 0.15)
		(layers "F.Cu" "B.Cu")
		(remove_unused_layers yes)
		(keep_end_layers yes)
		(zone_layer_connections "In7.Cu")
		(net 48)
	)
	(via
		(at 175.098252 144.883235)
		(size 0.35)
		(drill 0.15)
		(layers "F.Cu" "B.Cu")
		(remove_unused_layers yes)
		(keep_end_layers yes)
		(free yes)
		(zone_layer_connections "In7.Cu")
		(net 48)
	)
	(via
		(at 175 145.3875)
		(size 0.35)
		(drill 0.15)
		(layers "F.Cu" "B.Cu")
		(remove_unused_layers yes)
		(keep_end_layers yes)
		(free yes)
		(zone_layer_connections "In7.Cu")
		(net 48)
	)
	(via
		(at 175.076057 145.838736)
		(size 0.35)
		(drill 0.15)
		(layers "F.Cu" "B.Cu")
		(remove_unused_layers yes)
		(keep_end_layers yes)
		(free yes)
		(zone_layer_connections "In7.Cu")
		(net 48)
	)
	(via
		(at 196.1 132.72)
		(size 0.35)
		(drill 0.15)
		(layers "F.Cu" "B.Cu")
		(remove_unused_layers yes)
		(keep_end_layers yes)
		(zone_layer_connections)
		(net 48)
	)
	(via
		(at 178.25 145.51)
		(size 0.35)
		(drill 0.15)
		(layers "F.Cu" "B.Cu")
		(remove_unused_layers yes)
		(keep_end_layers yes)
		(free yes)
		(zone_layer_connections)
		(net 48)
	)
	(via
		(at 184.8045 126.3405)
		(size 0.35)
		(drill 0.15)
		(layers "F.Cu" "B.Cu")
		(remove_unused_layers yes)
		(keep_end_layers yes)
		(zone_layer_connections "In7.Cu")
		(net 48)
	)
	(via
		(at 191.149997 118.651)
		(size 0.35)
		(drill 0.15)
		(layers "F.Cu" "B.Cu")
		(remove_unused_layers yes)
		(keep_end_layers yes)
		(zone_layer_connections "In7.Cu")
		(net 48)
	)
	(via
		(at 184.8045 132.8425)
		(size 0.35)
		(drill 0.15)
		(layers "F.Cu" "B.Cu")
		(remove_unused_layers yes)
		(keep_end_layers yes)
		(zone_layer_connections "In7.Cu")
		(net 48)
	)
	(via
		(at 191.7 135.5)
		(size 0.35)
		(drill 0.15)
		(layers "F.Cu" "B.Cu")
		(remove_unused_layers yes)
		(keep_end_layers yes)
		(zone_layer_connections "In7.Cu")
		(net 48)
	)
	(via
		(at 192.499 137.901)
		(size 0.35)
		(drill 0.15)
		(layers "F.Cu" "B.Cu")
		(remove_unused_layers yes)
		(keep_end_layers yes)
		(zone_layer_connections "In7.Cu")
		(net 48)
	)
	(via
		(at 175.103997 147.399913)
		(size 0.35)
		(drill 0.15)
		(layers "F.Cu" "B.Cu")
		(remove_unused_layers yes)
		(keep_end_layers yes)
		(zone_layer_connections)
		(net 48)
	)
	(via
		(at 190.9 141.101)
		(size 0.35)
		(drill 0.15)
		(layers "F.Cu" "B.Cu")
		(remove_unused_layers yes)
		(keep_end_layers yes)
		(zone_layer_connections "In7.Cu")
		(net 48)
	)
	(via
		(at 175.45 145.5875)
		(size 0.35)
		(drill 0.15)
		(layers "F.Cu" "B.Cu")
		(remove_unused_layers yes)
		(keep_end_layers yes)
		(free yes)
		(zone_layer_connections "In7.Cu")
		(net 48)
	)
	(via
		(at 175.805 145.837498)
		(size 0.35)
		(drill 0.15)
		(layers "F.Cu" "B.Cu")
		(remove_unused_layers yes)
		(keep_end_layers yes)
		(free yes)
		(zone_layer_connections "In7.Cu")
		(net 48)
	)
	(via
		(at 220.15 134.4)
		(size 0.35)
		(drill 0.15)
		(layers "F.Cu" "B.Cu")
		(remove_unused_layers yes)
		(keep_end_layers yes)
		(zone_layer_connections "In7.Cu")
		(net 48)
	)
	(via
		(at 178.4035 132.1925)
		(size 0.35)
		(drill 0.15)
		(layers "F.Cu" "B.Cu")
		(remove_unused_layers yes)
		(keep_end_layers yes)
		(zone_layer_connections "In7.Cu")
		(net 48)
	)
	(via
		(at 191.9 118.651)
		(size 0.35)
		(drill 0.15)
		(layers "F.Cu" "B.Cu")
		(remove_unused_layers yes)
		(keep_end_layers yes)
		(zone_layer_connections "In7.Cu")
		(net 48)
	)
	(via
		(at 175.9 145.3875)
		(size 0.35)
		(drill 0.15)
		(layers "F.Cu" "B.Cu")
		(remove_unused_layers yes)
		(keep_end_layers yes)
		(free yes)
		(zone_layer_connections "In7.Cu")
		(net 48)
	)
	(via
		(at 181.6045 132.1925)
		(size 0.35)
		(drill 0.15)
		(layers "F.Cu" "B.Cu")
		(remove_unused_layers yes)
		(keep_end_layers yes)
		(zone_layer_connections "In7.Cu")
		(net 48)
	)
	(via
		(at 191.524999 118.201)
		(size 0.35)
		(drill 0.15)
		(layers "F.Cu" "B.Cu")
		(remove_unused_layers yes)
		(keep_end_layers yes)
		(zone_layer_connections "In7.Cu")
		(net 48)
	)
	(via
		(at 175.2 133.95)
		(size 0.35)
		(drill 0.15)
		(layers "F.Cu" "B.Cu")
		(remove_unused_layers yes)
		(keep_end_layers yes)
		(zone_layer_connections "In7.Cu")
		(net 48)
	)
	(via
		(at 175.800715 144.883049)
		(size 0.35)
		(drill 0.15)
		(layers "F.Cu" "B.Cu")
		(remove_unused_layers yes)
		(keep_end_layers yes)
		(free yes)
		(zone_layer_connections "In7.Cu")
		(net 48)
	)
	(via
		(at 197.365234 146.606582)
		(size 0.35)
		(drill 0.15)
		(layers "F.Cu" "B.Cu")
		(remove_unused_layers yes)
		(keep_end_layers yes)
		(zone_layer_connections "In7.Cu")
		(net 48)
	)
	(via
		(at 212.55 142.15)
		(size 0.35)
		(drill 0.15)
		(layers "F.Cu" "B.Cu")
		(remove_unused_layers yes)
		(keep_end_layers yes)
		(zone_layer_connections)
		(net 48)
	)
	(via
		(at 181.6045 126.9905)
		(size 0.35)
		(drill 0.15)
		(layers "F.Cu" "B.Cu")
		(remove_unused_layers yes)
		(keep_end_layers yes)
		(zone_layer_connections "In7.Cu")
		(net 48)
	)
	(via
		(at 222.425 138.675)
		(size 0.35)
		(drill 0.15)
		(layers "F.Cu" "B.Cu")
		(remove_unused_layers yes)
		(keep_end_layers yes)
		(zone_layer_connections)
		(net 48)
	)
	(segment
		(start 177.20125 144.80125)
		(end 177.27 144.87)
		(width 0.1)
		(layer "B.Cu")
		(net 48)
	)
	(segment
		(start 190.1 138.7)
		(end 190.8 138.7)
		(width 0.4)
		(layer "B.Cu")
		(net 48)
	)
	(segment
		(start 222.4245 138.6745)
		(end 222.425 138.675)
		(width 0.256)
		(layer "B.Cu")
		(net 48)
	)
	(segment
		(start 177.499326 145.46)
		(end 178.2 145.46)
		(width 0.1)
		(layer "B.Cu")
		(net 48)
	)
	(segment
		(start 212.55 142.15)
		(end 212.415 142.015)
		(width 0.174)
		(layer "B.Cu")
		(net 48)
	)
	(segment
		(start 191.72 119.221003)
		(end 191.149997 118.651)
		(width 0.182)
		(layer "B.Cu")
		(net 48)
	)
	(segment
		(start 176.77 144.80125)
		(end 177.20125 144.80125)
		(width 0.1)
		(layer "B.Cu")
		(net 48)
	)
	(segment
		(start 191.72 120.171)
		(end 191.72 119.221003)
		(width 0.182)
		(layer "B.Cu")
		(net 48)
	)
	(segment
		(start 191.749 137.901)
		(end 192.499 137.901)
		(width 0.4)
		(layer "B.Cu")
		(net 48)
	)
	(segment
		(start 219.818 134.282)
		(end 219.6 134.064)
		(width 0.256)
		(layer "B.Cu")
		(net 48)
	)
	(segment
		(start 177.27 145.230674)
		(end 177.499326 145.46)
		(width 0.1)
		(layer "B.Cu")
		(net 48)
	)
	(segment
		(start 178.2 145.46)
		(end 178.25 145.51)
		(width 0.1)
		(layer "B.Cu")
		(net 48)
	)
	(segment
		(start 219.818 134.282)
		(end 220.032 134.282)
		(width 0.256)
		(layer "B.Cu")
		(net 48)
	)
	(segment
		(start 195.91 131.584)
		(end 196.175 131.849)
		(width 0.4)
		(layer "B.Cu")
		(net 48)
	)
	(segment
		(start 220.15 134.85)
		(end 220.15 134.4)
		(width 0.256)
		(layer "B.Cu")
		(net 48)
	)
	(segment
		(start 196.175 132.645)
		(end 196.1 132.72)
		(width 0.4)
		(layer "B.Cu")
		(net 48)
	)
	(segment
		(start 222.4245 138.136)
		(end 222.4245 138.6745)
		(width 0.256)
		(layer "B.Cu")
		(net 48)
	)
	(segment
		(start 220.032 134.282)
		(end 220.15 134.4)
		(width 0.256)
		(layer "B.Cu")
		(net 48)
	)
	(segment
		(start 212.415 142.015)
		(end 212.415 141.634)
		(width 0.174)
		(layer "B.Cu")
		(net 48)
	)
	(segment
		(start 196.175 131.849)
		(end 196.175 132.645)
		(width 0.4)
		(layer "B.Cu")
		(net 48)
	)
	(segment
		(start 176.62 144.95125)
		(end 176.77 144.80125)
		(width 0.1)
		(layer "B.Cu")
		(net 48)
	)
	(segment
		(start 176.62 145.38875)
		(end 176.62 144.95125)
		(width 0.1)
		(layer "B.Cu")
		(net 48)
	)
	(segment
		(start 219.6 134.064)
		(end 219.6 133.729)
		(width 0.256)
		(layer "B.Cu")
		(net 48)
	)
	(segment
		(start 191.71 137.94)
		(end 191.749 137.901)
		(width 0.4)
		(layer "B.Cu")
		(net 48)
	)
	(segment
		(start 177.27 144.87)
		(end 177.27 145.230674)
		(width 0.1)
		(layer "B.Cu")
		(net 48)
	)
	(segment
		(start 192.121 120.171)
		(end 192.121 118.872)
		(width 0.182)
		(layer "B.Cu")
		(net 48)
	)
	(segment
		(start 192.121 118.872)
		(end 191.9 118.651)
		(width 0.182)
		(layer "B.Cu")
		(net 48)
	)
	(segment
		(start 190.8 138.7)
		(end 190.910589 138.810589)
		(width 0.4)
		(layer "B.Cu")
		(net 48)
	)
	(segment
		(start 177.77763 146.304)
		(end 177.35163 146.73)
		(width 0.1)
		(layer "In7.Cu")
		(net 48)
	)
	(segment
		(start 177.784206 146.304)
		(end 177.77763 146.304)
		(width 0.1)
		(layer "In7.Cu")
		(net 48)
	)
	(segment
		(start 175.420087 147.399913)
		(end 175.103997 147.399913)
		(width 0.1)
		(layer "In7.Cu")
		(net 48)
	)
	(segment
		(start 176.09 146.73)
		(end 175.420087 147.399913)
		(width 0.1)
		(layer "In7.Cu")
		(net 48)
	)
	(segment
		(start 177.99 146.098206)
		(end 177.784206 146.304)
		(width 0.1)
		(layer "In7.Cu")
		(net 48)
	)
	(segment
		(start 178.25 145.51)
		(end 177.99 145.77)
		(width 0.1)
		(layer "In7.Cu")
		(net 48)
	)
	(segment
		(start 222.425 138.675)
		(end 222.425 138.670996)
		(width 0.4)
		(layer "In7.Cu")
		(net 48)
	)
	(segment
		(start 222.425 138.670996)
		(end 222.873087 138.222909)
		(width 0.4)
		(layer "In7.Cu")
		(net 48)
	)
	(segment
		(start 177.99 145.77)
		(end 177.99 146.098206)
		(width 0.1)
		(layer "In7.Cu")
		(net 48)
	)
	(segment
		(start 177.35163 146.73)
		(end 176.09 146.73)
		(width 0.1)
		(layer "In7.Cu")
		(net 48)
	)
	(segment
		(start 214.8 141.05)
		(end 216.35 141.05)
		(width 0.256)
		(layer "In9.Cu")
		(net 48)
	)
	(segment
		(start 214.15 142.15)
		(end 214.45 141.85)
		(width 0.256)
		(layer "In9.Cu")
		(net 48)
	)
	(segment
		(start 216.85 140.55)
		(end 218.15 140.55)
		(width 0.256)
		(layer "In9.Cu")
		(net 48)
	)
	(segment
		(start 216.35 141.05)
		(end 216.85 140.55)
		(width 0.256)
		(layer "In9.Cu")
		(net 48)
	)
	(segment
		(start 214.45 141.85)
		(end 214.45 141.4)
		(width 0.256)
		(layer "In9.Cu")
		(net 48)
	)
	(segment
		(start 214.45 141.4)
		(end 214.8 141.05)
		(width 0.256)
		(layer "In9.Cu")
		(net 48)
	)
	(segment
		(start 212.55 142.15)
		(end 214.15 142.15)
		(width 0.256)
		(layer "In9.Cu")
		(net 48)
	)
	(segment
		(start 220.15 138.55)
		(end 220.15 134.4)
		(width 0.256)
		(layer "In9.Cu")
		(net 48)
	)
	(segment
		(start 218.15 140.55)
		(end 220.15 138.55)
		(width 0.256)
		(layer "In9.Cu")
		(net 48)
	)
	(segment
		(start 200.098 134.299)
		(end 200.499 134.7)
		(width 0.4)
		(layer "F.Cu")
		(net 49)
	)
	(segment
		(start 199.699 130.701)
		(end 198.899 131.501)
		(width 0.4)
		(layer "F.Cu")
		(net 49)
	)
	(segment
		(start 197.709 130.31)
		(end 198.1 130.701)
		(width 0.4)
		(layer "F.Cu")
		(net 49)
	)
	(segment
		(start 198.1 130.701)
		(end 198.1 130.7)
		(width 0.4)
		(layer "F.Cu")
		(net 49)
	)
	(segment
		(start 200.098 134.299)
		(end 199.699 133.9)
		(width 0.4)
		(layer "F.Cu")
		(net 49)
	)
	(segment
		(start 198.1 130.7)
		(end 198.899 129.901)
		(width 0.4)
		(layer "F.Cu")
		(net 49)
	)
	(segment
		(start 197.709 130.302)
		(end 197.709 130.31)
		(width 0.4)
		(layer "F.Cu")
		(net 49)
	)
	(via
		(at 200.499 134.7)
		(size 0.35)
		(drill 0.15)
		(layers "F.Cu" "B.Cu")
		(remove_unused_layers yes)
		(keep_end_layers yes)
		(zone_layer_connections "In4.Cu")
		(net 49)
	)
	(via
		(at 198.5 130.3)
		(size 0.35)
		(drill 0.15)
		(layers "F.Cu" "B.Cu")
		(remove_unused_layers yes)
		(keep_end_layers yes)
		(zone_layer_connections "In4.Cu")
		(net 49)
	)
	(via
		(at 216.425 127.95)
		(size 0.35)
		(drill 0.15)
		(layers "F.Cu" "B.Cu")
		(remove_unused_layers yes)
		(keep_end_layers yes)
		(zone_layer_connections "In4.Cu")
		(net 49)
	)
	(via
		(at 216.95 127.95)
		(size 0.35)
		(drill 0.15)
		(layers "F.Cu" "B.Cu")
		(remove_unused_layers yes)
		(keep_end_layers yes)
		(zone_layer_connections "In4.Cu")
		(net 49)
	)
	(via
		(at 217.925 127.95)
		(size 0.35)
		(drill 0.15)
		(layers "F.Cu" "B.Cu")
		(remove_unused_layers yes)
		(keep_end_layers yes)
		(zone_layer_connections "In4.Cu")
		(net 49)
	)
	(via
		(at 199.699 130.701)
		(size 0.35)
		(drill 0.15)
		(layers "F.Cu" "B.Cu")
		(remove_unused_layers yes)
		(keep_end_layers yes)
		(zone_layer_connections "In4.Cu")
		(net 49)
	)
	(via
		(at 197.709 130.302)
		(size 0.35)
		(drill 0.15)
		(layers "F.Cu" "B.Cu")
		(remove_unused_layers yes)
		(keep_end_layers yes)
		(zone_layer_connections "In4.Cu")
		(net 49)
	)
	(via
		(at 200.55 136.25)
		(size 0.35)
		(drill 0.15)
		(layers "F.Cu" "B.Cu")
		(remove_unused_layers yes)
		(keep_end_layers yes)
		(zone_layer_connections "In4.Cu")
		(net 49)
	)
	(via
		(at 217.475 127.95)
		(size 0.35)
		(drill 0.15)
		(layers "F.Cu" "B.Cu")
		(remove_unused_layers yes)
		(keep_end_layers yes)
		(zone_layer_connections "In4.Cu")
		(net 49)
	)
	(segment
		(start 199.89 130.37)
		(end 199.4 130.37)
		(width 0.4)
		(layer "B.Cu")
		(net 49)
	)
	(segment
		(start 200.344 134.7)
		(end 199.89 134.246)
		(width 0.4)
		(layer "B.Cu")
		(net 49)
	)
	(segment
		(start 200.027 134.387)
		(end 199.89 134.25)
		(width 0.4)
		(layer "B.Cu")
		(net 49)
	)
	(segment
		(start 201 133.85)
		(end 201 134.199)
		(width 0.4)
		(layer "B.Cu")
		(net 49)
	)
	(segment
		(start 200.812 134.387)
		(end 200.499 134.7)
		(width 0.4)
		(layer "B.Cu")
		(net 49)
	)
	(segment
		(start 218.47 128.05)
		(end 218.37 127.95)
		(width 0.4)
		(layer "B.Cu")
		(net 49)
	)
	(segment
		(start 200.55 134.387)
		(end 200.613 134.387)
		(width 0.4)
		(layer "B.Cu")
		(net 49)
	)
	(segment
		(start 199.4 130.37)
		(end 199.332 130.302)
		(width 0.4)
		(layer "B.Cu")
		(net 49)
	)
	(segment
		(start 218.37 127.95)
		(end 217.475 127.95)
		(width 0.4)
		(layer "B.Cu")
		(net 49)
	)
	(segment
		(start 216.425 127.95)
		(end 216.95 127.95)
		(width 0.4)
		(layer "B.Cu")
		(net 49)
	)
	(segment
		(start 200.613 134.387)
		(end 201.1 133.9)
		(width 0.4)
		(layer "B.Cu")
		(net 49)
	)
	(segment
		(start 197.15 129.599999)
		(end 197.15 129.1)
		(width 0.256)
		(layer "B.Cu")
		(net 49)
	)
	(segment
		(start 199.699 130.701)
		(end 199.4 130.402)
		(width 0.4)
		(layer "B.Cu")
		(net 49)
	)
	(segment
		(start 199.4 130.402)
		(end 199.4 130.37)
		(width 0.4)
		(layer "B.Cu")
		(net 49)
	)
	(segment
		(start 217.475 127.95)
		(end 216.95 127.95)
		(width 0.4)
		(layer "B.Cu")
		(net 49)
	)
	(segment
		(start 200.55 134.387)
		(end 200.027 134.387)
		(width 0.4)
		(layer "B.Cu")
		(net 49)
	)
	(segment
		(start 199.699 130.701)
		(end 199.89 130.51)
		(width 0.4)
		(layer "B.Cu")
		(net 49)
	)
	(segment
		(start 199.89 130.51)
		(end 199.89 130.37)
		(width 0.4)
		(layer "B.Cu")
		(net 49)
	)
	(segment
		(start 197.709 130.302)
		(end 197.709 130.158999)
		(width 0.256)
		(layer "B.Cu")
		(net 49)
	)
	(segment
		(start 200.499 134.7)
		(end 200.344 134.7)
		(width 0.4)
		(layer "B.Cu")
		(net 49)
	)
	(segment
		(start 197.709 130.158999)
		(end 197.15 129.599999)
		(width 0.256)
		(layer "B.Cu")
		(net 49)
	)
	(segment
		(start 199.332 130.302)
		(end 197.709 130.302)
		(width 0.4)
		(layer "B.Cu")
		(net 49)
	)
	(segment
		(start 201 134.199)
		(end 200.812 134.387)
		(width 0.4)
		(layer "B.Cu")
		(net 49)
	)
	(segment
		(start 200.812 134.387)
		(end 200.55 134.387)
		(width 0.4)
		(layer "B.Cu")
		(net 49)
	)
	(segment
		(start 176.32 146.56)
		(end 176.45 146.69)
		(width 0.1)
		(layer "F.Cu")
		(net 50)
	)
	(segment
		(start 221.7298 117.5107)
		(end 221.7298 117.9827)
		(width 0.174)
		(layer "F.Cu")
		(net 50)
	)
	(segment
		(start 193.95 120.65)
		(end 194.67 120.65)
		(width 0.15)
		(layer "F.Cu")
		(net 50)
	)
	(segment
		(start 220.0015 148.352556)
		(end 219.449981 148.904075)
		(width 0.256)
		(layer "F.Cu")
		(net 50)
	)
	(segment
		(start 196.95 130.25)
		(end 197.299 129.901)
		(width 0.4)
		(layer "F.Cu")
		(net 50)
	)
	(segment
		(start 218.673 149.327)
		(end 218.673 150.775)
		(width 0.174)
		(layer "F.Cu")
		(net 50)
	)
	(segment
		(start 193.009 118.151)
		(end 193.511 118.151)
		(width 0.2)
		(layer "F.Cu")
		(net 50)
	)
	(segment
		(start 223.0015 146.9215)
		(end 223.0015 146.617)
		(width 0.174)
		(layer "F.Cu")
		(net 50)
	)
	(segment
		(start 193.97 118.61)
		(end 193.97 119.16)
		(width 0.2)
		(layer "F.Cu")
		(net 50)
	)
	(segment
		(start 214.314499 150.7)
		(end 214.615 150.399499)
		(width 0.174)
		(layer "F.Cu")
		(net 50)
	)
	(segment
		(start 194.85 120.04)
		(end 194.85 120.47)
		(width 0.2)
		(layer "F.Cu")
		(net 50)
	)
	(segment
		(start 214.615 150.399499)
		(end 214.615 149.987)
		(width 0.174)
		(layer "F.Cu")
		(net 50)
	)
	(segment
		(start 192.725 118.435)
		(end 193.009 118.151)
		(width 0.2)
		(layer "F.Cu")
		(net 50)
	)
	(segment
		(start 216.160337 124.506566)
		(end 216.05 124.396229)
		(width 0.174)
		(layer "F.Cu")
		(net 50)
	)
	(segment
		(start 178.103234 147.053234)
		(end 178.006468 147.15)
		(width 0.174)
		(layer "F.Cu")
		(net 50)
	)
	(segment
		(start 214.615 144.797773)
		(end 214.615 144.338)
		(width 0.256)
		(layer "F.Cu")
		(net 50)
	)
	(segment
		(start 213.815 150.7)
		(end 214.314499 150.7)
		(width 0.174)
		(layer "F.Cu")
		(net 50)
	)
	(segment
		(start 210.263 145.136)
		(end 210.263 144.163)
		(width 0.174)
		(layer "F.Cu")
		(net 50)
	)
	(segment
		(start 194.67 120.65)
		(end 194.85 120.47)
		(width 0.15)
		(layer "F.Cu")
		(net 50)
	)
	(segment
		(start 222.7028 117.9827)
		(end 221.7298 117.9827)
		(width 0.2)
		(layer "F.Cu")
		(net 50)
	)
	(segment
		(start 216.05 124.396229)
		(end 216.05 123.875)
		(width 0.174)
		(layer "F.Cu")
		(net 50)
	)
	(segment
		(start 193.97 119.16)
		(end 194.85 120.04)
		(width 0.2)
		(layer "F.Cu")
		(net 50)
	)
	(segment
		(start 199.85 121.43)
		(end 197.788758 121.43)
		(width 0.15)
		(layer "F.Cu")
		(net 50)
	)
	(segment
		(start 220.0015 147.817)
		(end 220.0015 148.352556)
		(width 0.256)
		(layer "F.Cu")
		(net 50)
	)
	(segment
		(start 176.45 146.69)
		(end 176.45 147.15)
		(width 0.1)
		(layer "F.Cu")
		(net 50)
	)
	(segment
		(start 197.788758 121.43)
		(end 197.724379 121.365621)
		(width 0.15)
		(layer "F.Cu")
		(net 50)
	)
	(segment
		(start 210.413 144.163)
		(end 210.700019 144.450019)
		(width 0.174)
		(layer "F.Cu")
		(net 50)
	)
	(segment
		(start 210.263 144.163)
		(end 210.413 144.163)
		(width 0.174)
		(layer "F.Cu")
		(net 50)
	)
	(segment
		(start 214.612521 144.800252)
		(end 214.615 144.797773)
		(width 0.256)
		(layer "F.Cu")
		(net 50)
	)
	(segment
		(start 216.802 146.8)
		(end 217.419999 146.8)
		(width 0.2)
		(layer "F.Cu")
		(net 50)
	)
	(segment
		(start 176.32 146.14)
		(end 176.32 146.56)
		(width 0.1)
		(layer "F.Cu")
		(net 50)
	)
	(segment
		(start 223.375 147.295)
		(end 223.0015 146.9215)
		(width 0.174)
		(layer "F.Cu")
		(net 50)
	)
	(segment
		(start 196.9 130.25)
		(end 196.95 130.25)
		(width 0.4)
		(layer "F.Cu")
		(net 50)
	)
	(segment
		(start 200.098 132.699)
		(end 199.699 132.3)
		(width 0.4)
		(layer "F.Cu")
		(net 50)
	)
	(segment
		(start 193.511 118.151)
		(end 193.97 118.61)
		(width 0.2)
		(layer "F.Cu")
		(net 50)
	)
	(segment
		(start 192.725 118.601)
		(end 192.725 118.435)
		(width 0.2)
		(layer "F.Cu")
		(net 50)
	)
	(segment
		(start 223.525 123.725)
		(end 222.075 123.725)
		(width 0.2)
		(layer "F.Cu")
		(net 50)
	)
	(segment
		(start 178.006468 147.15)
		(end 177.45 147.15)
		(width 0.174)
		(layer "F.Cu")
		(net 50)
	)
	(via
		(at 197.299 128.3)
		(size 0.35)
		(drill 0.15)
		(layers "F.Cu" "B.Cu")
		(remove_unused_layers yes)
		(keep_end_layers yes)
		(zone_layer_connections "In6.Cu")
		(net 50)
	)
	(via
		(at 220.1 133.25)
		(size 0.35)
		(drill 0.15)
		(layers "F.Cu" "B.Cu")
		(remove_unused_layers yes)
		(keep_end_layers yes)
		(zone_layer_connections "In6.Cu")
		(net 50)
	)
	(via
		(at 175.093252 137.933237)
		(size 0.35)
		(drill 0.15)
		(layers "F.Cu" "B.Cu")
		(remove_unused_layers yes)
		(keep_end_layers yes)
		(free yes)
		(zone_layer_connections "In2.Cu" "In6.Cu")
		(net 50)
	)
	(via
		(at 222.075 123.725)
		(size 0.35)
		(drill 0.15)
		(layers "F.Cu" "B.Cu")
		(remove_unused_layers yes)
		(keep_end_layers yes)
		(zone_layer_connections "In6.Cu")
		(net 50)
	)
	(via
		(at 181.601 119.215)
		(size 0.35)
		(drill 0.15)
		(layers "F.Cu" "B.Cu")
		(remove_unused_layers yes)
		(keep_end_layers yes)
		(zone_layer_connections "In6.Cu")
		(net 50)
	)
	(via
		(at 223.375 147.295)
		(size 0.35)
		(drill 0.15)
		(layers "F.Cu" "B.Cu")
		(remove_unused_layers yes)
		(keep_end_layers yes)
		(zone_layer_connections "In6.Cu")
		(net 50)
	)
	(via
		(at 215.9425 132.447)
		(size 0.35)
		(drill 0.15)
		(layers "F.Cu" "B.Cu")
		(remove_unused_layers yes)
		(keep_end_layers yes)
		(zone_layer_connections "In6.Cu")
		(net 50)
	)
	(via
		(at 223.95 139.95)
		(size 0.35)
		(drill 0.15)
		(layers "F.Cu" "B.Cu")
		(remove_unused_layers yes)
		(keep_end_layers yes)
		(zone_layer_connections "In6.Cu")
		(net 50)
	)
	(via
		(at 218.625 145.945)
		(size 0.35)
		(drill 0.15)
		(layers "F.Cu" "B.Cu")
		(remove_unused_layers yes)
		(keep_end_layers yes)
		(zone_layer_connections "In6.Cu")
		(net 50)
	)
	(via
		(at 223.5 139.95)
		(size 0.35)
		(drill 0.15)
		(layers "F.Cu" "B.Cu")
		(remove_unused_layers yes)
		(keep_end_layers yes)
		(zone_layer_connections "In6.Cu")
		(net 50)
	)
	(via
		(at 222.32 125.475)
		(size 0.35)
		(drill 0.15)
		(layers "F.Cu" "B.Cu")
		(remove_unused_layers yes)
		(keep_end_layers yes)
		(zone_layer_connections "In6.Cu")
		(net 50)
	)
	(via
		(at 218.673 149.327)
		(size 0.35)
		(drill 0.15)
		(layers "F.Cu" "B.Cu")
		(remove_unused_layers yes)
		(keep_end_layers yes)
		(zone_layer_connections "In6.Cu")
		(net 50)
	)
	(via
		(at 177.9 138.85)
		(size 0.35)
		(drill 0.15)
		(layers "F.Cu" "B.Cu")
		(remove_unused_layers yes)
		(keep_end_layers yes)
		(free yes)
		(zone_layer_connections "In2.Cu" "In6.Cu")
		(net 50)
	)
	(via
		(at 218.42 117.87)
		(size 0.35)
		(drill 0.15)
		(layers "F.Cu" "B.Cu")
		(remove_unused_layers yes)
		(keep_end_layers yes)
		(zone_layer_connections "In6.Cu")
		(net 50)
	)
	(via
		(at 223.95 137.35)
		(size 0.35)
		(drill 0.15)
		(layers "F.Cu" "B.Cu")
		(remove_unused_layers yes)
		(keep_end_layers yes)
		(zone_layer_connections "In6.Cu")
		(net 50)
	)
	(via
		(at 213.4435 130.95)
		(size 0.35)
		(drill 0.15)
		(layers "F.Cu" "B.Cu")
		(remove_unused_layers yes)
		(keep_end_layers yes)
		(zone_layer_connections "In6.Cu")
		(net 50)
	)
	(via
		(at 223.5 137.35)
		(size 0.35)
		(drill 0.15)
		(layers "F.Cu" "B.Cu")
		(remove_unused_layers yes)
		(keep_end_layers yes)
		(zone_layer_connections "In6.Cu")
		(net 50)
	)
	(via
		(at 225.2 123)
		(size 0.35)
		(drill 0.15)
		(layers "F.Cu" "B.Cu")
		(remove_unused_layers yes)
		(keep_end_layers yes)
		(zone_layer_connections "In6.Cu")
		(net 50)
	)
	(via
		(at 176.32 146.14)
		(size 0.35)
		(drill 0.15)
		(layers "F.Cu" "B.Cu")
		(remove_unused_layers yes)
		(keep_end_layers yes)
		(zone_layer_connections "In2.Cu" "In6.Cu")
		(net 50)
	)
	(via
		(at 202.9 129.1)
		(size 0.35)
		(drill 0.15)
		(layers "F.Cu" "B.Cu")
		(remove_unused_layers yes)
		(keep_end_layers yes)
		(zone_layer_connections "In6.Cu")
		(net 50)
	)
	(via
		(at 219.6 128.7)
		(size 0.35)
		(drill 0.15)
		(layers "F.Cu" "B.Cu")
		(remove_unused_layers yes)
		(keep_end_layers yes)
		(zone_layer_connections "In6.Cu")
		(net 50)
	)
	(via
		(at 186.29 140.166)
		(size 0.35)
		(drill 0.15)
		(layers "F.Cu" "B.Cu")
		(remove_unused_layers yes)
		(keep_end_layers yes)
		(zone_layer_connections "In2.Cu")
		(net 50)
	)
	(via
		(at 222.8 119.9)
		(size 0.35)
		(drill 0.15)
		(layers "F.Cu" "B.Cu")
		(remove_unused_layers yes)
		(keep_end_layers yes)
		(zone_layer_connections "In6.Cu")
		(net 50)
	)
	(via
		(at 213.815 150.7)
		(size 0.35)
		(drill 0.15)
		(layers "F.Cu" "B.Cu")
		(remove_unused_layers yes)
		(keep_end_layers yes)
		(zone_layer_connections "In6.Cu")
		(net 50)
	)
	(via
		(at 175.445 138.637502)
		(size 0.35)
		(drill 0.15)
		(layers "F.Cu" "B.Cu")
		(remove_unused_layers yes)
		(keep_end_layers yes)
		(free yes)
		(zone_layer_connections "In2.Cu" "In6.Cu")
		(net 50)
	)
	(via
		(at 213.51 123.6)
		(size 0.35)
		(drill 0.15)
		(layers "F.Cu" "B.Cu")
		(remove_unused_layers yes)
		(keep_end_layers yes)
		(zone_layer_connections "In6.Cu")
		(net 50)
	)
	(via
		(at 178.103234 147.053234)
		(size 0.35)
		(drill 0.15)
		(layers "F.Cu" "B.Cu")
		(remove_unused_layers yes)
		(keep_end_layers yes)
		(zone_layer_connections "In2.Cu" "In6.Cu")
		(net 50)
	)
	(via
		(at 219.6 131.8)
		(size 0.35)
		(drill 0.15)
		(layers "F.Cu" "B.Cu")
		(remove_unused_layers yes)
		(keep_end_layers yes)
		(zone_layer_connections "In6.Cu")
		(net 50)
	)
	(via
		(at 220 141.84)
		(size 0.35)
		(drill 0.15)
		(layers "F.Cu" "B.Cu")
		(remove_unused_layers yes)
		(keep_end_layers yes)
		(zone_layer_connections "In6.Cu")
		(net 50)
	)
	(via
		(at 200.098 132.699)
		(size 0.35)
		(drill 0.15)
		(layers "F.Cu" "B.Cu")
		(remove_unused_layers yes)
		(keep_end_layers yes)
		(zone_layer_connections)
		(net 50)
	)
	(via
		(at 193.1 118.151)
		(size 0.35)
		(drill 0.15)
		(layers "F.Cu" "B.Cu")
		(remove_unused_layers yes)
		(keep_end_layers yes)
		(zone_layer_connections "In6.Cu")
		(net 50)
	)
	(via
		(at 215.982999 151.8215)
		(size 0.35)
		(drill 0.15)
		(layers "F.Cu" "B.Cu")
		(remove_unused_layers yes)
		(keep_end_layers yes)
		(zone_layer_connections "In6.Cu")
		(net 50)
	)
	(via
		(at 186.46 122.33)
		(size 0.35)
		(drill 0.15)
		(layers "F.Cu" "B.Cu")
		(remove_unused_layers yes)
		(keep_end_layers yes)
		(zone_layer_connections "In6.Cu")
		(net 50)
	)
	(via
		(at 219.6 132.7)
		(size 0.35)
		(drill 0.15)
		(layers "F.Cu" "B.Cu")
		(remove_unused_layers yes)
		(keep_end_layers yes)
		(zone_layer_connections "In6.Cu")
		(net 50)
	)
	(via
		(at 214.612521 144.800252)
		(size 0.35)
		(drill 0.15)
		(layers "F.Cu" "B.Cu")
		(remove_unused_layers yes)
		(keep_end_layers yes)
		(zone_layer_connections "In6.Cu")
		(net 50)
	)
	(via
		(at 175.795715 137.933051)
		(size 0.35)
		(drill 0.15)
		(layers "F.Cu" "B.Cu")
		(remove_unused_layers yes)
		(keep_end_layers yes)
		(free yes)
		(zone_layer_connections "In2.Cu" "In6.Cu")
		(net 50)
	)
	(via
		(at 221.7298 117.5107)
		(size 0.35)
		(drill 0.15)
		(layers "F.Cu" "B.Cu")
		(remove_unused_layers yes)
		(keep_end_layers yes)
		(zone_layer_connections "In6.Cu")
		(net 50)
	)
	(via
		(at 192.725 118.601)
		(size 0.35)
		(drill 0.15)
		(layers "F.Cu" "B.Cu")
		(remove_unused_layers yes)
		(keep_end_layers yes)
		(zone_layer_connections "In6.Cu")
		(net 50)
	)
	(via
		(at 211.3 153.575)
		(size 0.35)
		(drill 0.15)
		(layers "F.Cu" "B.Cu")
		(remove_unused_layers yes)
		(keep_end_layers yes)
		(zone_layer_connections "In6.Cu")
		(net 50)
	)
	(via
		(at 219.5995 129.5995)
		(size 0.35)
		(drill 0.15)
		(layers "F.Cu" "B.Cu")
		(remove_unused_layers yes)
		(keep_end_layers yes)
		(zone_layer_connections "In6.Cu")
		(net 50)
	)
	(via
		(at 174.995 138.437502)
		(size 0.35)
		(drill 0.15)
		(layers "F.Cu" "B.Cu")
		(remove_unused_layers yes)
		(keep_end_layers yes)
		(free yes)
		(zone_layer_connections "In2.Cu" "In6.Cu")
		(net 50)
	)
	(via
		(at 212.75 120.15)
		(size 0.35)
		(drill 0.15)
		(layers "F.Cu" "B.Cu")
		(remove_unused_layers yes)
		(keep_end_layers yes)
		(zone_layer_connections)
		(net 50)
	)
	(via
		(at 197.724379 121.365621)
		(size 0.35)
		(drill 0.15)
		(layers "F.Cu" "B.Cu")
		(remove_unused_layers yes)
		(keep_end_layers yes)
		(zone_layer_connections "In6.Cu")
		(net 50)
	)
	(via
		(at 221.48 141.81)
		(size 0.35)
		(drill 0.15)
		(layers "F.Cu" "B.Cu")
		(remove_unused_layers yes)
		(keep_end_layers yes)
		(zone_layer_connections "In6.Cu")
		(net 50)
	)
	(via
		(at 209.35 136.525)
		(size 0.35)
		(drill 0.15)
		(layers "F.Cu" "B.Cu")
		(remove_unused_layers yes)
		(keep_end_layers yes)
		(zone_layer_connections "In6.Cu")
		(net 50)
	)
	(via
		(at 218.36 123.01)
		(size 0.35)
		(drill 0.15)
		(layers "F.Cu" "B.Cu")
		(remove_unused_layers yes)
		(keep_end_layers yes)
		(zone_layer_connections "In6.Cu")
		(net 50)
	)
	(via
		(at 216.55 116.45)
		(size 0.35)
		(drill 0.15)
		(layers "F.Cu" "B.Cu")
		(remove_unused_layers yes)
		(keep_end_layers yes)
		(zone_layer_connections "In6.Cu")
		(net 50)
	)
	(via
		(at 196.9 130.25)
		(size 0.35)
		(drill 0.15)
		(layers "F.Cu" "B.Cu")
		(remove_unused_layers yes)
		(keep_end_layers yes)
		(zone_layer_connections "In6.Cu")
		(net 50)
	)
	(via
		(at 175.895 138.437502)
		(size 0.35)
		(drill 0.15)
		(layers "F.Cu" "B.Cu")
		(remove_unused_layers yes)
		(keep_end_layers yes)
		(free yes)
		(zone_layer_connections "In2.Cu" "In6.Cu")
		(net 50)
	)
	(via
		(at 213.9435 130.45)
		(size 0.35)
		(drill 0.15)
		(layers "F.Cu" "B.Cu")
		(remove_unused_layers yes)
		(keep_end_layers yes)
		(zone_layer_connections "In6.Cu")
		(net 50)
	)
	(via
		(at 223.89658 132.529634)
		(size 0.35)
		(drill 0.15)
		(layers "F.Cu" "B.Cu")
		(remove_unused_layers yes)
		(keep_end_layers yes)
		(zone_layer_connections "In6.Cu")
		(net 50)
	)
	(via
		(at 175.071057 138.888738)
		(size 0.35)
		(drill 0.15)
		(layers "F.Cu" "B.Cu")
		(remove_unused_layers yes)
		(keep_end_layers yes)
		(free yes)
		(zone_layer_connections "In2.Cu" "In6.Cu")
		(net 50)
	)
	(via
		(at 220.0995 131.1)
		(size 0.35)
		(drill 0.15)
		(layers "F.Cu" "B.Cu")
		(remove_unused_layers yes)
		(keep_end_layers yes)
		(zone_layer_connections "In6.Cu")
		(net 50)
	)
	(via
		(at 192.48 142.65)
		(size 0.35)
		(drill 0.15)
		(layers "F.Cu" "B.Cu")
		(remove_unused_layers yes)
		(keep_end_layers yes)
		(zone_layer_connections "In2.Cu")
		(net 50)
	)
	(via
		(at 192.35 118.151)
		(size 0.35)
		(drill 0.15)
		(layers "F.Cu" "B.Cu")
		(remove_unused_layers yes)
		(keep_end_layers yes)
		(zone_layer_connections "In6.Cu")
		(net 50)
	)
	(via
		(at 216.160337 124.506566)
		(size 0.35)
		(drill 0.15)
		(layers "F.Cu" "B.Cu")
		(remove_unused_layers yes)
		(keep_end_layers yes)
		(zone_layer_connections "In6.Cu")
		(net 50)
	)
	(via
		(at 220.0995 130.0995)
		(size 0.35)
		(drill 0.15)
		(layers "F.Cu" "B.Cu")
		(remove_unused_layers yes)
		(keep_end_layers yes)
		(zone_layer_connections "In6.Cu")
		(net 50)
	)
	(via
		(at 215.4405 132.949)
		(size 0.35)
		(drill 0.15)
		(layers "F.Cu" "B.Cu")
		(remove_unused_layers yes)
		(keep_end_layers yes)
		(zone_layer_connections "In6.Cu")
		(net 50)
	)
	(via
		(at 175.445 138.187502)
		(size 0.35)
		(drill 0.15)
		(layers "F.Cu" "B.Cu")
		(remove_unused_layers yes)
		(keep_end_layers yes)
		(free yes)
		(zone_layer_connections "In2.Cu" "In6.Cu")
		(net 50)
	)
	(via
		(at 192.56 144.45)
		(size 0.35)
		(drill 0.15)
		(layers "F.Cu" "B.Cu")
		(remove_unused_layers yes)
		(keep_end_layers yes)
		(zone_layer_connections "In2.Cu")
		(net 50)
	)
	(via
		(at 175.8 138.8875)
		(size 0.35)
		(drill 0.15)
		(layers "F.Cu" "B.Cu")
		(remove_unused_layers yes)
		(keep_end_layers yes)
		(free yes)
		(zone_layer_connections "In2.Cu" "In6.Cu")
		(net 50)
	)
	(via
		(at 213.265 146.8)
		(size 0.35)
		(drill 0.15)
		(layers "F.Cu" "B.Cu")
		(remove_unused_layers yes)
		(keep_end_layers yes)
		(zone_layer_connections "In6.Cu")
		(net 50)
	)
	(via
		(at 217.419999 146.8)
		(size 0.35)
		(drill 0.15)
		(layers "F.Cu" "B.Cu")
		(remove_unused_layers yes)
		(keep_end_layers yes)
		(zone_layer_connections "In6.Cu")
		(net 50)
	)
	(via
		(at 210.700019 144.450019)
		(size 0.35)
		(drill 0.15)
		(layers "F.Cu" "B.Cu")
		(remove_unused_layers yes)
		(keep_end_layers yes)
		(zone_layer_connections "In6.Cu")
		(net 50)
	)
	(via
		(at 223.286013 141.767289)
		(size 0.35)
		(drill 0.15)
		(layers "F.Cu" "B.Cu")
		(remove_unused_layers yes)
		(keep_end_layers yes)
		(zone_layer_connections "In6.Cu")
		(net 50)
	)
	(via
		(at 212.5335 151.819501)
		(size 0.35)
		(drill 0.15)
		(layers "F.Cu" "B.Cu")
		(remove_unused_layers yes)
		(keep_end_layers yes)
		(zone_layer_connections "In6.Cu")
		(net 50)
	)
	(via
		(at 219.449981 148.904075)
		(size 0.35)
		(drill 0.15)
		(layers "F.Cu" "B.Cu")
		(remove_unused_layers yes)
		(keep_end_layers yes)
		(zone_layer_connections "In6.Cu")
		(net 50)
	)
	(segment
		(start 176.95 138.9)
		(end 176.95 138.4375)
		(width 0.1)
		(layer "B.Cu")
		(net 50)
	)
	(segment
		(start 223.5 139.95)
		(end 223.95 139.95)
		(width 0.256)
		(layer "B.Cu")
		(net 50)
	)
	(segment
		(start 211.3 153.575)
		(end 211.175 153.45)
		(width 0.174)
		(layer "B.Cu")
		(net 50)
	)
	(segment
		(start 223.9 132.533054)
		(end 223.89658 132.529634)
		(width 0.256)
		(layer "B.Cu")
		(net 50)
	)
	(segment
		(start 209.35 136.525)
		(end 209.175 136.35)
		(width 0.174)
		(layer "B.Cu")
		(net 50)
	)
	(segment
		(start 221.7175 144.415)
		(end 223.015 144.415)
		(width 0.15)
		(layer "B.Cu")
		(net 50)
	)
	(segment
		(start 224 141.86)
		(end 224.15 142.01)
		(width 0.15)
		(layer "B.Cu")
		(net 50)
	)
	(segment
		(start 192.75 142.65)
		(end 192.48 142.65)
		(width 0.15)
		(layer "B.Cu")
		(net 50)
	)
	(segment
		(start 218.625 145.565)
		(end 218.625 145.945)
		(width 0.4)
		(layer "B.Cu")
		(net 50)
	)
	(segment
		(start 219.5995 129.5995)
		(end 220.0995 130.0995)
		(width 0.256)
		(layer "B.Cu")
		(net 50)
	)
	(segment
		(start 222.4245 136.74)
		(end 222.4245 137.1245)
		(width 0.256)
		(layer "B.Cu")
		(net 50)
	)
	(segment
		(start 208.7 136.38)
		(end 208.7 137.3)
		(width 0.174)
		(layer "B.Cu")
		(net 50)
	)
	(segment
		(start 177.65 146.866)
		(end 177.916 146.866)
		(width 0.174)
		(layer "B.Cu")
		(net 50)
	)
	(segment
		(start 222.4245 137.1245)
		(end 222.65 137.35)
		(width 0.256)
		(layer "B.Cu")
		(net 50)
	)
	(segment
		(start 177.916 146.866)
		(end 178.103234 147.053234)
		(width 0.174)
		(layer "B.Cu")
		(net 50)
	)
	(segment
		(start 215.545 123.738)
		(end 216.160337 124.353337)
		(width 0.174)
		(layer "B.Cu")
		(net 50)
	)
	(segment
		(start 214.6765 132.697)
		(end 215.6765 132.697)
		(width 0.174)
		(layer "B.Cu")
		(net 50)
	)
	(segment
		(start 186.8 121.99)
		(end 186.8 121.33)
		(width 0.15)
		(layer "B.Cu")
		(net 50)
	)
	(segment
		(start 208.73 133.35)
		(end 208.73 135.35)
		(width 0.174)
		(layer "B.Cu")
		(net 50)
	)
	(segment
		(start 222.9245 139.9945)
		(end 223.04 140.11)
		(width 0.256)
		(layer "B.Cu")
		(net 50)
	)
	(segment
		(start 216.160337 124.353337)
		(end 216.160337 124.506566)
		(width 0.174)
		(layer "B.Cu")
		(net 50)
	)
	(segment
		(start 213.199 147.689)
		(end 212.965 147.455)
		(width 0.2)
		(layer "B.Cu")
		(net 50)
	)
	(segment
		(start 186.286 140.17)
		(end 186.29 140.166)
		(width 0.125)
		(layer "B.Cu")
		(net 50)
	)
	(segment
		(start 219.5995 128.7005)
		(end 219.6 128.7)
		(width 0.256)
		(layer "B.Cu")
		(net 50)
	)
	(segment
		(start 221.7298 117.5107)
		(end 221.8968 117.3437)
		(width 0.174)
		(layer "B.Cu")
		(net 50)
	)
	(segment
		(start 215.6765 132.697)
		(end 215.6925 132.681)
		(width 0.174)
		(layer "B.Cu")
		(net 50)
	)
	(segment
		(start 186.46 122.33)
		(end 186.8 121.99)
		(width 0.15)
		(layer "B.Cu")
		(net 50)
	)
	(segment
		(start 220.1 133.25)
		(end 220.1 133.729)
		(width 0.256)
		(layer "B.Cu")
		(net 50)
	)
	(segment
		(start 222.505 123.725)
		(end 222.75 123.48)
		(width 0.2)
		(layer "B.Cu")
		(net 50)
	)
	(segment
		(start 208.73 136.35)
		(end 208.7 136.38)
		(width 0.174)
		(layer "B.Cu")
		(net 50)
	)
	(segment
		(start 215.06 124.035)
		(end 215.361 123.734)
		(width 0.15)
		(layer "B.Cu")
		(net 50)
	)
	(segment
		(start 219.361 149.327)
		(end 219.6 149.566)
		(width 0.174)
		(layer "B.Cu")
		(net 50)
	)
	(segment
		(start 213.6925 130.713)
		(end 214.6925 130.713)
		(width 0.174)
		(layer "B.Cu")
		(net 50)
	)
	(segment
		(start 187.47 140.4)
		(end 187.15 140.4)
		(width 0.174)
		(layer "B.Cu")
		(net 50)
	)
	(segment
		(start 222.075 123.725)
		(end 222.505 123.725)
		(width 0.2)
		(layer "B.Cu")
		(net 50)
	)
	(segment
		(start 214.742561 147.689)
		(end 215.133561 148.08)
		(width 0.2)
		(layer "B.Cu")
		(net 50)
	)
	(segment
		(start 213.377 118.754)
		(end 213.377 119.754)
		(width 0.174)
		(layer "B.Cu")
		(net 50)
	)
	(segment
		(start 217.3275 145.3675)
		(end 216.845 145.85)
		(width 0.15)
		(layer "B.Cu")
		(net 50)
	)
	(segment
		(start 212.5335 151.819501)
		(end 212.5335 152.6465)
		(width 0.15)
		(layer "B.Cu")
		(net 50)
	)
	(segment
		(start 219.6 131.8)
		(end 219.6 132.25)
		(width 0.256)
		(layer "B.Cu")
		(net 50)
	)
	(segment
		(start 222.35 125.475)
		(end 222.45 125.475)
		(width 0.2)
		(layer "B.Cu")
		(net 50)
	)
	(segment
		(start 222.4245 139.615)
		(end 222.4245 139.9995)
		(width 0.256)
		(layer "B.Cu")
		(net 50)
	)
	(segment
		(start 213.51 123.6)
		(end 212.576 124.534)
		(width 0.174)
		(layer "B.Cu")
		(net 50)
	)
	(segment
		(start 214.742561 147.689)
		(end 213.199 147.689)
		(width 0.2)
		(layer "B.Cu")
		(net 50)
	)
	(segment
		(start 218.77 145.42)
		(end 218.625 145.565)
		(width 0.4)
		(layer "B.Cu")
		(net 50)
	)
	(segment
		(start 222.535 140.11)
		(end 223.04 140.11)
		(width 0.256)
		(layer "B.Cu")
		(net 50)
	)
	(segment
		(start 177.9 138.85)
		(end 177.7 139.05)
		(width 0.1)
		(layer "B.Cu")
		(net 50)
	)
	(segment
		(start 216.329 117.08)
		(end 217.35 117.08)
		(width 0.15)
		(layer "B.Cu")
		(net 50)
	)
	(segment
		(start 222.4245 139.9995)
		(end 222.535 140.11)
		(width 0.256)
		(layer "B.Cu")
		(net 50)
	)
	(segment
		(start 222.925 137.35)
		(end 223.5 137.35)
		(width 0.256)
		(layer "B.Cu")
		(net 50)
	)
	(segment
		(start 192.922 118.798)
		(end 192.725 118.601)
		(width 0.182)
		(layer "B.Cu")
		(net 50)
	)
	(segment
		(start 212.965 147.1)
		(end 213.265 146.8)
		(width 0.2)
		(layer "B.Cu")
		(net 50)
	)
	(segment
		(start 213.815 150.7)
		(end 213.365 150.7)
		(width 0.174)
		(layer "B.Cu")
		(net 50)
	)
	(segment
		(start 192.44 145.3)
		(end 192.44 144.57)
		(width 0.2)
		(layer "B.Cu")
		(net 50)
	)
	(segment
		(start 192.44 144.57)
		(end 192.56 144.45)
		(width 0.2)
		(layer "B.Cu")
		(net 50)
	)
	(segment
		(start 216.55 116.859)
		(end 216.329 117.08)
		(width 0.15)
		(layer "B.Cu")
		(net 50)
	)
	(segment
		(start 210.9 144.17)
		(end 211.965 144.17)
		(width 0.2)
		(layer "B.Cu")
		(net 50)
	)
	(segment
		(start 192.522 120.171)
		(end 192.522 118.804)
		(width 0.182)
		(layer "B.Cu")
		(net 50)
	)
	(segment
		(start 223.9 146.815)
		(end 223.855 146.815)
		(width 0.4)
		(layer "B.Cu")
		(net 50)
	)
	(segment
		(start 213.51 123.6)
		(end 213.648 123.738)
		(width 0.174)
		(layer "B.Cu")
		(net 50)
	)
	(segment
		(start 218.42 117.87)
		(end 218.16 117.87)
		(width 0.15)
		(layer "B.Cu")
		(net 50)
	)
	(segment
		(start 219.6 132.75)
		(end 219.6 132.25)
		(width 0.256)
		(layer "B.Cu")
		(net 50)
	)
	(segment
		(start 222.65 137.35)
		(end 222.925 137.35)
		(width 0.256)
		(layer "B.Cu")
		(net 50)
	)
	(segment
		(start 212.75 120.15)
		(end 212.981 120.15)
		(width 0.174)
		(layer "B.Cu")
		(net 50)
	)
	(segment
		(start 218.766817 145.416817)
		(end 218.77 145.42)
		(width 0.4)
		(layer "B.Cu")
		(net 50)
	)
	(segment
		(start 203.05 129.25)
		(end 202.9 129.1)
		(width 0.256)
		(layer "B.Cu")
		(net 50)
	)
	(segment
		(start 223.9 133.275)
		(end 223.9 132.533054)
		(width 0.256)
		(layer "B.Cu")
		(net 50)
	)
	(segment
		(start 187.85 121.33)
		(end 186.8 121.33)
		(width 0.15)
		(layer "B.Cu")
		(net 50)
	)
	(segment
		(start 209.175 136.35)
		(end 208.73 136.35)
		(width 0.174)
		(layer "B.Cu")
		(net 50)
	)
	(segment
		(start 215.85 125.39)
		(end 215.3 125.39)
		(width 0.15)
		(layer "B.Cu")
		(net 50)
	)
	(segment
		(start 222.9 146.818052)
		(end 223.375974 147.294026)
		(width 0.4)
		(layer "B.Cu")
		(net 50)
	)
	(segment
		(start 221.7175 144.415)
		(end 220.7175 144.415)
		(width 0.256)
		(layer "B.Cu")
		(net 50)
	)
	(segment
		(start 197.299 127.674)
		(end 197.299 128.3)
		(width 0.4)
		(layer "B.Cu")
		(net 50)
	)
	(segment
		(start 216.469411 126.009411)
		(end 215.85 125.39)
		(width 0.15)
		(layer "B.Cu")
		(net 50)
	)
	(segment
		(start 218.795 145.375)
		(end 218.797 145.377)
		(width 0.174)
		(layer "B.Cu")
		(net 50)
	)
	(segment
		(start 215.133561 148.08)
		(end 215.39 148.08)
		(width 0.2)
		(layer "B.Cu")
		(net 50)
	)
	(segment
		(start 186.916 140.166)
		(end 186.25 140.166)
		(width 0.174)
		(layer "B.Cu")
		(net 50)
	)
	(segment
		(start 218.725 145.3675)
		(end 219.765 145.3675)
		(width 0.256)
		(layer "B.Cu")
		(net 50)
	)
	(segment
		(start 218.673 149.327)
		(end 219.361 149.327)
		(width 0.174)
		(layer "B.Cu")
		(net 50)
	)
	(segment
		(start 219.765 145.3675)
		(end 220.7175 144.415)
		(width 0.256)
		(layer "B.Cu")
		(net 50)
	)
	(segment
		(start 208.73 136.35)
		(end 208.73 135.35)
		(width 0.174)
		(layer "B.Cu")
		(net 50)
	)
	(segment
		(start 192.522 118.804)
		(end 192.725 118.601)
		(width 0.182)
		(layer "B.Cu")
		(net 50)
	)
	(segment
		(start 215.89 148.58)
		(end 215.39 148.08)
		(width 0.2)
		(layer "B.Cu")
		(net 50)
	)
	(segment
		(start 215.89 147.58)
		(end 215.39 148.08)
		(width 0.2)
		(layer "B.Cu")
		(net 50)
	)
	(segment
		(start 212.931 150.266)
		(end 212.931 150.05)
		(width 0.174)
		(layer "B.Cu")
		(net 50)
	)
	(segment
		(start 216.849 146.229001)
		(end 217.419999 146.8)
		(width 0.174)
		(layer "B.Cu")
		(net 50)
	)
	(segment
		(start 212.5335 152.6465)
		(end 212.18 153)
		(width 0.15)
		(layer "B.Cu")
		(net 50)
	)
	(segment
		(start 212.965 147.455)
		(end 212.965 147.1)
		(width 0.2)
		(layer "B.Cu")
		(net 50)
	)
	(segment
		(start 215.982999 152.647001)
		(end 215.66 152.97)
		(width 0.15)
		(layer "B.Cu")
		(net 50)
	)
	(segment
		(start 177.7 139.05)
		(end 177.1 139.05)
		(width 0.1)
		(layer "B.Cu")
		(net 50)
	)
	(segment
		(start 222.9245 137.3495)
		(end 222.925 137.35)
		(width 0.256)
		(layer "B.Cu")
		(net 50)
	)
	(segment
		(start 223.04 140.11)
		(end 223.34 140.11)
		(width 0.256)
		(layer "B.Cu")
		(net 50)
	)
	(segment
		(start 215.3 125.39)
		(end 215.06 125.15)
		(width 0.15)
		(layer "B.Cu")
		(net 50)
	)
	(segment
		(start 203.53 129.25)
		(end 203.05 129.25)
		(width 0.256)
		(layer "B.Cu")
		(net 50)
	)
	(segment
		(start 212.981 120.15)
		(end 213.377 119.754)
		(width 0.174)
		(layer "B.Cu")
		(net 50)
	)
	(segment
		(start 223.015 144.415)
		(end 223.06 144.46)
		(width 0.15)
		(layer "B.Cu")
		(net 50)
	)
	(segment
		(start 192.922 120.171)
		(end 192.922 118.798)
		(width 0.182)
		(layer "B.Cu")
		(net 50)
	)
	(segment
		(start 213.648 123.738)
		(end 215.545 123.738)
		(width 0.174)
		(layer "B.Cu")
		(net 50)
	)
	(segment
		(start 187.15 140.4)
		(end 186.916 140.166)
		(width 0.174)
		(layer "B.Cu")
		(net 50)
	)
	(segment
		(start 219.5995 129.16)
		(end 219.5995 128.7005)
		(width 0.256)
		(layer "B.Cu")
		(net 50)
	)
	(segment
		(start 214.6925 130.713)
		(end 214.7085 130.697)
		(width 0.174)
		(layer "B.Cu")
		(net 50)
	)
	(segment
		(start 186.25 140.17)
		(end 186.286 140.17)
		(width 0.125)
		(layer "B.Cu")
		(net 50)
	)
	(segment
		(start 222.9 146.815)
		(end 222.9 146.818052)
		(width 0.4)
		(layer "B.Cu")
		(net 50)
	)
	(segment
		(start 218.725 145.3675)
		(end 217.3275 145.3675)
		(width 0.15)
		(layer "B.Cu")
		(net 50)
	)
	(segment
		(start 219.5995 129.16)
		(end 219.5995 129.5995)
		(width 0.256)
		(layer "B.Cu")
		(net 50)
	)
	(segment
		(start 218.16 117.87)
		(end 217.36 117.07)
		(width 0.15)
		(layer "B.Cu")
		(net 50)
	)
	(segment
		(start 215.06 125.15)
		(end 215.06 124.035)
		(width 0.15)
		(layer "B.Cu")
		(net 50)
	)
	(segment
		(start 216.55 116.41)
		(end 216.55 116.859)
		(width 0.15)
		(layer "B.Cu")
		(net 50)
	)
	(segment
		(start 222.45 125.475)
		(end 223.4 126.425)
		(width 0.2)
		(layer "B.Cu")
		(net 50)
	)
	(segment
		(start 217.600589 126.009411)
		(end 216.469411 126.009411)
		(width 0.15)
		(layer "B.Cu")
		(net 50)
	)
	(segment
		(start 213.365 150.7)
		(end 212.931 150.266)
		(width 0.174)
		(layer "B.Cu")
		(net 50)
	)
	(segment
		(start 223.855 146.815)
		(end 223.375974 147.294026)
		(width 0.4)
		(layer "B.Cu")
		(net 50)
	)
	(segment
		(start 217.35 117.08)
		(end 217.36 117.07)
		(width 0.15)
		(layer "B.Cu")
		(net 50)
	)
	(segment
		(start 215.329 117.08)
		(end 216.329 117.08)
		(width 0.15)
		(layer "B.Cu")
		(net 50)
	)
	(segment
		(start 212.576 124.534)
		(end 212.576 124.754)
		(width 0.174)
		(layer "B.Cu")
		(net 50)
	)
	(segment
		(start 220.1 133.25)
		(end 219.6 132.75)
		(width 0.256)
		(layer "B.Cu")
		(net 50)
	)
	(segment
		(start 223.5 137.35)
		(end 223.95 137.35)
		(width 0.256)
		(layer "B.Cu")
		(net 50)
	)
	(segment
		(start 222.9245 136.74)
		(end 222.9245 137.3495)
		(width 0.256)
		(layer "B.Cu")
		(net 50)
	)
	(segment
		(start 177.1 139.05)
		(end 176.95 138.9)
		(width 0.1)
		(layer "B.Cu")
		(net 50)
	)
	(segment
		(start 223.34 140.11)
		(end 223.5 139.95)
		(width 0.256)
		(layer "B.Cu")
		(net 50)
	)
	(segment
		(start 223.22 141.86)
		(end 224 141.86)
		(width 0.15)
		(layer "B.Cu")
		(net 50)
	)
	(segment
		(start 211.175 153.45)
		(end 211.175 153.035)
		(width 0.174)
		(layer "B.Cu")
		(net 50)
	)
	(segment
		(start 216.849 145.85)
		(end 216.849 146.229001)
		(width 0.174)
		(layer "B.Cu")
		(net 50)
	)
	(segment
		(start 222.9245 139.615)
		(end 222.9245 139.9945)
		(width 0.256)
		(layer "B.Cu")
		(net 50)
	)
	(segment
		(start 215.982999 151.8215)
		(end 215.982999 152.647001)
		(width 0.15)
		(layer "B.Cu")
		(net 50)
	)
	(segment
		(start 220.0995 130.0995)
		(end 220.0995 130.639)
		(width 0.256)
		(layer "B.Cu")
		(net 50)
	)
	(segment
		(start 200.2 131.671752)
		(end 200.2 131.25)
		(width 0.4)
		(layer "In6.Cu")
		(net 50)
	)
	(segment
		(start 200.098 132.699)
		(end 200.024 132.625)
		(width 0.4)
		(layer "In6.Cu")
		(net 50)
	)
	(segment
		(start 200.024 131.847752)
		(end 200.2 131.671752)
		(width 0.4)
		(layer "In6.Cu")
		(net 50)
	)
	(segment
		(start 200.024 132.625)
		(end 200.024 131.847752)
		(width 0.4)
		(layer "In6.Cu")
		(net 50)
	)
	(segment
		(start 212.75 120.15)
		(end 213.26 120.15)
		(width 0.35)
		(layer "In6.Cu")
		(net 50)
	)
	(segment
		(start 178.79 141.13)
		(end 178.326 140.666)
		(width 0.1)
		(layer "In7.Cu")
		(net 50)
	)
	(segment
		(start 178.443498 144.486502)
		(end 178.45173 144.486502)
		(width 0.1)
		(layer "In7.Cu")
		(net 50)
	)
	(segment
		(start 178.326 139.276)
		(end 177.9 138.85)
		(width 0.1)
		(layer "In7.Cu")
		(net 50)
	)
	(segment
		(start 178.79 144.148232)
		(end 178.79 141.13)
		(width 0.1)
		(layer "In7.Cu")
		(net 50)
	)
	(segment
		(start 178.28 144.65)
		(end 178.443498 144.486502)
		(width 0.1)
		(layer "In7.Cu")
		(net 50)
	)
	(segment
		(start 178.326 140.666)
		(end 178.326 139.276)
		(width 0.1)
		(layer "In7.Cu")
		(net 50)
	)
	(segment
		(start 176.32 146.14)
		(end 177.81 144.65)
		(width 0.1)
		(layer "In7.Cu")
		(net 50)
	)
	(segment
		(start 178.45173 144.486502)
		(end 178.79 144.148232)
		(width 0.1)
		(layer "In7.Cu")
		(net 50)
	)
	(segment
		(start 177.81 144.65)
		(end 178.28 144.65)
		(width 0.1)
		(layer "In7.Cu")
		(net 50)
	)
	(segment
		(start 220 141.31)
		(end 220.14 141.17)
		(width 0.35)
		(layer "In11.Cu")
		(net 50)
	)
	(segment
		(start 223.286013 141.767289)
		(end 223.286013 141.506013)
		(width 0.35)
		(layer "In11.Cu")
		(net 50)
	)
	(segment
		(start 220.14 141.17)
		(end 221.48 141.17)
		(width 0.35)
		(layer "In11.Cu")
		(net 50)
	)
	(segment
		(start 222.95 141.17)
		(end 221.48 141.17)
		(width 0.35)
		(layer "In11.Cu")
		(net 50)
	)
	(segment
		(start 223.286013 141.506013)
		(end 222.95 141.17)
		(width 0.35)
		(layer "In11.Cu")
		(net 50)
	)
	(segment
		(start 220 141.84)
		(end 220 141.31)
		(width 0.35)
		(layer "In11.Cu")
		(net 50)
	)
	(segment
		(start 221.48 141.81)
		(end 221.48 141.17)
		(width 0.35)
		(layer "In11.Cu")
		(net 50)
	)
	(via
		(at 200.499 141.101)
		(size 0.35)
		(drill 0.15)
		(layers "F.Cu" "B.Cu")
		(remove_unused_layers yes)
		(keep_end_layers yes)
		(zone_layer_connections)
		(net 51)
	)
	(segment
		(start 200.391857 141.296242)
		(end 200.391857 141.208143)
		(width 0.125)
		(layer "B.Cu")
		(net 51)
	)
	(segment
		(start 200.932499 141.716807)
		(end 200.9325 141.716807)
		(width 0.125)
		(layer "B.Cu")
		(net 51)
	)
	(segment
		(start 200.745117 141.529423)
		(end 200.745116 141.529423)
		(width 0.125)
		(layer "B.Cu")
		(net 51)
	)
	(segment
		(start 201.01 142.082324)
		(end 201.01 142.053825)
		(width 0.125)
		(layer "B.Cu")
		(net 51)
	)
	(segment
		(start 200.951421 141.912505)
		(end 200.9325 141.893584)
		(width 0.125)
		(layer "B.Cu")
		(net 51)
	)
	(segment
		(start 200.391857 141.208143)
		(end 200.499 141.101)
		(width 0.125)
		(layer "B.Cu")
		(net 51)
	)
	(segment
		(start 200.568338 141.529423)
		(end 200.462681 141.423766)
		(width 0.125)
		(layer "B.Cu")
		(net 51)
	)
	(segment
		(start 200.9325 141.540029)
		(end 200.9325 141.54003)
		(width 0.125)
		(layer "B.Cu")
		(net 51)
	)
	(segment
		(start 200.640192 142.59)
		(end 200.912512 142.31768)
		(width 0.125)
		(layer "B.Cu")
		(net 51)
	)
	(segment
		(start 200.9325 141.54003)
		(end 200.921893 141.529423)
		(width 0.125)
		(layer "B.Cu")
		(net 51)
	)
	(segment
		(start 200.5 142.59)
		(end 200.640192 142.59)
		(width 0.125)
		(layer "B.Cu")
		(net 51)
	)
	(arc
		(start 200.912512 142.31768)
		(mid 200.984663 142.209698)
		(end 201.01 142.082324)
		(width 0.125)
		(layer "B.Cu")
		(net 51)
	)
	(arc
		(start 200.921893 141.529423)
		(mid 200.833505 141.492811)
		(end 200.745117 141.529423)
		(width 0.125)
		(layer "B.Cu")
		(net 51)
	)
	(arc
		(start 200.9325 141.716807)
		(mid 200.969112 141.628418)
		(end 200.9325 141.540029)
		(width 0.125)
		(layer "B.Cu")
		(net 51)
	)
	(arc
		(start 200.745116 141.529423)
		(mid 200.656727 141.566035)
		(end 200.568338 141.529423)
		(width 0.125)
		(layer "B.Cu")
		(net 51)
	)
	(arc
		(start 200.462681 141.423766)
		(mid 200.418987 141.364836)
		(end 200.391857 141.296242)
		(width 0.125)
		(layer "B.Cu")
		(net 51)
	)
	(arc
		(start 200.9325 141.893584)
		(mid 200.89589 141.805192)
		(end 200.932499 141.716807)
		(width 0.125)
		(layer "B.Cu")
		(net 51)
	)
	(arc
		(start 201.01 142.053825)
		(mid 200.994785 141.977378)
		(end 200.951421 141.912505)
		(width 0.125)
		(layer "B.Cu")
		(net 51)
	)
	(segment
		(start 211.44 129.45)
		(end 211.9435 129.45)
		(width 0.15)
		(layer "F.Cu")
		(net 52)
	)
	(via
		(at 211.44 129.45)
		(size 0.35)
		(drill 0.15)
		(layers "F.Cu" "B.Cu")
		(net 52)
	)
	(segment
		(start 211.71 131.06)
		(end 211.71 129.72)
		(width 0.15)
		(layer "B.Cu")
		(net 52)
	)
	(segment
		(start 211.71 129.72)
		(end 211.44 129.45)
		(width 0.15)
		(layer "B.Cu")
		(net 52)
	)
	(via
		(at 202.1 140.3)
		(size 0.35)
		(drill 0.15)
		(layers "F.Cu" "B.Cu")
		(remove_unused_layers yes)
		(keep_end_layers yes)
		(zone_layer_connections)
		(net 53)
	)
	(segment
		(start 200.63 143.09)
		(end 200.699277 143.159277)
		(width 0.125)
		(layer "B.Cu")
		(net 53)
	)
	(segment
		(start 201.7425 142.401919)
		(end 201.7425 141.084755)
		(width 0.125)
		(layer "B.Cu")
		(net 53)
	)
	(segment
		(start 202.1 140.520149)
		(end 202.1 140.3)
		(width 0.125)
		(layer "B.Cu")
		(net 53)
	)
	(segment
		(start 200.5 143.09)
		(end 200.63 143.09)
		(width 0.125)
		(layer "B.Cu")
		(net 53)
	)
	(segment
		(start 201.088696 143.159276)
		(end 201.669277 142.578695)
		(width 0.125)
		(layer "B.Cu")
		(net 53)
	)
	(segment
		(start 200.876053 143.2325)
		(end 200.911919 143.2325)
		(width 0.125)
		(layer "B.Cu")
		(net 53)
	)
	(segment
		(start 201.815724 140.907978)
		(end 202.026777 140.696925)
		(width 0.125)
		(layer "B.Cu")
		(net 53)
	)
	(segment
		(start 200.63 143.05)
		(end 200.73 143.15)
		(width 0.125)
		(layer "B.Cu")
		(net 53)
	)
	(segment
		(start 200.5 143.05)
		(end 200.63 143.05)
		(width 0.125)
		(layer "B.Cu")
		(net 53)
	)
	(arc
		(start 200.699277 143.159277)
		(mid 200.780383 143.21347)
		(end 200.876053 143.2325)
		(width 0.125)
		(layer "B.Cu")
		(net 53)
	)
	(arc
		(start 202.1 140.520149)
		(mid 202.08097 140.61582)
		(end 202.026777 140.696925)
		(width 0.125)
		(layer "B.Cu")
		(net 53)
	)
	(arc
		(start 201.7425 142.401919)
		(mid 201.72347 142.49759)
		(end 201.669277 142.578695)
		(width 0.125)
		(layer "B.Cu")
		(net 53)
	)
	(arc
		(start 201.815724 140.907978)
		(mid 201.761531 140.989084)
		(end 201.7425 141.084755)
		(width 0.125)
		(layer "B.Cu")
		(net 53)
	)
	(arc
		(start 200.911919 143.2325)
		(mid 201.00759 143.21347)
		(end 201.088696 143.159276)
		(width 0.125)
		(layer "B.Cu")
		(net 53)
	)
	(segment
		(start 195.39 145.49)
		(end 195.54 145.34)
		(width 0.1)
		(layer "F.Cu")
		(net 57)
	)
	(segment
		(start 195.39 145.9)
		(end 195.39 145.49)
		(width 0.1)
		(layer "F.Cu")
		(net 57)
	)
	(segment
		(start 195.86 145.21)
		(end 195.86 144.9)
		(width 0.1)
		(layer "F.Cu")
		(net 57)
	)
	(segment
		(start 195.54 145.34)
		(end 195.73 145.34)
		(width 0.1)
		(layer "F.Cu")
		(net 57)
	)
	(segment
		(start 195.73 145.34)
		(end 195.86 145.21)
		(width 0.1)
		(layer "F.Cu")
		(net 57)
	)
	(via
		(at 196.5 144.01)
		(size 0.35)
		(drill 0.15)
		(layers "F.Cu" "B.Cu")
		(remove_unused_layers yes)
		(keep_end_layers yes)
		(zone_layer_connections)
		(net 60)
	)
	(via
		(at 203.699 129.901)
		(size 0.35)
		(drill 0.15)
		(layers "F.Cu" "B.Cu")
		(remove_unused_layers yes)
		(keep_end_layers yes)
		(zone_layer_connections)
		(net 60)
	)
	(segment
		(start 206.697846 130.238549)
		(end 206.697847 130.238548)
		(width 0.09)
		(layer "In11.Cu")
		(net 60)
	)
	(segment
		(start 207.57 131.07)
		(end 207.57 130.719706)
		(width 0.09)
		(layer "In11.Cu")
		(net 60)
	)
	(segment
		(start 198.774581 147.865419)
		(end 198.654581 147.865419)
		(width 0.09)
		(layer "In11.Cu")
		(net 60)
	)
	(segment
		(start 206.733193 130.627466)
		(end 206.999411 130.361249)
		(width 0.09)
		(layer "In11.Cu")
		(net 60)
	)
	(segment
		(start 205.471455 129.629997)
		(end 205.261458 129.42)
		(width 0.09)
		(layer "In11.Cu")
		(net 60)
	)
	(segment
		(start 199.679826 150.19012)
		(end 199.844706 150.355)
		(width 0.09)
		(layer "In11.Cu")
		(net 60)
	)
	(segment
		(start 206.480291 129.629997)
		(end 205.471455 129.629997)
		(width 0.09)
		(layer "In11.Cu")
		(net 60)
	)
	(segment
		(start 207.415 132.015)
		(end 206.045 132.015)
		(width 0.09)
		(layer "In11.Cu")
		(net 60)
	)
	(segment
		(start 207.415 133.115)
		(end 206.745 133.115)
		(width 0.09)
		(layer "In11.Cu")
		(net 60)
	)
	(segment
		(start 206.745 132.325)
		(end 207.415 132.325)
		(width 0.09)
		(layer "In11.Cu")
		(net 60)
	)
	(segment
		(start 206.787278 130.149116)
		(end 206.697846 130.238549)
		(width 0.09)
		(layer "In11.Cu")
		(net 60)
	)
	(segment
		(start 204.67 150.355)
		(end 205.350294 150.355)
		(width 0.09)
		(layer "In11.Cu")
		(net 60)
	)
	(segment
		(start 199.432341 149.695148)
		(end 199.572241 149.555245)
		(width 0.09)
		(layer "In11.Cu")
		(net 60)
	)
	(segment
		(start 199.844706 150.355)
		(end 203.47 150.355)
		(width 0.09)
		(layer "In11.Cu")
		(net 60)
	)
	(segment
		(start 204.49 149.655)
		(end 204.49 150.175)
		(width 0.09)
		(layer "In11.Cu")
		(net 60)
	)
	(segment
		(start 207.57 137.014706)
		(end 207.57 133.27)
		(width 0.09)
		(layer "In11.Cu")
		(net 60)
	)
	(segment
		(start 207.681174 149.12)
		(end 207.92 148.881174)
		(width 0.09)
		(layer "In11.Cu")
		(net 60)
	)
	(segment
		(start 199.12 149.630294)
		(end 199.184853 149.695147)
		(width 0.09)
		(layer "In11.Cu")
		(net 60)
	)
	(segment
		(start 198.549162 147.970838)
		(end 198.549162 148.194581)
		(width 0.09)
		(layer "In11.Cu")
		(net 60)
	)
	(segment
		(start 207.92 137.364706)
		(end 207.57 137.014706)
		(width 0.09)
		(layer "In11.Cu")
		(net 60)
	)
	(segment
		(start 207.57 130.719706)
		(end 207.423674 130.57338)
		(width 0.09)
		(layer "In11.Cu")
		(net 60)
	)
	(segment
		(start 206.999411 130.361249)
		(end 206.99941 130.36125)
		(width 0.09)
		(layer "In11.Cu")
		(net 60)
	)
	(segment
		(start 199.819728 149.802732)
		(end 199.81973 149.802733)
		(width 0.09)
		(layer "In11.Cu")
		(net 60)
	)
	(segment
		(start 205.350294 150.355)
		(end 206.100294 149.605)
		(width 0.09)
		(layer "In11.Cu")
		(net 60)
	)
	(segment
		(start 206.100294 149.605)
		(end 206.795294 149.605)
		(width 0.09)
		(layer "In11.Cu")
		(net 60)
	)
	(segment
		(start 203.949706 129.42)
		(end 203.699 129.670706)
		(width 0.09)
		(layer "In11.Cu")
		(net 60)
	)
	(segment
		(start 198.654581 148.3)
		(end 199.611658 148.3)
		(width 0.09)
		(layer "In11.Cu")
		(net 60)
	)
	(segment
		(start 199.81973 149.802733)
		(end 199.679827 149.942633)
		(width 0.09)
		(layer "In11.Cu")
		(net 60)
	)
	(segment
		(start 199.819728 149.555244)
		(end 199.819729 149.555245)
		(width 0.09)
		(layer "In11.Cu")
		(net 60)
	)
	(segment
		(start 206.045 131.225)
		(end 207.415 131.225)
		(width 0.09)
		(layer "In11.Cu")
		(net 60)
	)
	(segment
		(start 206.575147 129.724853)
		(end 206.480291 129.629997)
		(width 0.09)
		(layer "In11.Cu")
		(net 60)
	)
	(segment
		(start 207.92 148.881174)
		(end 207.92 137.364706)
		(width 0.09)
		(layer "In11.Cu")
		(net 60)
	)
	(segment
		(start 199.611658 149.19)
		(end 199.325 149.19)
		(width 0.09)
		(layer "In11.Cu")
		(net 60)
	)
	(segment
		(start 206.945325 130.839598)
		(end 206.945326 130.839597)
		(width 0.09)
		(layer "In11.Cu")
		(net 60)
	)
	(segment
		(start 203.699 129.670706)
		(end 203.699 129.901)
		(width 0.09)
		(layer "In11.Cu")
		(net 60)
	)
	(segment
		(start 206.795294 149.605)
		(end 207.280294 149.12)
		(width 0.09)
		(layer "In11.Cu")
		(net 60)
	)
	(segment
		(start 207.280294 149.12)
		(end 207.681174 149.12)
		(width 0.09)
		(layer "In11.Cu")
		(net 60)
	)
	(segment
		(start 207.211542 130.57338)
		(end 206.945325 130.839598)
		(width 0.09)
		(layer "In11.Cu")
		(net 60)
	)
	(segment
		(start 196.23 144.2)
		(end 196.23 144.530294)
		(width 0.09)
		(layer "In11.Cu")
		(net 60)
	)
	(segment
		(start 196.23 144.530294)
		(end 199.12 147.420294)
		(width 0.09)
		(layer "In11.Cu")
		(net 60)
	)
	(segment
		(start 206.999411 130.149117)
		(end 206.99941 130.149116)
		(width 0.09)
		(layer "In11.Cu")
		(net 60)
	)
	(segment
		(start 199.43234 149.695146)
		(end 199.432341 149.695148)
		(width 0.09)
		(layer "In11.Cu")
		(net 60)
	)
	(segment
		(start 196.5 144.01)
		(end 196.42 144.01)
		(width 0.09)
		(layer "In11.Cu")
		(net 60)
	)
	(segment
		(start 206.485714 130.026417)
		(end 206.575147 129.936985)
		(width 0.09)
		(layer "In11.Cu")
		(net 60)
	)
	(segment
		(start 196.42 144.01)
		(end 196.23 144.2)
		(width 0.09)
		(layer "In11.Cu")
		(net 60)
	)
	(segment
		(start 203.65 150.175)
		(end 203.65 149.655)
		(width 0.09)
		(layer "In11.Cu")
		(net 60)
	)
	(segment
		(start 199.12 147.420294)
		(end 199.12 147.52)
		(width 0.09)
		(layer "In11.Cu")
		(net 60)
	)
	(segment
		(start 206.575147 129.936985)
		(end 206.575146 129.936986)
		(width 0.09)
		(layer "In11.Cu")
		(net 60)
	)
	(segment
		(start 199.12 149.395)
		(end 199.12 149.630294)
		(width 0.09)
		(layer "In11.Cu")
		(net 60)
	)
	(segment
		(start 205.261458 129.42)
		(end 203.949706 129.42)
		(width 0.09)
		(layer "In11.Cu")
		(net 60)
	)
	(arc
		(start 206.575146 129.936986)
		(mid 206.619081 129.83092)
		(end 206.575147 129.724853)
		(width 0.09)
		(layer "In11.Cu")
		(net 60)
	)
	(arc
		(start 206.045 132.015)
		(mid 205.765693 131.899307)
		(end 205.65 131.62)
		(width 0.09)
		(layer "In11.Cu")
		(net 60)
	)
	(arc
		(start 206.35 132.72)
		(mid 206.465693 132.440693)
		(end 206.745 132.325)
		(width 0.09)
		(layer "In11.Cu")
		(net 60)
	)
	(arc
		(start 204.07 149.235)
		(mid 204.366985 149.358015)
		(end 204.49 149.655)
		(width 0.09)
		(layer "In11.Cu")
		(net 60)
	)
	(arc
		(start 200.056658 148.745)
		(mid 199.926321 149.059663)
		(end 199.611658 149.19)
		(width 0.09)
		(layer "In11.Cu")
		(net 60)
	)
	(arc
		(start 206.945326 130.839597)
		(mid 206.83926 130.883532)
		(end 206.733193 130.839598)
		(width 0.09)
		(layer "In11.Cu")
		(net 60)
	)
	(arc
		(start 205.65 131.62)
		(mid 205.765693 131.340693)
		(end 206.045 131.225)
		(width 0.09)
		(layer "In11.Cu")
		(net 60)
	)
	(arc
		(start 206.485714 130.238549)
		(mid 206.44178 130.132483)
		(end 206.485714 130.026417)
		(width 0.09)
		(layer "In11.Cu")
		(net 60)
	)
	(arc
		(start 207.415 131.225)
		(mid 207.524602 131.179602)
		(end 207.57 131.07)
		(width 0.09)
		(layer "In11.Cu")
		(net 60)
	)
	(arc
		(start 207.423674 130.57338)
		(mid 207.317608 130.529446)
		(end 207.211542 130.57338)
		(width 0.09)
		(layer "In11.Cu")
		(net 60)
	)
	(arc
		(start 206.745 133.115)
		(mid 206.465693 132.999307)
		(end 206.35 132.72)
		(width 0.09)
		(layer "In11.Cu")
		(net 60)
	)
	(arc
		(start 198.549162 148.194581)
		(mid 198.580039 148.269123)
		(end 198.654581 148.3)
		(width 0.09)
		(layer "In11.Cu")
		(net 60)
	)
	(arc
		(start 204.49 150.175)
		(mid 204.542721 150.302279)
		(end 204.67 150.355)
		(width 0.09)
		(layer "In11.Cu")
		(net 60)
	)
	(arc
		(start 199.12 147.52)
		(mid 199.018829 147.764248)
		(end 198.774581 147.865419)
		(width 0.09)
		(layer "In11.Cu")
		(net 60)
	)
	(arc
		(start 207.57 132.17)
		(mid 207.524602 132.060398)
		(end 207.415 132.015)
		(width 0.09)
		(layer "In11.Cu")
		(net 60)
	)
	(arc
		(start 199.611658 148.3)
		(mid 199.926321 148.430337)
		(end 200.056658 148.745)
		(width 0.09)
		(layer "In11.Cu")
		(net 60)
	)
	(arc
		(start 199.819729 149.555245)
		(mid 199.870985 149.678989)
		(end 199.819728 149.802732)
		(width 0.09)
		(layer "In11.Cu")
		(net 60)
	)
	(arc
		(start 199.679827 149.942633)
		(mid 199.62857 150.066376)
		(end 199.679826 150.19012)
		(width 0.09)
		(layer "In11.Cu")
		(net 60)
	)
	(arc
		(start 203.65 149.655)
		(mid 203.773015 149.358015)
		(end 204.07 149.235)
		(width 0.09)
		(layer "In11.Cu")
		(net 60)
	)
	(arc
		(start 206.99941 130.149116)
		(mid 206.893344 130.105182)
		(end 206.787278 130.149116)
		(width 0.09)
		(layer "In11.Cu")
		(net 60)
	)
	(arc
		(start 206.733193 130.839598)
		(mid 206.689259 130.733532)
		(end 206.733193 130.627466)
		(width 0.09)
		(layer "In11.Cu")
		(net 60)
	)
	(arc
		(start 206.697847 130.238548)
		(mid 206.591781 130.282483)
		(end 206.485714 130.238549)
		(width 0.09)
		(layer "In11.Cu")
		(net 60)
	)
	(arc
		(start 207.57 133.27)
		(mid 207.524602 133.160398)
		(end 207.415 133.115)
		(width 0.09)
		(layer "In11.Cu")
		(net 60)
	)
	(arc
		(start 203.47 150.355)
		(mid 203.597279 150.302279)
		(end 203.65 150.175)
		(width 0.09)
		(layer "In11.Cu")
		(net 60)
	)
	(arc
		(start 199.325 149.19)
		(mid 199.180043 149.250043)
		(end 199.12 149.395)
		(width 0.09)
		(layer "In11.Cu")
		(net 60)
	)
	(arc
		(start 206.99941 130.36125)
		(mid 207.043345 130.255184)
		(end 206.999411 130.149117)
		(width 0.09)
		(layer "In11.Cu")
		(net 60)
	)
	(arc
		(start 199.572241 149.555245)
		(mid 199.695984 149.503988)
		(end 199.819728 149.555244)
		(width 0.09)
		(layer "In11.Cu")
		(net 60)
	)
	(arc
		(start 198.654581 147.865419)
		(mid 198.580039 147.896296)
		(end 198.549162 147.970838)
		(width 0.09)
		(layer "In11.Cu")
		(net 60)
	)
	(arc
		(start 199.184853 149.695147)
		(mid 199.308597 149.746403)
		(end 199.43234 149.695146)
		(width 0.09)
		(layer "In11.Cu")
		(net 60)
	)
	(arc
		(start 207.415 132.325)
		(mid 207.524602 132.279602)
		(end 207.57 132.17)
		(width 0.09)
		(layer "In11.Cu")
		(net 60)
	)
	(segment
		(start 212.1245 152.2245)
		(end 212.1315 152.2245)
		(width 0.15)
		(layer "F.Cu")
		(net 62)
	)
	(segment
		(start 217.55 147.8)
		(end 216.802 147.8)
		(width 0.15)
		(layer "F.Cu")
		(net 62)
	)
	(segment
		(start 215.58 151.52)
		(end 215.58 152.223)
		(width 0.15)
		(layer "F.Cu")
		(net 62)
	)
	(segment
		(start 215.58 152.223)
		(end 215.5815 152.2245)
		(width 0.15)
		(layer "F.Cu")
		(net 62)
	)
	(segment
		(start 212.12 152.22)
		(end 212.1245 152.2245)
		(width 0.15)
		(layer "F.Cu")
		(net 62)
	)
	(via
		(at 213.615 144.75)
		(size 0.35)
		(drill 0.15)
		(layers "F.Cu" "B.Cu")
		(remove_unused_layers yes)
		(keep_end_layers yes)
		(zone_layer_connections)
		(net 62)
	)
	(via
		(at 217.55 147.8)
		(size 0.35)
		(drill 0.15)
		(layers "F.Cu" "B.Cu")
		(remove_unused_layers yes)
		(keep_end_layers yes)
		(zone_layer_connections)
		(net 62)
	)
	(via
		(at 212.12 152.22)
		(size 0.35)
		(drill 0.15)
		(layers "F.Cu" "B.Cu")
		(remove_unused_layers yes)
		(keep_end_layers yes)
		(zone_layer_connections)
		(net 62)
	)
	(via
		(at 210.57 149.77)
		(size 0.35)
		(drill 0.15)
		(layers "F.Cu" "B.Cu")
		(remove_unused_layers yes)
		(keep_end_layers yes)
		(zone_layer_connections)
		(net 62)
	)
	(via
		(at 215.58 151.52)
		(size 0.35)
		(drill 0.15)
		(layers "F.Cu" "B.Cu")
		(remove_unused_layers yes)
		(keep_end_layers yes)
		(zone_layer_connections)
		(net 62)
	)
	(segment
		(start 217.55 147.8)
		(end 217.764 148.014)
		(width 0.15)
		(layer "B.Cu")
		(net 62)
	)
	(segment
		(start 212.13 151.12)
		(end 211.175 151.12)
		(width 0.15)
		(layer "B.Cu")
		(net 62)
	)
	(segment
		(start 215.57 151.51)
		(end 215.57 151.12)
		(width 0.15)
		(layer "B.Cu")
		(net 62)
	)
	(segment
		(start 217.764 148.014)
		(end 217.764 149.686)
		(width 0.15)
		(layer "B.Cu")
		(net 62)
	)
	(segment
		(start 211.175 151.12)
		(end 210.57 150.515)
		(width 0.15)
		(layer "B.Cu")
		(net 62)
	)
	(segment
		(start 216.33 151.12)
		(end 215.57 151.12)
		(width 0.15)
		(layer "B.Cu")
		(net 62)
	)
	(segment
		(start 210.57 150.515)
		(end 210.57 150.413)
		(width 0.15)
		(layer "B.Cu")
		(net 62)
	)
	(segment
		(start 212.12 151.13)
		(end 212.13 151.12)
		(width 0.15)
		(layer "B.Cu")
		(net 62)
	)
	(segment
		(start 212.12 152.22)
		(end 212.12 151.13)
		(width 0.15)
		(layer "B.Cu")
		(net 62)
	)
	(segment
		(start 211.175 152.07)
		(end 211.175 151.12)
		(width 0.15)
		(layer "B.Cu")
		(net 62)
	)
	(segment
		(start 209.912 150.413)
		(end 209.322 151.003)
		(width 0.15)
		(layer "B.Cu")
		(net 62)
	)
	(segment
		(start 217.764 149.686)
		(end 216.33 151.12)
		(width 0.15)
		(layer "B.Cu")
		(net 62)
	)
	(segment
		(start 215.58 151.52)
		(end 215.57 151.51)
		(width 0.15)
		(layer "B.Cu")
		(net 62)
	)
	(segment
		(start 215.57 151.12)
		(end 212.13 151.12)
		(width 0.15)
		(layer "B.Cu")
		(net 62)
	)
	(segment
		(start 209.912 150.413)
		(end 210.57 150.413)
		(width 0.15)
		(layer "B.Cu")
		(net 62)
	)
	(segment
		(start 209.322 151.003)
		(end 209.322 151.461)
		(width 0.15)
		(layer "B.Cu")
		(net 62)
	)
	(segment
		(start 210.57 149.77)
		(end 210.57 150.413)
		(width 0.15)
		(layer "B.Cu")
		(net 62)
	)
	(segment
		(start 211.825 148.93)
		(end 211.825 146.54)
		(width 0.1)
		(layer "In2.Cu")
		(net 62)
	)
	(segment
		(start 210.57 149.77)
		(end 210.985 149.77)
		(width 0.1)
		(layer "In2.Cu")
		(net 62)
	)
	(segment
		(start 211.825 146.54)
		(end 213.615 144.75)
		(width 0.1)
		(layer "In2.Cu")
		(net 62)
	)
	(segment
		(start 210.985 149.77)
		(end 211.825 148.93)
		(width 0.1)
		(layer "In2.Cu")
		(net 62)
	)
	(via
		(at 201.324 118.135)
		(size 0.35)
		(drill 0.15)
		(layers "F.Cu" "B.Cu")
		(remove_unused_layers yes)
		(keep_end_layers yes)
		(zone_layer_connections)
		(net 63)
	)
	(via
		(at 202.1 132.3)
		(size 0.35)
		(drill 0.15)
		(layers "F.Cu" "B.Cu")
		(remove_unused_layers yes)
		(keep_end_layers yes)
		(zone_layer_connections)
		(net 63)
	)
	(segment
		(start 201.324 118.135)
		(end 201 118.135)
		(width 0.15)
		(layer "B.Cu")
		(net 63)
	)
	(segment
		(start 201 118.135)
		(end 200.519 118.616)
		(width 0.15)
		(layer "B.Cu")
		(net 63)
	)
	(segment
		(start 200.519 118.616)
		(end 200.519 120.168)
		(width 0.15)
		(layer "B.Cu")
		(net 63)
	)
	(segment
		(start 200.519 120.168)
		(end 200.522 120.171)
		(width 0.15)
		(layer "B.Cu")
		(net 63)
	)
	(segment
		(start 198.21 121.39)
		(end 199.69165 121.39)
		(width 0.1)
		(layer "In9.Cu")
		(net 63)
	)
	(segment
		(start 201.64 117.81)
		(end 201.3 118.15)
		(width 0.1)
		(layer "In9.Cu")
		(net 63)
	)
	(segment
		(start 202.736512 118.297892)
		(end 202.24862 117.81)
		(width 0.1)
		(layer "In9.Cu")
		(net 63)
	)
	(segment
		(start 195.43 121.44)
		(end 195.43 121.03)
		(width 0.1)
		(layer "In9.Cu")
		(net 63)
	)
	(segment
		(start 202.183187 120.203325)
		(end 202.736512 119.65)
		(width 0.1)
		(layer "In9.Cu")
		(net 63)
	)
	(segment
		(start 202.1 132.3)
		(end 201.65 132.75)
		(width 0.1)
		(layer "In9.Cu")
		(net 63)
	)
	(segment
		(start 194.803522 131.05)
		(end 194.575 130.821478)
		(width 0.1)
		(layer "In9.Cu")
		(net 63)
	)
	(segment
		(start 199.69165 121.39)
		(end 200.878325 120.203325)
		(width 0.1)
		(layer "In9.Cu")
		(net 63)
	)
	(segment
		(start 200.2 131.05)
		(end 194.803522 131.05)
		(width 0.1)
		(layer "In9.Cu")
		(net 63)
	)
	(segment
		(start 194.575 122.295)
		(end 195.43 121.44)
		(width 0.1)
		(layer "In9.Cu")
		(net 63)
	)
	(segment
		(start 202.736512 119.65)
		(end 202.736512 118.297892)
		(width 0.1)
		(layer "In9.Cu")
		(net 63)
	)
	(segment
		(start 200.9 131.75)
		(end 200.2 131.05)
		(width 0.1)
		(layer "In9.Cu")
		(net 63)
	)
	(segment
		(start 200.9 132.5)
		(end 200.9 131.75)
		(width 0.1)
		(layer "In9.Cu")
		(net 63)
	)
	(segment
		(start 195.727 120.733)
		(end 197.553 120.733)
		(width 0.1)
		(layer "In9.Cu")
		(net 63)
	)
	(segment
		(start 194.575 130.821478)
		(end 194.575 122.295)
		(width 0.1)
		(layer "In9.Cu")
		(net 63)
	)
	(segment
		(start 197.553 120.733)
		(end 198.21 121.39)
		(width 0.1)
		(layer "In9.Cu")
		(net 63)
	)
	(segment
		(start 200.878325 120.203325)
		(end 202.183187 120.203325)
		(width 0.1)
		(layer "In9.Cu")
		(net 63)
	)
	(segment
		(start 195.43 121.03)
		(end 195.727 120.733)
		(width 0.1)
		(layer "In9.Cu")
		(net 63)
	)
	(segment
		(start 201.15 132.75)
		(end 200.9 132.5)
		(width 0.1)
		(layer "In9.Cu")
		(net 63)
	)
	(segment
		(start 201.65 132.75)
		(end 201.15 132.75)
		(width 0.1)
		(layer "In9.Cu")
		(net 63)
	)
	(segment
		(start 202.24862 117.81)
		(end 201.64 117.81)
		(width 0.1)
		(layer "In9.Cu")
		(net 63)
	)
	(via
		(at 202.1 141.101)
		(size 0.35)
		(drill 0.15)
		(layers "F.Cu" "B.Cu")
		(remove_unused_layers yes)
		(keep_end_layers yes)
		(zone_layer_connections)
		(net 64)
	)
	(segment
		(start 202.1325 141.675)
		(end 202.137436 141.675)
		(width 0.125)
		(layer "B.Cu")
		(net 64)
	)
	(segment
		(start 200.699276 143.520724)
		(end 200.63 143.59)
		(width 0.125)
		(layer "B.Cu")
		(net 64)
	)
	(segment
		(start 200.876053 143.4475)
		(end 201.000975 143.4475)
		(width 0.125)
		(layer "B.Cu")
		(net 64)
	)
	(segment
		(start 200.63 143.59)
		(end 200.5 143.59)
		(width 0.125)
		(layer "B.Cu")
		(net 64)
	)
	(segment
		(start 201.63679 143.162728)
		(end 201.636788 143.162729)
		(width 0.125)
		(layer "B.Cu")
		(net 64)
	)
	(segment
		(start 201.9575 142.2)
		(end 201.9575 142.490975)
		(width 0.125)
		(layer "B.Cu")
		(net 64)
	)
	(segment
		(start 201.389302 143.162728)
		(end 201.177751 143.374277)
		(width 0.125)
		(layer "B.Cu")
		(net 64)
	)
	(segment
		(start 200.5 143.55)
		(end 200.63 143.55)
		(width 0.125)
		(layer "B.Cu")
		(net 64)
	)
	(segment
		(start 201.884277 143.162727)
		(end 201.884276 143.162728)
		(width 0.125)
		(layer "B.Cu")
		(net 64)
	)
	(segment
		(start 202.1 141.101)
		(end 202.030723 141.170277)
		(width 0.125)
		(layer "B.Cu")
		(net 64)
	)
	(segment
		(start 201.389301 143.16273)
		(end 201.389302 143.162728)
		(width 0.125)
		(layer "B.Cu")
		(net 64)
	)
	(segment
		(start 202.137436 142.025)
		(end 202.1325 142.025)
		(width 0.125)
		(layer "B.Cu")
		(net 64)
	)
	(segment
		(start 201.9575 141.347053)
		(end 201.9575 141.5)
		(width 0.125)
		(layer "B.Cu")
		(net 64)
	)
	(arc
		(start 202.137436 141.675)
		(mid 202.26118 141.726256)
		(end 202.312436 141.85)
		(width 0.125)
		(layer "B.Cu")
		(net 64)
	)
	(arc
		(start 201.9575 142.490975)
		(mid 201.93847 142.586646)
		(end 201.884276 142.667752)
		(width 0.125)
		(layer "B.Cu")
		(net 64)
	)
	(arc
		(start 201.884276 142.91524)
		(mid 201.935533 143.038983)
		(end 201.884277 143.162727)
		(width 0.125)
		(layer "B.Cu")
		(net 64)
	)
	(arc
		(start 202.030723 141.170277)
		(mid 201.97653 141.251383)
		(end 201.9575 141.347053)
		(width 0.125)
		(layer "B.Cu")
		(net 64)
	)
	(arc
		(start 201.177751 143.374277)
		(mid 201.096646 143.42847)
		(end 201.000975 143.4475)
		(width 0.125)
		(layer "B.Cu")
		(net 64)
	)
	(arc
		(start 200.876053 143.4475)
		(mid 200.780382 143.46653)
		(end 200.699276 143.520724)
		(width 0.125)
		(layer "B.Cu")
		(net 64)
	)
	(arc
		(start 201.636788 143.162729)
		(mid 201.513044 143.111473)
		(end 201.389301 143.16273)
		(width 0.125)
		(layer "B.Cu")
		(net 64)
	)
	(arc
		(start 201.9575 141.5)
		(mid 202.008756 141.623744)
		(end 202.1325 141.675)
		(width 0.125)
		(layer "B.Cu")
		(net 64)
	)
	(arc
		(start 201.884276 143.162728)
		(mid 201.760532 143.213985)
		(end 201.63679 143.162728)
		(width 0.125)
		(layer "B.Cu")
		(net 64)
	)
	(arc
		(start 202.312436 141.85)
		(mid 202.26118 141.973744)
		(end 202.137436 142.025)
		(width 0.125)
		(layer "B.Cu")
		(net 64)
	)
	(arc
		(start 201.884276 142.667752)
		(mid 201.83302 142.791496)
		(end 201.884276 142.91524)
		(width 0.125)
		(layer "B.Cu")
		(net 64)
	)
	(arc
		(start 202.1325 142.025)
		(mid 202.008756 142.076256)
		(end 201.9575 142.2)
		(width 0.125)
		(layer "B.Cu")
		(net 64)
	)
	(via
		(at 194.099 140.3)
		(size 0.35)
		(drill 0.15)
		(layers "F.Cu" "B.Cu")
		(remove_unused_layers yes)
		(keep_end_layers yes)
		(zone_layer_connections)
		(net 66)
	)
	(segment
		(start 195.480724 143.530724)
		(end 195.55 143.6)
		(width 0.125)
		(layer "B.Cu")
		(net 66)
	)
	(segment
		(start 194.099 140.3)
		(end 194.099 140.497447)
		(width 0.125)
		(layer "B.Cu")
		(net 66)
	)
	(segment
		(start 194.834277 143.384277)
		(end 193.834723 142.384723)
		(width 0.125)
		(layer "B.Cu")
		(net 66)
	)
	(segment
		(start 193.7615 142.207947)
		(end 193.7615 141.042053)
		(width 0.125)
		(layer "B.Cu")
		(net 66)
	)
	(segment
		(start 195.55 143.6)
		(end 195.68 143.6)
		(width 0.125)
		(layer "B.Cu")
		(net 66)
	)
	(segment
		(start 194.025776 140.674224)
		(end 193.834723 140.865277)
		(width 0.125)
		(layer "B.Cu")
		(net 66)
	)
	(segment
		(start 195.011053 143.4575)
		(end 195.303947 143.4575)
		(width 0.125)
		(layer "B.Cu")
		(net 66)
	)
	(arc
		(start 194.025776 140.674224)
		(mid 194.079969 140.593118)
		(end 194.099 140.497447)
		(width 0.125)
		(layer "B.Cu")
		(net 66)
	)
	(arc
		(start 193.834723 142.384723)
		(mid 193.78053 142.303617)
		(end 193.7615 142.207947)
		(width 0.125)
		(layer "B.Cu")
		(net 66)
	)
	(arc
		(start 193.7615 141.042053)
		(mid 193.78053 140.946382)
		(end 193.834723 140.865277)
		(width 0.125)
		(layer "B.Cu")
		(net 66)
	)
	(arc
		(start 195.303947 143.4575)
		(mid 195.399618 143.47653)
		(end 195.480724 143.530724)
		(width 0.125)
		(layer "B.Cu")
		(net 66)
	)
	(arc
		(start 195.011053 143.4575)
		(mid 194.915382 143.43847)
		(end 194.834277 143.384277)
		(width 0.125)
		(layer "B.Cu")
		(net 66)
	)
	(via
		(at 211.31 119.13)
		(size 0.35)
		(drill 0.15)
		(layers "F.Cu" "B.Cu")
		(remove_unused_layers yes)
		(keep_end_layers yes)
		(zone_layer_connections)
		(net 68)
	)
	(via
		(at 196.45 129.1)
		(size 0.35)
		(drill 0.15)
		(layers "F.Cu" "B.Cu")
		(remove_unused_layers yes)
		(keep_end_layers yes)
		(zone_layer_connections)
		(net 68)
	)
	(segment
		(start 196.7 128)
		(end 196.819 128.119)
		(width 0.09)
		(layer "In9.Cu")
		(net 68)
	)
	(segment
		(start 196.14 123.469706)
		(end 196.14 126.250294)
		(width 0.09)
		(layer "In9.Cu")
		(net 68)
	)
	(segment
		(start 210.89 119.203582)
		(end 210.89 120.029706)
		(width 0.09)
		(layer "In9.Cu")
		(net 68)
	)
	(segment
		(start 207.042597 122.787697)
		(end 207.58 122.250294)
		(width 0.09)
		(layer "In9.Cu")
		(net 68)
	)
	(segment
		(start 207.58 122.250294)
		(end 207.58 121.53)
		(width 0.09)
		(layer "In9.Cu")
		(net 68)
	)
	(segment
		(start 207.395 121.345)
		(end 206.524706 121.345)
		(width 0.09)
		(layer "In9.Cu")
		(net 68)
	)
	(segment
		(start 205.895 121.974706)
		(end 205.895 122.674706)
		(width 0.09)
		(layer "In9.Cu")
		(net 68)
	)
	(segment
		(start 208.132597 123.137109)
		(end 208.132597 125.04)
		(width 0.09)
		(layer "In9.Cu")
		(net 68)
	)
	(segment
		(start 209.214169 122.495)
		(end 208.774706 122.495)
		(width 0.09)
		(layer "In9.Cu")
		(net 68)
	)
	(segment
		(start 211.093582 119)
		(end 210.89 119.203582)
		(width 0.09)
		(layer "In9.Cu")
		(net 68)
	)
	(segment
		(start 204.28 122.65)
		(end 204.28 121.53)
		(width 0.09)
		(layer "In9.Cu")
		(net 68)
	)
	(segment
		(start 209.77 121.149706)
		(end 209.77 121.939169)
		(width 0.09)
		(layer "In9.Cu")
		(net 68)
	)
	(segment
		(start 196.819 128.119)
		(end 196.819 128.491)
		(width 0.09)
		(layer "In9.Cu")
		(net 68)
	)
	(segment
		(start 208.774706 122.495)
		(end 208.132597 123.137109)
		(width 0.09)
		(layer "In9.Cu")
		(net 68)
	)
	(segment
		(start 196.7 126.810294)
		(end 196.7 128)
		(width 0.09)
		(layer "In9.Cu")
		(net 68)
	)
	(segment
		(start 210.89 120.029706)
		(end 209.77 121.149706)
		(width 0.09)
		(layer "In9.Cu")
		(net 68)
	)
	(segment
		(start 207.042597 125.040001)
		(end 207.042597 122.787697)
		(width 0.09)
		(layer "In9.Cu")
		(net 68)
	)
	(segment
		(start 205.374706 123.195)
		(end 204.825 123.195)
		(width 0.09)
		(layer "In9.Cu")
		(net 68)
	)
	(segment
		(start 211.18 119)
		(end 211.093582 119)
		(width 0.09)
		(layer "In9.Cu")
		(net 68)
	)
	(segment
		(start 207.58 121.53)
		(end 207.395 121.345)
		(width 0.09)
		(layer "In9.Cu")
		(net 68)
	)
	(segment
		(start 211.31 119.13)
		(end 211.18 119)
		(width 0.09)
		(layer "In9.Cu")
		(net 68)
	)
	(segment
		(start 209.77 121.939169)
		(end 209.214169 122.495)
		(width 0.09)
		(layer "In9.Cu")
		(net 68)
	)
	(segment
		(start 196.45 128.86)
		(end 196.45 129.1)
		(width 0.09)
		(layer "In9.Cu")
		(net 68)
	)
	(segment
		(start 203.125 123.195)
		(end 196.414706 123.195)
		(width 0.09)
		(layer "In9.Cu")
		(net 68)
	)
	(segment
		(start 196.819 128.491)
		(end 196.45 128.86)
		(width 0.09)
		(layer "In9.Cu")
		(net 68)
	)
	(segment
		(start 196.414706 123.195)
		(end 196.14 123.469706)
		(width 0.09)
		(layer "In9.Cu")
		(net 68)
	)
	(segment
		(start 206.524706 121.345)
		(end 205.895 121.974706)
		(width 0.09)
		(layer "In9.Cu")
		(net 68)
	)
	(segment
		(start 196.14 126.250294)
		(end 196.7 126.810294)
		(width 0.09)
		(layer "In9.Cu")
		(net 68)
	)
	(segment
		(start 203.67 121.53)
		(end 203.67 122.65)
		(width 0.09)
		(layer "In9.Cu")
		(net 68)
	)
	(segment
		(start 205.895 122.674706)
		(end 205.374706 123.195)
		(width 0.09)
		(layer "In9.Cu")
		(net 68)
	)
	(arc
		(start 204.28 121.53)
		(mid 204.190668 121.314332)
		(end 203.975 121.225)
		(width 0.09)
		(layer "In9.Cu")
		(net 68)
	)
	(arc
		(start 207.587597 125.585)
		(mid 207.202224 125.425373)
		(end 207.042597 125.040001)
		(width 0.09)
		(layer "In9.Cu")
		(net 68)
	)
	(arc
		(start 203.975 121.225)
		(mid 203.759332 121.314332)
		(end 203.67 121.53)
		(width 0.09)
		(layer "In9.Cu")
		(net 68)
	)
	(arc
		(start 203.67 122.65)
		(mid 203.510373 123.035373)
		(end 203.125 123.195)
		(width 0.09)
		(layer "In9.Cu")
		(net 68)
	)
	(arc
		(start 204.825 123.195)
		(mid 204.439627 123.035373)
		(end 204.28 122.65)
		(width 0.09)
		(layer "In9.Cu")
		(net 68)
	)
	(arc
		(start 208.132597 125.04)
		(mid 207.972971 125.425373)
		(end 207.587597 125.585)
		(width 0.09)
		(layer "In9.Cu")
		(net 68)
	)
	(segment
		(start 220.875 118.51)
		(end 221 118.635)
		(width 0.1)
		(layer "F.Cu")
		(net 70)
	)
	(segment
		(start 220.7 118.51)
		(end 220.875 118.51)
		(width 0.1)
		(layer "F.Cu")
		(net 70)
	)
	(segment
		(start 220.56 118.65)
		(end 220.7 118.51)
		(width 0.1)
		(layer "F.Cu")
		(net 70)
	)
	(segment
		(start 220.275 118.65)
		(end 220.56 118.65)
		(width 0.1)
		(layer "F.Cu")
		(net 70)
	)
	(via
		(at 221 118.635)
		(size 0.35)
		(drill 0.15)
		(layers "F.Cu" "B.Cu")
		(remove_unused_layers yes)
		(keep_end_layers yes)
		(zone_layer_connections)
		(net 70)
	)
	(via
		(at 208.972 116.8)
		(size 0.35)
		(drill 0.15)
		(layers "F.Cu" "B.Cu")
		(remove_unused_layers yes)
		(keep_end_layers yes)
		(zone_layer_connections)
		(net 70)
	)
	(segment
		(start 208.922 117.246)
		(end 208.8345 117.1585)
		(width 0.1)
		(layer "B.Cu")
		(net 70)
	)
	(segment
		(start 208.8345 117.1585)
		(end 208.8345 117.044855)
		(width 0.1)
		(layer "B.Cu")
		(net 70)
	)
	(segment
		(start 208.832 117.042355)
		(end 208.832 116.94)
		(width 0.1)
		(layer "B.Cu")
		(net 70)
	)
	(segment
		(start 208.922 117.461)
		(end 208.922 117.246)
		(width 0.1)
		(layer "B.Cu")
		(net 70)
	)
	(segment
		(start 208.832 116.94)
		(end 208.972 116.8)
		(width 0.1)
		(layer "B.Cu")
		(net 70)
	)
	(segment
		(start 208.8345 117.044855)
		(end 208.832 117.042355)
		(width 0.1)
		(layer "B.Cu")
		(net 70)
	)
	(segment
		(start 212.479706 117.58)
		(end 212.01116 117.111454)
		(width 0.09)
		(layer "In2.Cu")
		(net 70)
	)
	(segment
		(start 223.37 118.17)
		(end 223.37 116.910294)
		(width 0.09)
		(layer "In2.Cu")
		(net 70)
	)
	(segment
		(start 209.169706 117.34)
		(end 208.842 117.012294)
		(width 0.09)
		(layer "In2.Cu")
		(net 70)
	)
	(segment
		(start 212.01116 117.111454)
		(end 210.21884 117.111454)
		(width 0.09)
		(layer "In2.Cu")
		(net 70)
	)
	(segment
		(start 223.039706 116.58)
		(end 221.200294 116.58)
		(width 0.09)
		(layer "In2.Cu")
		(net 70)
	)
	(segment
		(start 208.842 117.012294)
		(end 208.842 116.93)
		(width 0.09)
		(layer "In2.Cu")
		(net 70)
	)
	(segment
		(start 213.900294 116.88)
		(end 213.200294 117.58)
		(width 0.09)
		(layer "In2.Cu")
		(net 70)
	)
	(segment
		(start 223.37 116.910294)
		(end 223.039706 116.58)
		(width 0.09)
		(layer "In2.Cu")
		(net 70)
	)
	(segment
		(start 221.115 118.52)
		(end 223.02 118.52)
		(width 0.09)
		(layer "In2.Cu")
		(net 70)
	)
	(segment
		(start 221.200294 116.58)
		(end 220.450294 117.33)
		(width 0.09)
		(layer "In2.Cu")
		(net 70)
	)
	(segment
		(start 210.21884 117.111454)
		(end 209.990294 117.34)
		(width 0.09)
		(layer "In2.Cu")
		(net 70)
	)
	(segment
		(start 223.02 118.52)
		(end 223.37 118.17)
		(width 0.09)
		(layer "In2.Cu")
		(net 70)
	)
	(segment
		(start 221 118.635)
		(end 221.115 118.52)
		(width 0.09)
		(layer "In2.Cu")
		(net 70)
	)
	(segment
		(start 213.200294 117.58)
		(end 212.479706 117.58)
		(width 0.09)
		(layer "In2.Cu")
		(net 70)
	)
	(segment
		(start 208.842 116.93)
		(end 208.972 116.8)
		(width 0.09)
		(layer "In2.Cu")
		(net 70)
	)
	(segment
		(start 219.949706 117.33)
		(end 219.499706 116.88)
		(width 0.09)
		(layer "In2.Cu")
		(net 70)
	)
	(segment
		(start 220.450294 117.33)
		(end 219.949706 117.33)
		(width 0.09)
		(layer "In2.Cu")
		(net 70)
	)
	(segment
		(start 209.990294 117.34)
		(end 209.169706 117.34)
		(width 0.09)
		(layer "In2.Cu")
		(net 70)
	)
	(segment
		(start 219.499706 116.88)
		(end 213.900294 116.88)
		(width 0.09)
		(layer "In2.Cu")
		(net 70)
	)
	(segment
		(start 220.7 121.51)
		(end 220.875 121.51)
		(width 0.1)
		(layer "F.Cu")
		(net 71)
	)
	(segment
		(start 220.56 121.65)
		(end 220.7 121.51)
		(width 0.1)
		(layer "F.Cu")
		(net 71)
	)
	(segment
		(start 220.275 121.65)
		(end 220.56 121.65)
		(width 0.1)
		(layer "F.Cu")
		(net 71)
	)
	(segment
		(start 220.875 121.51)
		(end 221 121.635)
		(width 0.1)
		(layer "F.Cu")
		(net 71)
	)
	(via
		(at 221 121.635)
		(size 0.35)
		(drill 0.15)
		(layers "F.Cu" "B.Cu")
		(remove_unused_layers yes)
		(keep_end_layers yes)
		(zone_layer_connections)
		(net 71)
	)
	(via
		(at 209.326 119.095)
		(size 0.35)
		(drill 0.15)
		(layers "F.Cu" "B.Cu")
		(remove_unused_layers yes)
		(keep_end_layers yes)
		(zone_layer_connections)
		(net 71)
	)
	(segment
		(start 208.8295 119.8685)
		(end 208.917 119.956)
		(width 0.1)
		(layer "B.Cu")
		(net 71)
	)
	(segment
		(start 208.8295 119.086064)
		(end 208.8295 119.8685)
		(width 0.1)
		(layer "B.Cu")
		(net 71)
	)
	(segment
		(start 208.998064 118.9175)
		(end 208.8295 119.086064)
		(width 0.1)
		(layer "B.Cu")
		(net 71)
	)
	(segment
		(start 208.917 119.956)
		(end 208.917 120.171)
		(width 0.1)
		(layer "B.Cu")
		(net 71)
	)
	(segment
		(start 209.1455 118.9175)
		(end 208.998064 118.9175)
		(width 0.1)
		(layer "B.Cu")
		(net 71)
	)
	(segment
		(start 209.323 119.095)
		(end 209.1455 118.9175)
		(width 0.1)
		(layer "B.Cu")
		(net 71)
	)
	(segment
		(start 217.845 120.43105)
		(end 217.845 121.61895)
		(width 0.09)
		(layer "In2.Cu")
		(net 71)
	)
	(segment
		(start 215.13 121.480758)
		(end 215.13 121.47)
		(width 0.09)
		(layer "In2.Cu")
		(net 71)
	)
	(segment
		(start 219.670294 121.52)
		(end 219.470294 121.32)
		(width 0.09)
		(layer "In2.Cu")
		(net 71)
	)
	(segment
		(start 212.130294 120.77)
		(end 211.670294 120.77)
		(width 0.09)
		(layer "In2.Cu")
		(net 71)
	)
	(segment
		(start 218.135 120.935)
		(end 218.135 120.43105)
		(width 0.09)
		(layer "In2.Cu")
		(net 71)
	)
	(segment
		(start 214.98 121.32)
		(end 212.680294 121.32)
		(width 0.09)
		(layer "In2.Cu")
		(net 71)
	)
	(segment
		(start 219.470294 121.32)
		(end 218.52 121.32)
		(width 0.09)
		(layer "In2.Cu")
		(net 71)
	)
	(segment
		(start 220.885 121.52)
		(end 219.670294 121.52)
		(width 0.09)
		(layer "In2.Cu")
		(net 71)
	)
	(segment
		(start 215.43 121.47)
		(end 215.43 121.480758)
		(width 0.09)
		(layer "In2.Cu")
		(net 71)
	)
	(segment
		(start 212.680294 121.32)
		(end 212.130294 120.77)
		(width 0.09)
		(layer "In2.Cu")
		(net 71)
	)
	(segment
		(start 216.785 120.431047)
		(end 216.785 121.61895)
		(width 0.09)
		(layer "In2.Cu")
		(net 71)
	)
	(segment
		(start 217.075 121.61895)
		(end 217.075 120.431047)
		(width 0.09)
		(layer "In2.Cu")
		(net 71)
	)
	(segment
		(start 215.87 121.32)
		(end 215.58 121.32)
		(width 0.09)
		(layer "In2.Cu")
		(net 71)
	)
	(segment
		(start 209.4935 118.9275)
		(end 209.326 119.095)
		(width 0.09)
		(layer "In2.Cu")
		(net 71)
	)
	(segment
		(start 209.827794 118.9275)
		(end 209.4935 118.9275)
		(width 0.09)
		(layer "In2.Cu")
		(net 71)
	)
	(segment
		(start 211.670294 120.77)
		(end 209.827794 118.9275)
		(width 0.09)
		(layer "In2.Cu")
		(net 71)
	)
	(segment
		(start 221 121.635)
		(end 220.885 121.52)
		(width 0.09)
		(layer "In2.Cu")
		(net 71)
	)
	(segment
		(start 216.015 121.61895)
		(end 216.015 121.465)
		(width 0.09)
		(layer "In2.Cu")
		(net 71)
	)
	(arc
		(start 215.43 121.480758)
		(mid 215.386066 121.586824)
		(end 215.28 121.630758)
		(width 0.09)
		(layer "In2.Cu")
		(net 71)
	)
	(arc
		(start 218.135 120.43105)
		(mid 218.09253 120.32852)
		(end 217.99 120.28605)
		(width 0.09)
		(layer "In2.Cu")
		(net 71)
	)
	(arc
		(start 217.845 121.61895)
		(mid 217.732236 121.891186)
		(end 217.46 122.00395)
		(width 0.09)
		(layer "In2.Cu")
		(net 71)
	)
	(arc
		(start 217.075 120.431047)
		(mid 217.03253 120.328517)
		(end 216.93 120.286047)
		(width 0.09)
		(layer "In2.Cu")
		(net 71)
	)
	(arc
		(start 216.4 122.00395)
		(mid 216.127764 121.891186)
		(end 216.015 121.61895)
		(width 0.09)
		(layer "In2.Cu")
		(net 71)
	)
	(arc
		(start 216.015 121.465)
		(mid 215.97253 121.36247)
		(end 215.87 121.32)
		(width 0.09)
		(layer "In2.Cu")
		(net 71)
	)
	(arc
		(start 217.99 120.28605)
		(mid 217.88747 120.32852)
		(end 217.845 120.43105)
		(width 0.09)
		(layer "In2.Cu")
		(net 71)
	)
	(arc
		(start 215.28 121.630758)
		(mid 215.173934 121.586824)
		(end 215.13 121.480758)
		(width 0.09)
		(layer "In2.Cu")
		(net 71)
	)
	(arc
		(start 216.93 120.286047)
		(mid 216.82747 120.328517)
		(end 216.785 120.431047)
		(width 0.09)
		(layer "In2.Cu")
		(net 71)
	)
	(arc
		(start 215.58 121.32)
		(mid 215.473934 121.363934)
		(end 215.43 121.47)
		(width 0.09)
		(layer "In2.Cu")
		(net 71)
	)
	(arc
		(start 217.46 122.00395)
		(mid 217.187764 121.891186)
		(end 217.075 121.61895)
		(width 0.09)
		(layer "In2.Cu")
		(net 71)
	)
	(arc
		(start 216.785 121.61895)
		(mid 216.672236 121.891186)
		(end 216.4 122.00395)
		(width 0.09)
		(layer "In2.Cu")
		(net 71)
	)
	(arc
		(start 215.13 121.47)
		(mid 215.086066 121.363934)
		(end 214.98 121.32)
		(width 0.09)
		(layer "In2.Cu")
		(net 71)
	)
	(arc
		(start 218.52 121.32)
		(mid 218.247764 121.207236)
		(end 218.135 120.935)
		(width 0.09)
		(layer "In2.Cu")
		(net 71)
	)
	(segment
		(start 220.7 118.29)
		(end 220.875 118.29)
		(width 0.1)
		(layer "F.Cu")
		(net 72)
	)
	(segment
		(start 220.56 118.15)
		(end 220.7 118.29)
		(width 0.1)
		(layer "F.Cu")
		(net 72)
	)
	(segment
		(start 220.275 118.15)
		(end 220.56 118.15)
		(width 0.1)
		(layer "F.Cu")
		(net 72)
	)
	(segment
		(start 220.875 118.29)
		(end 221 118.165)
		(width 0.1)
		(layer "F.Cu")
		(net 72)
	)
	(via
		(at 221 118.165)
		(size 0.35)
		(drill 0.15)
		(layers "F.Cu" "B.Cu")
		(remove_unused_layers yes)
		(keep_end_layers yes)
		(zone_layer_connections)
		(net 72)
	)
	(via
		(at 208.472 116.8)
		(size 0.35)
		(drill 0.15)
		(layers "F.Cu" "B.Cu")
		(remove_unused_layers yes)
		(keep_end_layers yes)
		(zone_layer_connections)
		(net 72)
	)
	(segment
		(start 208.612 116.94)
		(end 208.472 116.8)
		(width 0.1)
		(layer "B.Cu")
		(net 72)
	)
	(segment
		(start 208.527 117.461)
		(end 208.527 117.246)
		(width 0.1)
		(layer "B.Cu")
		(net 72)
	)
	(segment
		(start 208.6145 117.129045)
		(end 208.612 117.126545)
		(width 0.1)
		(layer "B.Cu")
		(net 72)
	)
	(segment
		(start 208.527 117.246)
		(end 208.6145 117.1585)
		(width 0.1)
		(layer "B.Cu")
		(net 72)
	)
	(segment
		(start 208.612 117.126545)
		(end 208.612 116.94)
		(width 0.1)
		(layer "B.Cu")
		(net 72)
	)
	(segment
		(start 208.6145 117.1585)
		(end 208.6145 117.129045)
		(width 0.1)
		(layer "B.Cu")
		(net 72)
	)
	(segment
		(start 222.92 118.28)
		(end 223.13 118.07)
		(width 0.09)
		(layer "In2.Cu")
		(net 72)
	)
	(segment
		(start 223.13 117.009706)
		(end 222.940294 116.82)
		(width 0.09)
		(layer "In2.Cu")
		(net 72)
	)
	(segment
		(start 220.549706 117.57)
		(end 219.850294 117.57)
		(width 0.09)
		(layer "In2.Cu")
		(net 72)
	)
	(segment
		(start 211.911748 117.351454)
		(end 210.318252 117.351454)
		(width 0.09)
		(layer "In2.Cu")
		(net 72)
	)
	(segment
		(start 222.15 118.28)
		(end 222.92 118.28)
		(width 0.09)
		(layer "In2.Cu")
		(net 72)
	)
	(segment
		(start 219.850294 117.57)
		(end 219.400294 117.12)
		(width 0.09)
		(layer "In2.Cu")
		(net 72)
	)
	(segment
		(start 208.602 116.93)
		(end 208.472 116.8)
		(width 0.09)
		(layer "In2.Cu")
		(net 72)
	)
	(segment
		(start 212.380294 117.82)
		(end 211.911748 117.351454)
		(width 0.09)
		(layer "In2.Cu")
		(net 72)
	)
	(segment
		(start 221.115 118.28)
		(end 221.49 118.28)
		(width 0.09)
		(layer "In2.Cu")
		(net 72)
	)
	(segment
		(start 221 118.165)
		(end 221.115 118.28)
		(width 0.09)
		(layer "In2.Cu")
		(net 72)
	)
	(segment
		(start 210.089706 117.58)
		(end 209.070294 117.58)
		(width 0.09)
		(layer "In2.Cu")
		(net 72)
	)
	(segment
		(start 223.13 118.07)
		(end 223.13 117.009706)
		(width 0.09)
		(layer "In2.Cu")
		(net 72)
	)
	(segment
		(start 209.070294 117.58)
		(end 208.602 117.111706)
		(width 0.09)
		(layer "In2.Cu")
		(net 72)
	)
	(segment
		(start 219.400294 117.12)
		(end 213.999706 117.12)
		(width 0.09)
		(layer "In2.Cu")
		(net 72)
	)
	(segment
		(start 221.655 118.115)
		(end 221.655 118.104291)
		(width 0.09)
		(layer "In2.Cu")
		(net 72)
	)
	(segment
		(start 221.985 118.104291)
		(end 221.985 118.115)
		(width 0.09)
		(layer "In2.Cu")
		(net 72)
	)
	(segment
		(start 210.318252 117.351454)
		(end 210.089706 117.58)
		(width 0.09)
		(layer "In2.Cu")
		(net 72)
	)
	(segment
		(start 213.999706 117.12)
		(end 213.299706 117.82)
		(width 0.09)
		(layer "In2.Cu")
		(net 72)
	)
	(segment
		(start 221.299706 116.82)
		(end 220.549706 117.57)
		(width 0.09)
		(layer "In2.Cu")
		(net 72)
	)
	(segment
		(start 213.299706 117.82)
		(end 212.380294 117.82)
		(width 0.09)
		(layer "In2.Cu")
		(net 72)
	)
	(segment
		(start 208.602 117.111706)
		(end 208.602 116.93)
		(width 0.09)
		(layer "In2.Cu")
		(net 72)
	)
	(segment
		(start 222.940294 116.82)
		(end 221.299706 116.82)
		(width 0.09)
		(layer "In2.Cu")
		(net 72)
	)
	(arc
		(start 221.49 118.28)
		(mid 221.606673 118.231673)
		(end 221.655 118.115)
		(width 0.09)
		(layer "In2.Cu")
		(net 72)
	)
	(arc
		(start 221.985 118.115)
		(mid 222.033327 118.231673)
		(end 222.15 118.28)
		(width 0.09)
		(layer "In2.Cu")
		(net 72)
	)
	(arc
		(start 221.82 117.939291)
		(mid 221.936673 117.987618)
		(end 221.985 118.104291)
		(width 0.09)
		(layer "In2.Cu")
		(net 72)
	)
	(arc
		(start 221.655 118.104291)
		(mid 221.703327 117.987618)
		(end 221.82 117.939291)
		(width 0.09)
		(layer "In2.Cu")
		(net 72)
	)
	(segment
		(start 220.275 121.15)
		(end 220.56 121.15)
		(width 0.1)
		(layer "F.Cu")
		(net 73)
	)
	(segment
		(start 220.7 121.29)
		(end 220.875 121.29)
		(width 0.1)
		(layer "F.Cu")
		(net 73)
	)
	(segment
		(start 220.875 121.29)
		(end 221 121.165)
		(width 0.1)
		(layer "F.Cu")
		(net 73)
	)
	(segment
		(start 220.56 121.15)
		(end 220.7 121.29)
		(width 0.1)
		(layer "F.Cu")
		(net 73)
	)
	(via
		(at 221 121.165)
		(size 0.35)
		(drill 0.15)
		(layers "F.Cu" "B.Cu")
		(remove_unused_layers yes)
		(keep_end_layers yes)
		(zone_layer_connections)
		(net 73)
	)
	(via
		(at 209.326 118.52)
		(size 0.35)
		(drill 0.15)
		(layers "F.Cu" "B.Cu")
		(remove_unused_layers yes)
		(keep_end_layers yes)
		(zone_layer_connections)
		(net 73)
	)
	(segment
		(start 209.323 118.52)
		(end 209.1455 118.6975)
		(width 0.1)
		(layer "B.Cu")
		(net 73)
	)
	(segment
		(start 208.6095 118.994936)
		(end 208.6095 119.8685)
		(width 0.1)
		(layer "B.Cu")
		(net 73)
	)
	(segment
		(start 209.1455 118.6975)
		(end 208.906936 118.6975)
		(width 0.1)
		(layer "B.Cu")
		(net 73)
	)
	(segment
		(start 208.906936 118.6975)
		(end 208.6095 118.994936)
		(width 0.1)
		(layer "B.Cu")
		(net 73)
	)
	(segment
		(start 208.522 119.956)
		(end 208.522 120.171)
		(width 0.1)
		(layer "B.Cu")
		(net 73)
	)
	(segment
		(start 208.6095 119.8685)
		(end 208.522 119.956)
		(width 0.1)
		(layer "B.Cu")
		(net 73)
	)
	(segment
		(start 212.779706 121.08)
		(end 215.87 121.08)
		(width 0.09)
		(layer "In2.Cu")
		(net 73)
	)
	(segment
		(start 216.545 120.431047)
		(end 216.545 121.61895)
		(width 0.09)
		(layer "In2.Cu")
		(net 73)
	)
	(segment
		(start 219.769706 121.28)
		(end 219.569706 121.08)
		(width 0.09)
		(layer "In2.Cu")
		(net 73)
	)
	(segment
		(start 217.605 120.43105)
		(end 217.605 121.61895)
		(width 0.09)
		(layer "In2.Cu")
		(net 73)
	)
	(segment
		(start 216.255 121.61895)
		(end 216.255 121.465)
		(width 0.09)
		(layer "In2.Cu")
		(net 73)
	)
	(segment
		(start 209.4935 118.6875)
		(end 209.326 118.52)
		(width 0.09)
		(layer "In2.Cu")
		(net 73)
	)
	(segment
		(start 220.885 121.28)
		(end 219.769706 121.28)
		(width 0.09)
		(layer "In2.Cu")
		(net 73)
	)
	(segment
		(start 211.769706 120.53)
		(end 209.927206 118.6875)
		(width 0.09)
		(layer "In2.Cu")
		(net 73)
	)
	(segment
		(start 209.927206 118.6875)
		(end 209.4935 118.6875)
		(width 0.09)
		(layer "In2.Cu")
		(net 73)
	)
	(segment
		(start 217.315 121.61895)
		(end 217.315 120.431047)
		(width 0.09)
		(layer "In2.Cu")
		(net 73)
	)
	(segment
		(start 218.375 120.935)
		(end 218.375 120.43105)
		(width 0.09)
		(layer "In2.Cu")
		(net 73)
	)
	(segment
		(start 212.229706 120.53)
		(end 211.769706 120.53)
		(width 0.09)
		(layer "In2.Cu")
		(net 73)
	)
	(segment
		(start 219.569706 121.08)
		(end 218.52 121.08)
		(width 0.09)
		(layer "In2.Cu")
		(net 73)
	)
	(segment
		(start 221 121.165)
		(end 220.885 121.28)
		(width 0.09)
		(layer "In2.Cu")
		(net 73)
	)
	(segment
		(start 212.779706 121.08)
		(end 212.229706 120.53)
		(width 0.09)
		(layer "In2.Cu")
		(net 73)
	)
	(arc
		(start 217.99 120.04605)
		(mid 217.717764 120.158814)
		(end 217.605 120.43105)
		(width 0.09)
		(layer "In2.Cu")
		(net 73)
	)
	(arc
		(start 216.255 121.465)
		(mid 216.142236 121.192764)
		(end 215.87 121.08)
		(width 0.09)
		(layer "In2.Cu")
		(net 73)
	)
	(arc
		(start 216.545 121.61895)
		(mid 216.50253 121.72148)
		(end 216.4 121.76395)
		(width 0.09)
		(layer "In2.Cu")
		(net 73)
	)
	(arc
		(start 216.93 120.046047)
		(mid 216.657764 120.158811)
		(end 216.545 120.431047)
		(width 0.09)
		(layer "In2.Cu")
		(net 73)
	)
	(arc
		(start 218.52 121.08)
		(mid 218.41747 121.03753)
		(end 218.375 120.935)
		(width 0.09)
		(layer "In2.Cu")
		(net 73)
	)
	(arc
		(start 217.315 120.431047)
		(mid 217.202236 120.158811)
		(end 216.93 120.046047)
		(width 0.09)
		(layer "In2.Cu")
		(net 73)
	)
	(arc
		(start 216.4 121.76395)
		(mid 216.29747 121.72148)
		(end 216.255 121.61895)
		(width 0.09)
		(layer "In2.Cu")
		(net 73)
	)
	(arc
		(start 217.46 121.76395)
		(mid 217.35747 121.72148)
		(end 217.315 121.61895)
		(width 0.09)
		(layer "In2.Cu")
		(net 73)
	)
	(arc
		(start 217.605 121.61895)
		(mid 217.56253 121.72148)
		(end 217.46 121.76395)
		(width 0.09)
		(layer "In2.Cu")
		(net 73)
	)
	(arc
		(start 218.375 120.43105)
		(mid 218.262236 120.158814)
		(end 217.99 120.04605)
		(width 0.09)
		(layer "In2.Cu")
		(net 73)
	)
	(segment
		(start 220.56 119.65)
		(end 220.7 119.79)
		(width 0.1)
		(layer "F.Cu")
		(net 74)
	)
	(segment
		(start 220.7 119.79)
		(end 220.875 119.79)
		(width 0.1)
		(layer "F.Cu")
		(net 74)
	)
	(segment
		(start 220.875 119.79)
		(end 221 119.665)
		(width 0.1)
		(layer "F.Cu")
		(net 74)
	)
	(segment
		(start 220.275 119.65)
		(end 220.56 119.65)
		(width 0.1)
		(layer "F.Cu")
		(net 74)
	)
	(via
		(at 207.767 116.8)
		(size 0.35)
		(drill 0.15)
		(layers "F.Cu" "B.Cu")
		(remove_unused_layers yes)
		(keep_end_layers yes)
		(zone_layer_connections)
		(net 74)
	)
	(via
		(at 221 119.665)
		(size 0.35)
		(drill 0.15)
		(layers "F.Cu" "B.Cu")
		(remove_unused_layers yes)
		(keep_end_layers yes)
		(zone_layer_connections)
		(net 74)
	)
	(segment
		(start 207.6295 117.1585)
		(end 207.6295 117.044855)
		(width 0.1)
		(layer "B.Cu")
		(net 74)
	)
	(segment
		(start 207.6295 117.044855)
		(end 207.627 117.042355)
		(width 0.1)
		(layer "B.Cu")
		(net 74)
	)
	(segment
		(start 207.717 117.461)
		(end 207.717 117.246)
		(width 0.1)
		(layer "B.Cu")
		(net 74)
	)
	(segment
		(start 207.717 117.246)
		(end 207.6295 117.1585)
		(width 0.1)
		(layer "B.Cu")
		(net 74)
	)
	(segment
		(start 207.627 116.94)
		(end 207.767 116.8)
		(width 0.1)
		(layer "B.Cu")
		(net 74)
	)
	(segment
		(start 207.627 117.042355)
		(end 207.627 116.94)
		(width 0.1)
		(layer "B.Cu")
		(net 74)
	)
	(segment
		(start 210.937125 117.782875)
		(end 210.937125 117.782874)
		(width 0.09)
		(layer "In2.Cu")
		(net 74)
	)
	(segment
		(start 215.615 119.515)
		(end 215.615 119.857248)
		(width 0.09)
		(layer "In2.Cu")
		(net 74)
	)
	(segment
		(start 211.187125 117.782874)
		(end 211.187125 117.782875)
		(width 0.09)
		(layer "In2.Cu")
		(net 74)
	)
	(segment
		(start 208.399706 117.3)
		(end 208.969706 117.87)
		(width 0.09)
		(layer "In2.Cu")
		(net 74)
	)
	(segment
		(start 211.02425 117.695749)
		(end 211.1 117.695749)
		(width 0.09)
		(layer "In2.Cu")
		(net 74)
	)
	(segment
		(start 213.775 119.56)
		(end 213.945294 119.56)
		(width 0.09)
		(layer "In2.Cu")
		(net 74)
	)
	(segment
		(start 214.375294 119.13)
		(end 215.23 119.13)
		(width 0.09)
		(layer "In2.Cu")
		(net 74)
	)
	(segment
		(start 220.885 119.78)
		(end 221 119.665)
		(width 0.09)
		(layer "In2.Cu")
		(net 74)
	)
	(segment
		(start 208.969706 117.87)
		(end 210.35 117.87)
		(width 0.09)
		(layer "In2.Cu")
		(net 74)
	)
	(segment
		(start 210.524148 117.695851)
		(end 210.6 117.695851)
		(width 0.09)
		(layer "In2.Cu")
		(net 74)
	)
	(segment
		(start 210.437074 117.782926)
		(end 210.437074 117.782925)
		(width 0.09)
		(layer "In2.Cu")
		(net 74)
	)
	(segment
		(start 207.767 116.8)
		(end 207.637 116.93)
		(width 0.09)
		(layer "In2.Cu")
		(net 74)
	)
	(segment
		(start 212.755 119.38)
		(end 212.755 118.46)
		(width 0.09)
		(layer "In2.Cu")
		(net 74)
	)
	(segment
		(start 211.87 118.370294)
		(end 211.87 119.220294)
		(width 0.09)
		(layer "In2.Cu")
		(net 74)
	)
	(segment
		(start 207.637 116.93)
		(end 207.637 117.141461)
		(width 0.09)
		(layer "In2.Cu")
		(net 74)
	)
	(segment
		(start 207.795539 117.3)
		(end 208.399706 117.3)
		(width 0.09)
		(layer "In2.Cu")
		(net 74)
	)
	(segment
		(start 207.637 117.141461)
		(end 207.795539 117.3)
		(width 0.09)
		(layer "In2.Cu")
		(net 74)
	)
	(segment
		(start 211.87 119.220294)
		(end 212.209706 119.56)
		(width 0.09)
		(layer "In2.Cu")
		(net 74)
	)
	(segment
		(start 211.27425 117.87)
		(end 211.369706 117.87)
		(width 0.09)
		(layer "In2.Cu")
		(net 74)
	)
	(segment
		(start 216.29 119.13)
		(end 219.199706 119.13)
		(width 0.09)
		(layer "In2.Cu")
		(net 74)
	)
	(segment
		(start 219.199706 119.13)
		(end 219.849706 119.78)
		(width 0.09)
		(layer "In2.Cu")
		(net 74)
	)
	(segment
		(start 213.595 118.46)
		(end 213.595 119.38)
		(width 0.09)
		(layer "In2.Cu")
		(net 74)
	)
	(segment
		(start 213.945294 119.56)
		(end 214.375294 119.13)
		(width 0.09)
		(layer "In2.Cu")
		(net 74)
	)
	(segment
		(start 210.774148 117.87)
		(end 210.85 117.87)
		(width 0.09)
		(layer "In2.Cu")
		(net 74)
	)
	(segment
		(start 210.687074 117.782925)
		(end 210.687074 117.782926)
		(width 0.09)
		(layer "In2.Cu")
		(net 74)
	)
	(segment
		(start 215.905 119.857248)
		(end 215.905 119.515)
		(width 0.09)
		(layer "In2.Cu")
		(net 74)
	)
	(segment
		(start 212.209706 119.56)
		(end 212.575 119.56)
		(width 0.09)
		(layer "In2.Cu")
		(net 74)
	)
	(segment
		(start 211.369706 117.87)
		(end 211.87 118.370294)
		(width 0.09)
		(layer "In2.Cu")
		(net 74)
	)
	(segment
		(start 219.849706 119.78)
		(end 220.885 119.78)
		(width 0.09)
		(layer "In2.Cu")
		(net 74)
	)
	(arc
		(start 211.1 117.695749)
		(mid 211.161607 117.721267)
		(end 211.187125 117.782874)
		(width 0.09)
		(layer "In2.Cu")
		(net 74)
	)
	(arc
		(start 211.187125 117.782875)
		(mid 211.212643 117.844482)
		(end 211.27425 117.87)
		(width 0.09)
		(layer "In2.Cu")
		(net 74)
	)
	(arc
		(start 210.437074 117.782925)
		(mid 210.462577 117.721354)
		(end 210.524148 117.695851)
		(width 0.09)
		(layer "In2.Cu")
		(net 74)
	)
	(arc
		(start 215.615 119.857248)
		(mid 215.65747 119.959778)
		(end 215.76 120.002248)
		(width 0.09)
		(layer "In2.Cu")
		(net 74)
	)
	(arc
		(start 210.937125 117.782874)
		(mid 210.962643 117.721267)
		(end 211.02425 117.695749)
		(width 0.09)
		(layer "In2.Cu")
		(net 74)
	)
	(arc
		(start 212.575 119.56)
		(mid 212.702279 119.507279)
		(end 212.755 119.38)
		(width 0.09)
		(layer "In2.Cu")
		(net 74)
	)
	(arc
		(start 215.76 120.002248)
		(mid 215.86253 119.959778)
		(end 215.905 119.857248)
		(width 0.09)
		(layer "In2.Cu")
		(net 74)
	)
	(arc
		(start 210.6 117.695851)
		(mid 210.661571 117.721354)
		(end 210.687074 117.782925)
		(width 0.09)
		(layer "In2.Cu")
		(net 74)
	)
	(arc
		(start 215.23 119.13)
		(mid 215.502236 119.242764)
		(end 215.615 119.515)
		(width 0.09)
		(layer "In2.Cu")
		(net 74)
	)
	(arc
		(start 210.85 117.87)
		(mid 210.911607 117.844482)
		(end 210.937125 117.782875)
		(width 0.09)
		(layer "In2.Cu")
		(net 74)
	)
	(arc
		(start 210.687074 117.782926)
		(mid 210.712577 117.844497)
		(end 210.774148 117.87)
		(width 0.09)
		(layer "In2.Cu")
		(net 74)
	)
	(arc
		(start 212.755 118.46)
		(mid 212.878015 118.163015)
		(end 213.175 118.04)
		(width 0.09)
		(layer "In2.Cu")
		(net 74)
	)
	(arc
		(start 213.175 118.04)
		(mid 213.471985 118.163015)
		(end 213.595 118.46)
		(width 0.09)
		(layer "In2.Cu")
		(net 74)
	)
	(arc
		(start 215.905 119.515)
		(mid 216.017764 119.242764)
		(end 216.29 119.13)
		(width 0.09)
		(layer "In2.Cu")
		(net 74)
	)
	(arc
		(start 210.35 117.87)
		(mid 210.411571 117.844497)
		(end 210.437074 117.782926)
		(width 0.09)
		(layer "In2.Cu")
		(net 74)
	)
	(arc
		(start 213.595 119.38)
		(mid 213.647721 119.507279)
		(end 213.775 119.56)
		(width 0.09)
		(layer "In2.Cu")
		(net 74)
	)
	(segment
		(start 220.875 122.79)
		(end 221 122.665)
		(width 0.1)
		(layer "F.Cu")
		(net 75)
	)
	(segment
		(start 220.56 122.65)
		(end 220.7 122.79)
		(width 0.1)
		(layer "F.Cu")
		(net 75)
	)
	(segment
		(start 220.7 122.79)
		(end 220.875 122.79)
		(width 0.1)
		(layer "F.Cu")
		(net 75)
	)
	(segment
		(start 220.275 122.65)
		(end 220.56 122.65)
		(width 0.1)
		(layer "F.Cu")
		(net 75)
	)
	(via
		(at 208.123 119.095)
		(size 0.35)
		(drill 0.15)
		(layers "F.Cu" "B.Cu")
		(remove_unused_layers yes)
		(keep_end_layers yes)
		(zone_layer_connections)
		(net 75)
	)
	(via
		(at 221 122.665)
		(size 0.35)
		(drill 0.15)
		(layers "F.Cu" "B.Cu")
		(remove_unused_layers yes)
		(keep_end_layers yes)
		(zone_layer_connections)
		(net 75)
	)
	(segment
		(start 207.6295 119.8685)
		(end 207.717 119.956)
		(width 0.1)
		(layer "B.Cu")
		(net 75)
	)
	(segment
		(start 207.9455 118.9175)
		(end 207.798064 118.9175)
		(width 0.1)
		(layer "B.Cu")
		(net 75)
	)
	(segment
		(start 207.717 119.956)
		(end 207.717 120.171)
		(width 0.1)
		(layer "B.Cu")
		(net 75)
	)
	(segment
		(start 207.6295 119.086064)
		(end 207.6295 119.8685)
		(width 0.1)
		(layer "B.Cu")
		(net 75)
	)
	(segment
		(start 208.123 119.095)
		(end 207.9455 118.9175)
		(width 0.1)
		(layer "B.Cu")
		(net 75)
	)
	(segment
		(start 207.798064 118.9175)
		(end 207.6295 119.086064)
		(width 0.1)
		(layer "B.Cu")
		(net 75)
	)
	(segment
		(start 215.450294 124.18)
		(end 215.900294 123.73)
		(width 0.09)
		(layer "In2.Cu")
		(net 75)
	)
	(segment
		(start 219.030294 123.73)
		(end 219.980294 122.78)
		(width 0.09)
		(layer "In2.Cu")
		(net 75)
	)
	(segment
		(start 215.900294 123.73)
		(end 219.030294 123.73)
		(width 0.09)
		(layer "In2.Cu")
		(net 75)
	)
	(segment
		(start 207.6 119.119706)
		(end 207.6 119.175)
		(width 0.09)
		(layer "In2.Cu")
		(net 75)
	)
	(segment
		(start 209.784444 120.155946)
		(end 209.831824 120.203326)
		(width 0.09)
		(layer "In2.Cu")
		(net 75)
	)
	(segment
		(start 209.655049 120.155945)
		(end 209.655048 120.155946)
		(width 0.09)
		(layer "In2.Cu")
		(net 75)
	)
	(segment
		(start 209.275 120.155946)
		(end 209.525652 120.155946)
		(width 0.09)
		(layer "In2.Cu")
		(net 75)
	)
	(segment
		(start 210.008553 120.509499)
		(end 210.008554 120.509499)
		(width 0.09)
		(layer "In2.Cu")
		(net 75)
	)
	(segment
		(start 210.185328 120.815622)
		(end 211.47 122.100294)
		(width 0.09)
		(layer "In2.Cu")
		(net 75)
	)
	(segment
		(start 210.008554 120.509498)
		(end 210.008553 120.509499)
		(width 0.09)
		(layer "In2.Cu")
		(net 75)
	)
	(segment
		(start 219.980294 122.78)
		(end 220.885 122.78)
		(width 0.09)
		(layer "In2.Cu")
		(net 75)
	)
	(segment
		(start 208.975 119.955946)
		(end 209.075 119.955946)
		(width 0.09)
		(layer "In2.Cu")
		(net 75)
	)
	(segment
		(start 207.6 119.675)
		(end 207.6 119.890294)
		(width 0.09)
		(layer "In2.Cu")
		(net 75)
	)
	(segment
		(start 212.599706 124.18)
		(end 215.450294 124.18)
		(width 0.09)
		(layer "In2.Cu")
		(net 75)
	)
	(segment
		(start 208.375 119.955946)
		(end 208.475 119.955946)
		(width 0.09)
		(layer "In2.Cu")
		(net 75)
	)
	(segment
		(start 208.123 119.095)
		(end 207.9555 118.9275)
		(width 0.09)
		(layer "In2.Cu")
		(net 75)
	)
	(segment
		(start 210.137902 120.509499)
		(end 210.18533 120.556927)
		(width 0.09)
		(layer "In2.Cu")
		(net 75)
	)
	(segment
		(start 210.18533 120.686275)
		(end 210.185328 120.686274)
		(width 0.09)
		(layer "In2.Cu")
		(net 75)
	)
	(segment
		(start 207.9555 118.9275)
		(end 207.792206 118.9275)
		(width 0.09)
		(layer "In2.Cu")
		(net 75)
	)
	(segment
		(start 209.831824 120.462118)
		(end 209.879205 120.509499)
		(width 0.09)
		(layer "In2.Cu")
		(net 75)
	)
	(segment
		(start 211.47 122.100294)
		(end 211.47 123.050294)
		(width 0.09)
		(layer "In2.Cu")
		(net 75)
	)
	(segment
		(start 208.675 120.155946)
		(end 208.775 120.155946)
		(width 0.09)
		(layer "In2.Cu")
		(net 75)
	)
	(segment
		(start 220.885 122.78)
		(end 221 122.665)
		(width 0.09)
		(layer "In2.Cu")
		(net 75)
	)
	(segment
		(start 207.6 119.890294)
		(end 207.865652 120.155946)
		(width 0.09)
		(layer "In2.Cu")
		(net 75)
	)
	(segment
		(start 207.865652 120.155946)
		(end 208.175 120.155946)
		(width 0.09)
		(layer "In2.Cu")
		(net 75)
	)
	(segment
		(start 207.792206 118.9275)
		(end 207.6 119.119706)
		(width 0.09)
		(layer "In2.Cu")
		(net 75)
	)
	(segment
		(start 211.47 123.050294)
		(end 212.599706 124.18)
		(width 0.09)
		(layer "In2.Cu")
		(net 75)
	)
	(arc
		(start 207.725 119.3)
		(mid 207.813388 119.336612)
		(end 207.85 119.425)
		(width 0.09)
		(layer "In2.Cu")
		(net 75)
	)
	(arc
		(start 208.475 119.955946)
		(mid 208.545711 119.985235)
		(end 208.575 120.055946)
		(width 0.09)
		(layer "In2.Cu")
		(net 75)
	)
	(arc
		(start 208.775 120.155946)
		(mid 208.845711 120.126657)
		(end 208.875 120.055946)
		(width 0.09)
		(layer "In2.Cu")
		(net 75)
	)
	(arc
		(start 209.175 120.055946)
		(mid 209.204289 120.126657)
		(end 209.275 120.155946)
		(width 0.09)
		(layer "In2.Cu")
		(net 75)
	)
	(arc
		(start 209.831824 120.332722)
		(mid 209.805026 120.397421)
		(end 209.831824 120.462118)
		(width 0.09)
		(layer "In2.Cu")
		(net 75)
	)
	(arc
		(start 207.85 119.425)
		(mid 207.813388 119.513388)
		(end 207.725 119.55)
		(width 0.09)
		(layer "In2.Cu")
		(net 75)
	)
	(arc
		(start 210.008554 120.509499)
		(mid 210.073227 120.482709)
		(end 210.137902 120.509499)
		(width 0.09)
		(layer "In2.Cu")
		(net 75)
	)
	(arc
		(start 210.185328 120.686274)
		(mid 210.15854 120.750949)
		(end 210.185328 120.815622)
		(width 0.09)
		(layer "In2.Cu")
		(net 75)
	)
	(arc
		(start 207.6 119.175)
		(mid 207.636612 119.263388)
		(end 207.725 119.3)
		(width 0.09)
		(layer "In2.Cu")
		(net 75)
	)
	(arc
		(start 208.575 120.055946)
		(mid 208.604289 120.126657)
		(end 208.675 120.155946)
		(width 0.09)
		(layer "In2.Cu")
		(net 75)
	)
	(arc
		(start 208.875 120.055946)
		(mid 208.904289 119.985235)
		(end 208.975 119.955946)
		(width 0.09)
		(layer "In2.Cu")
		(net 75)
	)
	(arc
		(start 209.879205 120.509499)
		(mid 209.94388 120.536288)
		(end 210.008554 120.509498)
		(width 0.09)
		(layer "In2.Cu")
		(net 75)
	)
	(arc
		(start 209.655048 120.155946)
		(mid 209.719747 120.129148)
		(end 209.784444 120.155946)
		(width 0.09)
		(layer "In2.Cu")
		(net 75)
	)
	(arc
		(start 208.275 120.055946)
		(mid 208.304289 119.985235)
		(end 208.375 119.955946)
		(width 0.09)
		(layer "In2.Cu")
		(net 75)
	)
	(arc
		(start 209.831824 120.203326)
		(mid 209.858624 120.268025)
		(end 209.831824 120.332722)
		(width 0.09)
		(layer "In2.Cu")
		(net 75)
	)
	(arc
		(start 209.525652 120.155946)
		(mid 209.590352 120.182745)
		(end 209.655049 120.155945)
		(width 0.09)
		(layer "In2.Cu")
		(net 75)
	)
	(arc
		(start 209.075 119.955946)
		(mid 209.145711 119.985235)
		(end 209.175 120.055946)
		(width 0.09)
		(layer "In2.Cu")
		(net 75)
	)
	(arc
		(start 210.18533 120.556927)
		(mid 210.212118 120.6216)
		(end 210.18533 120.686275)
		(width 0.09)
		(layer "In2.Cu")
		(net 75)
	)
	(arc
		(start 207.725 119.55)
		(mid 207.636612 119.586612)
		(end 207.6 119.675)
		(width 0.09)
		(layer "In2.Cu")
		(net 75)
	)
	(arc
		(start 208.175 120.155946)
		(mid 208.245711 120.126657)
		(end 208.275 120.055946)
		(width 0.09)
		(layer "In2.Cu")
		(net 75)
	)
	(segment
		(start 220.7 120.01)
		(end 220.875 120.01)
		(width 0.1)
		(layer "F.Cu")
		(net 76)
	)
	(segment
		(start 220.275 120.15)
		(end 220.56 120.15)
		(width 0.1)
		(layer "F.Cu")
		(net 76)
	)
	(segment
		(start 220.875 120.01)
		(end 221 120.135)
		(width 0.1)
		(layer "F.Cu")
		(net 76)
	)
	(segment
		(start 220.56 120.15)
		(end 220.7 120.01)
		(width 0.1)
		(layer "F.Cu")
		(net 76)
	)
	(via
		(at 207.267 116.8)
		(size 0.35)
		(drill 0.15)
		(layers "F.Cu" "B.Cu")
		(remove_unused_layers yes)
		(keep_end_layers yes)
		(zone_layer_connections)
		(net 76)
	)
	(via
		(at 221 120.135)
		(size 0.35)
		(drill 0.15)
		(layers "F.Cu" "B.Cu")
		(remove_unused_layers yes)
		(keep_end_layers yes)
		(zone_layer_connections)
		(net 76)
	)
	(segment
		(start 207.4095 117.129045)
		(end 207.407 117.126545)
		(width 0.1)
		(layer "B.Cu")
		(net 76)
	)
	(segment
		(start 207.322 117.246)
		(end 207.4095 117.1585)
		(width 0.1)
		(layer "B.Cu")
		(net 76)
	)
	(segment
		(start 207.407 117.126545)
		(end 207.407 116.94)
		(width 0.1)
		(layer "B.Cu")
		(net 76)
	)
	(segment
		(start 207.322 117.461)
		(end 207.322 117.246)
		(width 0.1)
		(layer "B.Cu")
		(net 76)
	)
	(segment
		(start 207.4095 117.1585)
		(end 207.4095 117.129045)
		(width 0.1)
		(layer "B.Cu")
		(net 76)
	)
	(segment
		(start 207.407 116.94)
		(end 207.267 116.8)
		(width 0.1)
		(layer "B.Cu")
		(net 76)
	)
	(segment
		(start 213.355 118.46)
		(end 213.355 119.38)
		(width 0.09)
		(layer "In2.Cu")
		(net 76)
	)
	(segment
		(start 208.870294 118.11)
		(end 211.270294 118.11)
		(width 0.09)
		(layer "In2.Cu")
		(net 76)
	)
	(segment
		(start 220.885 120.02)
		(end 221 120.135)
		(width 0.09)
		(layer "In2.Cu")
		(net 76)
	)
	(segment
		(start 207.267 116.8)
		(end 207.397 116.93)
		(width 0.09)
		(layer "In2.Cu")
		(net 76)
	)
	(segment
		(start 211.63 118.469706)
		(end 211.63 119.319706)
		(width 0.09)
		(layer "In2.Cu")
		(net 76)
	)
	(segment
		(start 213.775 119.8)
		(end 214.044706 119.8)
		(width 0.09)
		(layer "In2.Cu")
		(net 76)
	)
	(segment
		(start 214.474706 119.37)
		(end 215.23 119.37)
		(width 0.09)
		(layer "In2.Cu")
		(net 76)
	)
	(segment
		(start 211.270294 118.11)
		(end 211.63 118.469706)
		(width 0.09)
		(layer "In2.Cu")
		(net 76)
	)
	(segment
		(start 211.63 119.319706)
		(end 212.110294 119.8)
		(width 0.09)
		(layer "In2.Cu")
		(net 76)
	)
	(segment
		(start 207.397 117.240873)
		(end 207.696127 117.54)
		(width 0.09)
		(layer "In2.Cu")
		(net 76)
	)
	(segment
		(start 219.750294 120.02)
		(end 220.885 120.02)
		(width 0.09)
		(layer "In2.Cu")
		(net 76)
	)
	(segment
		(start 215.375 119.515)
		(end 215.375 119.857248)
		(width 0.09)
		(layer "In2.Cu")
		(net 76)
	)
	(segment
		(start 216.29 119.37)
		(end 219.100294 119.37)
		(width 0.09)
		(layer "In2.Cu")
		(net 76)
	)
	(segment
		(start 207.696127 117.54)
		(end 208.300294 117.54)
		(width 0.09)
		(layer "In2.Cu")
		(net 76)
	)
	(segment
		(start 207.397 116.93)
		(end 207.397 117.240873)
		(width 0.09)
		(layer "In2.Cu")
		(net 76)
	)
	(segment
		(start 208.300294 117.54)
		(end 208.870294 118.11)
		(width 0.09)
		(layer "In2.Cu")
		(net 76)
	)
	(segment
		(start 219.100294 119.37)
		(end 219.750294 120.02)
		(width 0.09)
		(layer "In2.Cu")
		(net 76)
	)
	(segment
		(start 214.044706 119.8)
		(end 214.474706 119.37)
		(width 0.09)
		(layer "In2.Cu")
		(net 76)
	)
	(segment
		(start 212.995 119.38)
		(end 212.995 118.46)
		(width 0.09)
		(layer "In2.Cu")
		(net 76)
	)
	(segment
		(start 212.110294 119.8)
		(end 212.575 119.8)
		(width 0.09)
		(layer "In2.Cu")
		(net 76)
	)
	(segment
		(start 216.145 119.857248)
		(end 216.145 119.515)
		(width 0.09)
		(layer "In2.Cu")
		(net 76)
	)
	(arc
		(start 213.175 118.28)
		(mid 213.302279 118.332721)
		(end 213.355 118.46)
		(width 0.09)
		(layer "In2.Cu")
		(net 76)
	)
	(arc
		(start 212.995 118.46)
		(mid 213.047721 118.332721)
		(end 213.175 118.28)
		(width 0.09)
		(layer "In2.Cu")
		(net 76)
	)
	(arc
		(start 213.355 119.38)
		(mid 213.478015 119.676985)
		(end 213.775 119.8)
		(width 0.09)
		(layer "In2.Cu")
		(net 76)
	)
	(arc
		(start 215.76 120.242248)
		(mid 216.032236 120.129484)
		(end 216.145 119.857248)
		(width 0.09)
		(layer "In2.Cu")
		(net 76)
	)
	(arc
		(start 215.375 119.857248)
		(mid 215.487764 120.129484)
		(end 215.76 120.242248)
		(width 0.09)
		(layer "In2.Cu")
		(net 76)
	)
	(arc
		(start 216.145 119.515)
		(mid 216.18747 119.41247)
		(end 216.29 119.37)
		(width 0.09)
		(layer "In2.Cu")
		(net 76)
	)
	(arc
		(start 215.23 119.37)
		(mid 215.33253 119.41247)
		(end 215.375 119.515)
		(width 0.09)
		(layer "In2.Cu")
		(net 76)
	)
	(arc
		(start 212.575 119.8)
		(mid 212.871985 119.676985)
		(end 212.995 119.38)
		(width 0.09)
		(layer "In2.Cu")
		(net 76)
	)
	(segment
		(start 220.56 123.15)
		(end 220.7 123.01)
		(width 0.1)
		(layer "F.Cu")
		(net 77)
	)
	(segment
		(start 220.7 123.01)
		(end 220.875 123.01)
		(width 0.1)
		(layer "F.Cu")
		(net 77)
	)
	(segment
		(start 220.275 123.15)
		(end 220.56 123.15)
		(width 0.1)
		(layer "F.Cu")
		(net 77)
	)
	(segment
		(start 220.875 123.01)
		(end 221 123.135)
		(width 0.1)
		(layer "F.Cu")
		(net 77)
	)
	(via
		(at 208.123 118.52)
		(size 0.35)
		(drill 0.15)
		(layers "F.Cu" "B.Cu")
		(remove_unused_layers yes)
		(keep_end_layers yes)
		(zone_layer_connections)
		(net 77)
	)
	(via
		(at 221 123.135)
		(size 0.35)
		(drill 0.15)
		(layers "F.Cu" "B.Cu")
		(remove_unused_layers yes)
		(keep_end_layers yes)
		(zone_layer_connections)
		(net 77)
	)
	(segment
		(start 208.123 118.52)
		(end 207.9455 118.6975)
		(width 0.1)
		(layer "B.Cu")
		(net 77)
	)
	(segment
		(start 207.4095 118.994936)
		(end 207.4095 119.8685)
		(width 0.1)
		(layer "B.Cu")
		(net 77)
	)
	(segment
		(start 207.322 119.956)
		(end 207.322 120.171)
		(width 0.1)
		(layer "B.Cu")
		(net 77)
	)
	(segment
		(start 207.706936 118.6975)
		(end 207.4095 118.994936)
		(width 0.1)
		(layer "B.Cu")
		(net 77)
	)
	(segment
		(start 207.4095 119.8685)
		(end 207.322 119.956)
		(width 0.1)
		(layer "B.Cu")
		(net 77)
	)
	(segment
		(start 207.9455 118.6975)
		(end 207.706936 118.6975)
		(width 0.1)
		(layer "B.Cu")
		(net 77)
	)
	(segment
		(start 215.549706 124.42)
		(end 215.999706 123.97)
		(width 0.09)
		(layer "In2.Cu")
		(net 77)
	)
	(segment
		(start 220.885 123.02)
		(end 221 123.135)
		(width 0.09)
		(layer "In2.Cu")
		(net 77)
	)
	(segment
		(start 219.129706 123.97)
		(end 220.079706 123.02)
		(width 0.09)
		(layer "In2.Cu")
		(net 77)
	)
	(segment
		(start 212.500294 124.42)
		(end 215.549706 124.42)
		(width 0.09)
		(layer "In2.Cu")
		(net 77)
	)
	(segment
		(start 208.123 118.52)
		(end 207.9555 118.6875)
		(width 0.09)
		(layer "In2.Cu")
		(net 77)
	)
	(segment
		(start 207.36 119.020294)
		(end 207.36 119.989706)
		(width 0.09)
		(layer "In2.Cu")
		(net 77)
	)
	(segment
		(start 211.23 123.149706)
		(end 212.500294 124.42)
		(width 0.09)
		(layer "In2.Cu")
		(net 77)
	)
	(segment
		(start 215.999706 123.97)
		(end 219.129706 123.97)
		(width 0.09)
		(layer "In2.Cu")
		(net 77)
	)
	(segment
		(start 209.42624 120.395946)
		(end 211.23 122.199706)
		(width 0.09)
		(layer "In2.Cu")
		(net 77)
	)
	(segment
		(start 211.23 122.199706)
		(end 211.23 123.149706)
		(width 0.09)
		(layer "In2.Cu")
		(net 77)
	)
	(segment
		(start 207.692794 118.6875)
		(end 207.36 119.020294)
		(width 0.09)
		(layer "In2.Cu")
		(net 77)
	)
	(segment
		(start 207.36 119.989706)
		(end 207.76624 120.395946)
		(width 0.09)
		(layer "In2.Cu")
		(net 77)
	)
	(segment
		(start 207.76624 120.395946)
		(end 209.42624 120.395946)
		(width 0.09)
		(layer "In2.Cu")
		(net 77)
	)
	(segment
		(start 220.079706 123.02)
		(end 220.885 123.02)
		(width 0.09)
		(layer "In2.Cu")
		(net 77)
	)
	(segment
		(start 207.9555 118.6875)
		(end 207.692794 118.6875)
		(width 0.09)
		(layer "In2.Cu")
		(net 77)
	)
	(segment
		(start 206.87 117.05)
		(end 206.522 117.05)
		(width 0.1)
		(layer "F.Cu")
		(net 78)
	)
	(segment
		(start 218.05 123.875)
		(end 218.05 124.69)
		(width 0.1)
		(layer "F.Cu")
		(net 78)
	)
	(segment
		(start 218.05 124.69)
		(end 217.01 125.73)
		(width 0.1)
		(layer "F.Cu")
		(net 78)
	)
	(segment
		(start 213.4 125.73)
		(end 212.096 124.426)
		(width 0.1)
		(layer "F.Cu")
		(net 78)
	)
	(segment
		(start 207.794926 117.974926)
		(end 206.87 117.05)
		(width 0.1)
		(layer "F.Cu")
		(net 78)
	)
	(segment
		(start 207.794926 122.494926)
		(end 207.794926 117.974926)
		(width 0.1)
		(layer "F.Cu")
		(net 78)
	)
	(segment
		(start 212.096 124.426)
		(end 211.740794 124.426)
		(width 0.1)
		(layer "F.Cu")
		(net 78)
	)
	(segment
		(start 217.01 125.73)
		(end 213.4 125.73)
		(width 0.1)
		(layer "F.Cu")
		(net 78)
	)
	(segment
		(start 211.666794 124.5)
		(end 209.8 124.5)
		(width 0.1)
		(layer "F.Cu")
		(net 78)
	)
	(segment
		(start 209.8 124.5)
		(end 207.794926 122.494926)
		(width 0.1)
		(layer "F.Cu")
		(net 78)
	)
	(segment
		(start 211.740794 124.426)
		(end 211.666794 124.5)
		(width 0.1)
		(layer "F.Cu")
		(net 78)
	)
	(via
		(at 206.522 117.05)
		(size 0.35)
		(drill 0.15)
		(layers "F.Cu" "B.Cu")
		(remove_unused_layers yes)
		(keep_end_layers yes)
		(zone_layer_connections)
		(net 78)
	)
	(segment
		(start 214.65 124.7)
		(end 214.825 124.7)
		(width 0.1)
		(layer "F.Cu")
		(net 79)
	)
	(segment
		(start 214 125.35)
		(end 214.65 124.7)
		(width 0.1)
		(layer "F.Cu")
		(net 79)
	)
	(segment
		(start 213.75 125.35)
		(end 214 125.35)
		(width 0.1)
		(layer "F.Cu")
		(net 79)
	)
	(segment
		(start 215.05 124.475)
		(end 215.05 123.875)
		(width 0.1)
		(layer "F.Cu")
		(net 79)
	)
	(segment
		(start 214.825 124.7)
		(end 215.05 124.475)
		(width 0.1)
		(layer "F.Cu")
		(net 79)
	)
	(via
		(at 206.925 119.095)
		(size 0.35)
		(drill 0.15)
		(layers "F.Cu" "B.Cu")
		(remove_unused_layers yes)
		(keep_end_layers yes)
		(zone_layer_connections)
		(net 79)
	)
	(via
		(at 213.75 125.35)
		(size 0.35)
		(drill 0.15)
		(layers "F.Cu" "B.Cu")
		(remove_unused_layers yes)
		(keep_end_layers yes)
		(zone_layer_connections)
		(net 79)
	)
	(segment
		(start 206.788 119.095)
		(end 206.52 119.363)
		(width 0.15)
		(layer "B.Cu")
		(net 79)
	)
	(segment
		(start 206.52 119.363)
		(end 206.52 120.171)
		(width 0.15)
		(layer "B.Cu")
		(net 79)
	)
	(segment
		(start 206.925 119.095)
		(end 206.788 119.095)
		(width 0.15)
		(layer "B.Cu")
		(net 79)
	)
	(segment
		(start 213.41 122.95)
		(end 213.41 118.96038)
		(width 0.1)
		(layer "In9.Cu")
		(net 79)
	)
	(segment
		(start 213.41 118.96038)
		(end 211.94462 117.495)
		(width 0.1)
		(layer "In9.Cu")
		(net 79)
	)
	(segment
		(start 213.95 124.406794)
		(end 213.95 123.49)
		(width 0.1)
		(layer "In9.Cu")
		(net 79)
	)
	(segment
		(start 213.737 125.337)
		(end 213.737 124.619794)
		(width 0.1)
		(layer "In9.Cu")
		(net 79)
	)
	(segment
		(start 208.085 117.495)
		(end 207.26 118.32)
		(width 0.1)
		(layer "In9.Cu")
		(net 79)
	)
	(segment
		(start 213.737 124.619794)
		(end 213.95 124.406794)
		(width 0.1)
		(layer "In9.Cu")
		(net 79)
	)
	(segment
		(start 207.26 118.32)
		(end 207.26 118.76)
		(width 0.1)
		(layer "In9.Cu")
		(net 79)
	)
	(segment
		(start 213.75 125.35)
		(end 213.737 125.337)
		(width 0.1)
		(layer "In9.Cu")
		(net 79)
	)
	(segment
		(start 211.94462 117.495)
		(end 208.085 117.495)
		(width 0.1)
		(layer "In9.Cu")
		(net 79)
	)
	(segment
		(start 213.95 123.49)
		(end 213.41 122.95)
		(width 0.1)
		(layer "In9.Cu")
		(net 79)
	)
	(segment
		(start 207.26 118.76)
		(end 206.925 119.095)
		(width 0.1)
		(layer "In9.Cu")
		(net 79)
	)
	(segment
		(start 206.120973 117.290973)
		(end 206.32 117.49)
		(width 0.1)
		(layer "F.Cu")
		(net 80)
	)
	(segment
		(start 206.120973 116.84)
		(end 206.120973 117.290973)
		(width 0.1)
		(layer "F.Cu")
		(net 80)
	)
	(segment
		(start 206.99 117.49)
		(end 207.48 117.98)
		(width 0.1)
		(layer "F.Cu")
		(net 80)
	)
	(segment
		(start 207.48 117.98)
		(end 207.48 123.03)
		(width 0.1)
		(layer "F.Cu")
		(net 80)
	)
	(segment
		(start 210 125.55)
		(end 212.67 125.55)
		(width 0.1)
		(layer "F.Cu")
		(net 80)
	)
	(segment
		(start 213.12 126)
		(end 217.15 126)
		(width 0.1)
		(layer "F.Cu")
		(net 80)
	)
	(segment
		(start 217.15 126)
		(end 218.55 124.6)
		(width 0.1)
		(layer "F.Cu")
		(net 80)
	)
	(segment
		(start 207.48 123.03)
		(end 210 125.55)
		(width 0.1)
		(layer "F.Cu")
		(net 80)
	)
	(segment
		(start 218.55 124.6)
		(end 218.55 123.875)
		(width 0.1)
		(layer "F.Cu")
		(net 80)
	)
	(segment
		(start 212.67 125.55)
		(end 213.12 126)
		(width 0.1)
		(layer "F.Cu")
		(net 80)
	)
	(segment
		(start 206.32 117.49)
		(end 206.99 117.49)
		(width 0.1)
		(layer "F.Cu")
		(net 80)
	)
	(via
		(at 206.120973 116.84)
		(size 0.35)
		(drill 0.15)
		(layers "F.Cu" "B.Cu")
		(remove_unused_layers yes)
		(keep_end_layers yes)
		(zone_layer_connections)
		(net 80)
	)
	(segment
		(start 206.120973 116.84)
		(end 206.120973 117.459973)
		(width 0.15)
		(layer "B.Cu")
		(net 80)
	)
	(segment
		(start 206.120973 117.459973)
		(end 206.122 117.461)
		(width 0.15)
		(layer "B.Cu")
		(net 80)
	)
	(segment
		(start 215.275 124.725)
		(end 215.55 124.45)
		(width 0.1)
		(layer "F.Cu")
		(net 81)
	)
	(segment
		(start 214.45 125.4)
		(end 214.825 125.4)
		(width 0.1)
		(layer "F.Cu")
		(net 81)
	)
	(segment
		(start 215.275 124.95)
		(end 215.275 124.725)
		(width 0.1)
		(layer "F.Cu")
		(net 81)
	)
	(segment
		(start 215.55 124.45)
		(end 215.55 123.875)
		(width 0.1)
		(layer "F.Cu")
		(net 81)
	)
	(segment
		(start 214.825 125.4)
		(end 215.275 124.95)
		(width 0.1)
		(layer "F.Cu")
		(net 81)
	)
	(via
		(at 214.45 125.4)
		(size 0.35)
		(drill 0.15)
		(layers "F.Cu" "B.Cu")
		(remove_unused_layers yes)
		(keep_end_layers yes)
		(zone_layer_connections)
		(net 81)
	)
	(via
		(at 206.925 118.52)
		(size 0.35)
		(drill 0.15)
		(layers "F.Cu" "B.Cu")
		(remove_unused_layers yes)
		(keep_end_layers yes)
		(zone_layer_connections)
		(net 81)
	)
	(segment
		(start 206.12 119.001)
		(end 206.12 120.171)
		(width 0.15)
		(layer "B.Cu")
		(net 81)
	)
	(segment
		(start 206.925 118.52)
		(end 206.601 118.52)
		(width 0.15)
		(layer "B.Cu")
		(net 81)
	)
	(segment
		(start 206.601 118.52)
		(end 206.12 119.001)
		(width 0.15)
		(layer "B.Cu")
		(net 81)
	)
	(segment
		(start 206.52 118.115)
		(end 206.925 118.52)
		(width 0.1)
		(layer "In9.Cu")
		(net 81)
	)
	(segment
		(start 206.915 117.305)
		(end 206.52 117.7)
		(width 0.1)
		(layer "In9.Cu")
		(net 81)
	)
	(segment
		(start 214.45 125.4)
		(end 214.45 123.4)
		(width 0.1)
		(layer "In9.Cu")
		(net 81)
	)
	(segment
		(start 214.45 123.4)
		(end 213.81 122.76)
		(width 0.1)
		(layer "In9.Cu")
		(net 81)
	)
	(segment
		(start 213.81 118.89)
		(end 212.225 117.305)
		(width 0.1)
		(layer "In9.Cu")
		(net 81)
	)
	(segment
		(start 212.225 117.305)
		(end 206.915 117.305)
		(width 0.1)
		(layer "In9.Cu")
		(net 81)
	)
	(segment
		(start 206.52 117.7)
		(end 206.52 118.115)
		(width 0.1)
		(layer "In9.Cu")
		(net 81)
	)
	(segment
		(start 213.81 122.76)
		(end 213.81 118.89)
		(width 0.1)
		(layer "In9.Cu")
		(net 81)
	)
	(via
		(at 195.852595 144.015)
		(size 0.35)
		(drill 0.15)
		(layers "F.Cu" "B.Cu")
		(remove_unused_layers yes)
		(keep_end_layers yes)
		(zone_layer_connections)
		(net 82)
	)
	(via
		(at 203.699 130.65)
		(size 0.35)
		(drill 0.15)
		(layers "F.Cu" "B.Cu")
		(remove_unused_layers yes)
		(keep_end_layers yes)
		(zone_layer_connections)
		(net 82)
	)
	(segment
		(start 203.89 150.175)
		(end 203.89 149.655)
		(width 0.09)
		(layer "In11.Cu")
		(net 82)
	)
	(segment
		(start 206.894706 149.845)
		(end 207.379706 149.36)
		(width 0.09)
		(layer "In11.Cu")
		(net 82)
	)
	(segment
		(start 199.745294 150.595)
		(end 203.47 150.595)
		(width 0.09)
		(layer "In11.Cu")
		(net 82)
	)
	(segment
		(start 206.199706 149.845)
		(end 206.894706 149.845)
		(width 0.09)
		(layer "In11.Cu")
		(net 82)
	)
	(segment
		(start 195.852595 144.062595)
		(end 195.99 144.2)
		(width 0.09)
		(layer "In11.Cu")
		(net 82)
	)
	(segment
		(start 204.67 150.595)
		(end 205.449706 150.595)
		(width 0.09)
		(layer "In11.Cu")
		(net 82)
	)
	(segment
		(start 198.654581 148.54)
		(end 199.611658 148.54)
		(width 0.09)
		(layer "In11.Cu")
		(net 82)
	)
	(segment
		(start 207.81 136.915294)
		(end 207.81 133.27)
		(width 0.09)
		(layer "In11.Cu")
		(net 82)
	)
	(segment
		(start 203.850294 129.18)
		(end 203.379 129.651294)
		(width 0.09)
		(layer "In11.Cu")
		(net 82)
	)
	(segment
		(start 199.611658 148.95)
		(end 199.325 148.95)
		(width 0.09)
		(layer "In11.Cu")
		(net 82)
	)
	(segment
		(start 205.36087 129.18)
		(end 203.850294 129.18)
		(width 0.09)
		(layer "In11.Cu")
		(net 82)
	)
	(segment
		(start 207.81 131.07)
		(end 207.81 130.620294)
		(width 0.09)
		(layer "In11.Cu")
		(net 82)
	)
	(segment
		(start 205.570867 129.389997)
		(end 205.36087 129.18)
		(width 0.09)
		(layer "In11.Cu")
		(net 82)
	)
	(segment
		(start 204.25 149.655)
		(end 204.25 150.175)
		(width 0.09)
		(layer "In11.Cu")
		(net 82)
	)
	(segment
		(start 207.415 131.775)
		(end 206.045 131.775)
		(width 0.09)
		(layer "In11.Cu")
		(net 82)
	)
	(segment
		(start 195.852595 144.015)
		(end 195.852595 144.062595)
		(width 0.09)
		(layer "In11.Cu")
		(net 82)
	)
	(segment
		(start 207.780586 149.36)
		(end 208.16 148.980586)
		(width 0.09)
		(layer "In11.Cu")
		(net 82)
	)
	(segment
		(start 206.579703 129.389997)
		(end 205.570867 129.389997)
		(width 0.09)
		(layer "In11.Cu")
		(net 82)
	)
	(segment
		(start 203.699 130.349)
		(end 203.699 130.65)
		(width 0.09)
		(layer "In11.Cu")
		(net 82)
	)
	(segment
		(start 207.379706 149.36)
		(end 207.780586 149.36)
		(width 0.09)
		(layer "In11.Cu")
		(net 82)
	)
	(segment
		(start 198.774581 147.625419)
		(end 198.654581 147.625419)
		(width 0.09)
		(layer "In11.Cu")
		(net 82)
	)
	(segment
		(start 203.379 129.651294)
		(end 203.379 130.033549)
		(width 0.09)
		(layer "In11.Cu")
		(net 82)
	)
	(segment
		(start 195.99 144.629706)
		(end 198.88 147.519706)
		(width 0.09)
		(layer "In11.Cu")
		(net 82)
	)
	(segment
		(start 203.566451 130.221)
		(end 203.571 130.221)
		(width 0.09)
		(layer "In11.Cu")
		(net 82)
	)
	(segment
		(start 198.88 149.729706)
		(end 199.745294 150.595)
		(width 0.09)
		(layer "In11.Cu")
		(net 82)
	)
	(segment
		(start 207.415 132.875)
		(end 206.745 132.875)
		(width 0.09)
		(layer "In11.Cu")
		(net 82)
	)
	(segment
		(start 198.88 149.395)
		(end 198.88 149.729706)
		(width 0.09)
		(layer "In11.Cu")
		(net 82)
	)
	(segment
		(start 198.309162 147.970838)
		(end 198.309162 148.194581)
		(width 0.09)
		(layer "In11.Cu")
		(net 82)
	)
	(segment
		(start 208.16 137.265294)
		(end 207.81 136.915294)
		(width 0.09)
		(layer "In11.Cu")
		(net 82)
	)
	(segment
		(start 208.16 148.980586)
		(end 208.16 137.265294)
		(width 0.09)
		(layer "In11.Cu")
		(net 82)
	)
	(segment
		(start 203.379 130.033549)
		(end 203.566451 130.221)
		(width 0.09)
		(layer "In11.Cu")
		(net 82)
	)
	(segment
		(start 198.88 147.519706)
		(end 198.88 147.52)
		(width 0.09)
		(layer "In11.Cu")
		(net 82)
	)
	(segment
		(start 195.99 144.2)
		(end 195.99 144.629706)
		(width 0.09)
		(layer "In11.Cu")
		(net 82)
	)
	(segment
		(start 206.045 131.465)
		(end 207.415 131.465)
		(width 0.09)
		(layer "In11.Cu")
		(net 82)
	)
	(segment
		(start 205.449706 150.595)
		(end 206.199706 149.845)
		(width 0.09)
		(layer "In11.Cu")
		(net 82)
	)
	(segment
		(start 203.571 130.221)
		(end 203.699 130.349)
		(width 0.09)
		(layer "In11.Cu")
		(net 82)
	)
	(segment
		(start 206.745 132.565)
		(end 207.415 132.565)
		(width 0.09)
		(layer "In11.Cu")
		(net 82)
	)
	(segment
		(start 207.81 130.620294)
		(end 206.579703 129.389997)
		(width 0.09)
		(layer "In11.Cu")
		(net 82)
	)
	(arc
		(start 206.59 132.72)
		(mid 206.635398 132.610398)
		(end 206.745 132.565)
		(width 0.09)
		(layer "In11.Cu")
		(net 82)
	)
	(arc
		(start 206.045 131.775)
		(mid 205.935398 131.729602)
		(end 205.89 131.62)
		(width 0.09)
		(layer "In11.Cu")
		(net 82)
	)
	(arc
		(start 204.25 150.175)
		(mid 204.373015 150.471985)
		(end 204.67 150.595)
		(width 0.09)
		(layer "In11.Cu")
		(net 82)
	)
	(arc
		(start 207.81 132.17)
		(mid 207.694307 131.890693)
		(end 207.415 131.775)
		(width 0.09)
		(layer "In11.Cu")
		(net 82)
	)
	(arc
		(start 199.325 148.95)
		(mid 199.010337 149.080337)
		(end 198.88 149.395)
		(width 0.09)
		(layer "In11.Cu")
		(net 82)
	)
	(arc
		(start 207.415 132.565)
		(mid 207.694307 132.449307)
		(end 207.81 132.17)
		(width 0.09)
		(layer "In11.Cu")
		(net 82)
	)
	(arc
		(start 204.07 149.475)
		(mid 204.197279 149.527721)
		(end 204.25 149.655)
		(width 0.09)
		(layer "In11.Cu")
		(net 82)
	)
	(arc
		(start 205.89 131.62)
		(mid 205.935398 131.510398)
		(end 206.045 131.465)
		(width 0.09)
		(layer "In11.Cu")
		(net 82)
	)
	(arc
		(start 199.611658 148.54)
		(mid 199.756615 148.600043)
		(end 199.816658 148.745)
		(width 0.09)
		(layer "In11.Cu")
		(net 82)
	)
	(arc
		(start 203.47 150.595)
		(mid 203.766985 150.471985)
		(end 203.89 150.175)
		(width 0.09)
		(layer "In11.Cu")
		(net 82)
	)
	(arc
		(start 207.81 133.27)
		(mid 207.694307 132.990693)
		(end 207.415 132.875)
		(width 0.09)
		(layer "In11.Cu")
		(net 82)
	)
	(arc
		(start 198.88 147.52)
		(mid 198.849123 147.594542)
		(end 198.774581 147.625419)
		(width 0.09)
		(layer "In11.Cu")
		(net 82)
	)
	(arc
		(start 206.745 132.875)
		(mid 206.635398 132.829602)
		(end 206.59 132.72)
		(width 0.09)
		(layer "In11.Cu")
		(net 82)
	)
	(arc
		(start 203.89 149.655)
		(mid 203.942721 149.527721)
		(end 204.07 149.475)
		(width 0.09)
		(layer "In11.Cu")
		(net 82)
	)
	(arc
		(start 207.415 131.465)
		(mid 207.694307 131.349307)
		(end 207.81 131.07)
		(width 0.09)
		(layer "In11.Cu")
		(net 82)
	)
	(arc
		(start 198.654581 147.625419)
		(mid 198.410333 147.72659)
		(end 198.309162 147.970838)
		(width 0.09)
		(layer "In11.Cu")
		(net 82)
	)
	(arc
		(start 198.309162 148.194581)
		(mid 198.410333 148.438829)
		(end 198.654581 148.54)
		(width 0.09)
		(layer "In11.Cu")
		(net 82)
	)
	(arc
		(start 199.816658 148.745)
		(mid 199.756615 148.889957)
		(end 199.611658 148.95)
		(width 0.09)
		(layer "In11.Cu")
		(net 82)
	)
	(via
		(at 195.358831 143.995993)
		(size 0.35)
		(drill 0.15)
		(layers "F.Cu" "B.Cu")
		(remove_unused_layers yes)
		(keep_end_layers yes)
		(zone_layer_connections)
		(net 83)
	)
	(via
		(at 205.299 127.5)
		(size 0.35)
		(drill 0.15)
		(layers "F.Cu" "B.Cu")
		(remove_unused_layers yes)
		(keep_end_layers yes)
		(zone_layer_connections)
		(net 83)
	)
	(segment
		(start 198.032364 149.66517)
		(end 198.172267 149.525268)
		(width 0.09)
		(layer "In11.Cu")
		(net 83)
	)
	(segment
		(start 194.616162 145.257213)
		(end 194.616162 145.363375)
		(width 0.09)
		(layer "In11.Cu")
		(net 83)
	)
	(segment
		(start 196.796324 148.42206)
		(end 196.796324 148.422059)
		(width 0.09)
		(layer "In11.Cu")
		(net 83)
	)
	(segment
		(start 198.419754 149.525269)
		(end 198.419755 149.52527)
		(width 0.09)
		(layer "In11.Cu")
		(net 83)
	)
	(segment
		(start 195.358831 143.995993)
		(end 195.358831 144.071169)
		(width 0.09)
		(layer "In11.Cu")
		(net 83)
	)
	(segment
		(start 207.19017 128.479875)
		(end 207.190172 128.479878)
		(width 0.09)
		(layer "In11.Cu")
		(net 83)
	)
	(segment
		(start 196.971723 147.65269)
		(end 196.971724 147.652691)
		(width 0.09)
		(layer "In11.Cu")
		(net 83)
	)
	(segment
		(start 194.863081 145.130294)
		(end 194.743081 145.130294)
		(width 0.09)
		(layer "In11.Cu")
		(net 83)
	)
	(segment
		(start 196.971723 148.24666)
		(end 196.796324 148.42206)
		(width 0.09)
		(layer "In11.Cu")
		(net 83)
	)
	(segment
		(start 194.561962 146.330294)
		(end 195.958046 146.330294)
		(width 0.09)
		(layer "In11.Cu")
		(net 83)
	)
	(segment
		(start 198.032379 148.289091)
		(end 198.032378 148.289091)
		(width 0.09)
		(layer "In11.Cu")
		(net 83)
	)
	(segment
		(start 208.58 136.524706)
		(end 208.28 136.224706)
		(width 0.09)
		(layer "In11.Cu")
		(net 83)
	)
	(segment
		(start 195.23 147.110294)
		(end 195.947794 147.82809)
		(width 0.09)
		(layer "In11.Cu")
		(net 83)
	)
	(segment
		(start 195.23 144.2)
		(end 195.23 144.763375)
		(width 0.09)
		(layer "In11.Cu")
		(net 83)
	)
	(segment
		(start 197.644852 149.270588)
		(end 197.644852 149.270587)
		(width 0.09)
		(layer "In11.Cu")
		(net 83)
	)
	(segment
		(start 196.796322 148.676617)
		(end 196.796324 148.676619)
		(width 0.09)
		(layer "In11.Cu")
		(net 83)
	)
	(segment
		(start 208.28 136.224706)
		(end 208.28 129.569706)
		(width 0.09)
		(layer "In11.Cu")
		(net 83)
	)
	(segment
		(start 208.28 129.569706)
		(end 207.685147 128.974853)
		(width 0.09)
		(layer "In11.Cu")
		(net 83)
	)
	(segment
		(start 206.593014 128.582057)
		(end 206.593016 128.582058)
		(width 0.09)
		(layer "In11.Cu")
		(net 83)
	)
	(segment
		(start 205.800294 151.03)
		(end 206.700294 150.13)
		(width 0.09)
		(layer "In11.Cu")
		(net 83)
	)
	(segment
		(start 197.644852 149.525147)
		(end 197.784877 149.665171)
		(width 0.09)
		(layer "In11.Cu")
		(net 83)
	)
	(segment
		(start 207.335494 129.077015)
		(end 207.43766 128.974852)
		(width 0.09)
		(layer "In11.Cu")
		(net 83)
	)
	(segment
		(start 208.100294 150.13)
		(end 208.58 149.650294)
		(width 0.09)
		(layer "In11.Cu")
		(net 83)
	)
	(segment
		(start 206.593015 128.334571)
		(end 206.695195 128.232388)
		(width 0.09)
		(layer "In11.Cu")
		(net 83)
	)
	(segment
		(start 197.050881 148.676618)
		(end 197.43841 148.28909)
		(width 0.09)
		(layer "In11.Cu")
		(net 83)
	)
	(segment
		(start 198.032379 148.88306)
		(end 197.644852 149.270588)
		(width 0.09)
		(layer "In11.Cu")
		(net 83)
	)
	(segment
		(start 198.279852 149.91266)
		(end 198.419754 149.772757)
		(width 0.09)
		(layer "In11.Cu")
		(net 83)
	)
	(segment
		(start 207.088006 129.077015)
		(end 207.088008 129.077016)
		(width 0.09)
		(layer "In11.Cu")
		(net 83)
	)
	(segment
		(start 199.149706 151.03)
		(end 205.800294 151.03)
		(width 0.09)
		(layer "In11.Cu")
		(net 83)
	)
	(segment
		(start 206.210294 127.5)
		(end 205.299 127.5)
		(width 0.09)
		(layer "In11.Cu")
		(net 83)
	)
	(segment
		(start 194.561962 146.690294)
		(end 194.81 146.690294)
		(width 0.09)
		(layer "In11.Cu")
		(net 83)
	)
	(segment
		(start 207.088007 128.829529)
		(end 207.19017 128.727363)
		(width 0.09)
		(layer "In11.Cu")
		(net 83)
	)
	(segment
		(start 208.58 149.650294)
		(end 208.58 136.524706)
		(width 0.09)
		(layer "In11.Cu")
		(net 83)
	)
	(segment
		(start 195.358831 144.071169)
		(end 195.23 144.2)
		(width 0.09)
		(layer "In11.Cu")
		(net 83)
	)
	(segment
		(start 196.202353 147.828089)
		(end 196.377754 147.652689)
		(width 0.09)
		(layer "In11.Cu")
		(net 83)
	)
	(segment
		(start 206.700294 150.13)
		(end 208.100294 150.13)
		(width 0.09)
		(layer "In11.Cu")
		(net 83)
	)
	(segment
		(start 206.695195 127.9849)
		(end 206.210294 127.5)
		(width 0.09)
		(layer "In11.Cu")
		(net 83)
	)
	(segment
		(start 206.840502 128.582057)
		(end 206.942685 128.479877)
		(width 0.09)
		(layer "In11.Cu")
		(net 83)
	)
	(segment
		(start 194.743081 145.490294)
		(end 195.958046 145.490294)
		(width 0.09)
		(layer "In11.Cu")
		(net 83)
	)
	(segment
		(start 198.279853 150.160147)
		(end 199.149706 151.03)
		(width 0.09)
		(layer "In11.Cu")
		(net 83)
	)
	(arc
		(start 194.381962 146.510294)
		(mid 194.434683 146.637573)
		(end 194.561962 146.690294)
		(width 0.09)
		(layer "In11.Cu")
		(net 83)
	)
	(arc
		(start 198.032378 148.289091)
		(mid 198.155394 148.586075)
		(end 198.032379 148.88306)
		(width 0.09)
		(layer "In11.Cu")
		(net 83)
	)
	(arc
		(start 196.796324 148.422059)
		(mid 196.743603 148.549339)
		(end 196.796324 148.676619)
		(width 0.09)
		(layer "In11.Cu")
		(net 83)
	)
	(arc
		(start 196.796322 148.676617)
		(mid 196.923601 148.729338)
		(end 197.050881 148.676618)
		(width 0.09)
		(layer "In11.Cu")
		(net 83)
	)
	(arc
		(start 196.378046 145.910294)
		(mid 196.255031 146.207279)
		(end 195.958046 146.330294)
		(width 0.09)
		(layer "In11.Cu")
		(net 83)
	)
	(arc
		(start 206.593016 128.582058)
		(mid 206.541759 128.458315)
		(end 206.593015 128.334571)
		(width 0.09)
		(layer "In11.Cu")
		(net 83)
	)
	(arc
		(start 198.419755 149.52527)
		(mid 198.471011 149.649014)
		(end 198.419754 149.772757)
		(width 0.09)
		(layer "In11.Cu")
		(net 83)
	)
	(arc
		(start 198.172267 149.525268)
		(mid 198.296011 149.474012)
		(end 198.419754 149.525269)
		(width 0.09)
		(layer "In11.Cu")
		(net 83)
	)
	(arc
		(start 194.81 146.690294)
		(mid 195.106985 146.813309)
		(end 195.23 147.110294)
		(width 0.09)
		(layer "In11.Cu")
		(net 83)
	)
	(arc
		(start 207.19017 128.727363)
		(mid 207.241426 128.603619)
		(end 207.19017 128.479875)
		(width 0.09)
		(layer "In11.Cu")
		(net 83)
	)
	(arc
		(start 195.958046 145.490294)
		(mid 196.255031 145.613309)
		(end 196.378046 145.910294)
		(width 0.09)
		(layer "In11.Cu")
		(net 83)
	)
	(arc
		(start 196.377754 147.652689)
		(mid 196.674739 147.529674)
		(end 196.971723 147.65269)
		(width 0.09)
		(layer "In11.Cu")
		(net 83)
	)
	(arc
		(start 196.971724 147.652691)
		(mid 197.094739 147.949676)
		(end 196.971723 148.24666)
		(width 0.09)
		(layer "In11.Cu")
		(net 83)
	)
	(arc
		(start 198.279852 149.91266)
		(mid 198.228596 150.036404)
		(end 198.279853 150.160147)
		(width 0.09)
		(layer "In11.Cu")
		(net 83)
	)
	(arc
		(start 194.561962 146.330294)
		(mid 194.434683 146.383015)
		(end 194.381962 146.510294)
		(width 0.09)
		(layer "In11.Cu")
		(net 83)
	)
	(arc
		(start 195.23 144.763375)
		(mid 195.122532 145.022826)
		(end 194.863081 145.130294)
		(width 0.09)
		(layer "In11.Cu")
		(net 83)
	)
	(arc
		(start 197.43841 148.28909)
		(mid 197.735395 148.166075)
		(end 198.032379 148.289091)
		(width 0.09)
		(layer "In11.Cu")
		(net 83)
	)
	(arc
		(start 206.840502 128.582057)
		(mid 206.716758 128.633313)
		(end 206.593014 128.582057)
		(width 0.09)
		(layer "In11.Cu")
		(net 83)
	)
	(arc
		(start 194.743081 145.130294)
		(mid 194.653336 145.167468)
		(end 194.616162 145.257213)
		(width 0.09)
		(layer "In11.Cu")
		(net 83)
	)
	(arc
		(start 206.695195 128.232388)
		(mid 206.746451 128.108644)
		(end 206.695195 127.9849)
		(width 0.09)
		(layer "In11.Cu")
		(net 83)
	)
	(arc
		(start 197.784877 149.665171)
		(mid 197.908621 149.716427)
		(end 198.032364 149.66517)
		(width 0.09)
		(layer "In11.Cu")
		(net 83)
	)
	(arc
		(start 207.088008 129.077016)
		(mid 207.036751 128.953273)
		(end 207.088007 128.829529)
		(width 0.09)
		(layer "In11.Cu")
		(net 83)
	)
	(arc
		(start 207.335494 129.077015)
		(mid 207.21175 129.128271)
		(end 207.088006 129.077015)
		(width 0.09)
		(layer "In11.Cu")
		(net 83)
	)
	(arc
		(start 194.616162 145.363375)
		(mid 194.653336 145.45312)
		(end 194.743081 145.490294)
		(width 0.09)
		(layer "In11.Cu")
		(net 83)
	)
	(arc
		(start 197.644852 149.270587)
		(mid 197.592131 149.397867)
		(end 197.644852 149.525147)
		(width 0.09)
		(layer "In11.Cu")
		(net 83)
	)
	(arc
		(start 195.947794 147.82809)
		(mid 196.075074 147.88081)
		(end 196.202353 147.828089)
		(width 0.09)
		(layer "In11.Cu")
		(net 83)
	)
	(arc
		(start 207.685147 128.974853)
		(mid 207.561404 128.923596)
		(end 207.43766 128.974852)
		(width 0.09)
		(layer "In11.Cu")
		(net 83)
	)
	(arc
		(start 207.190172 128.479878)
		(mid 207.066429 128.428621)
		(end 206.942685 128.479877)
		(width 0.09)
		(layer "In11.Cu")
		(net 83)
	)
	(via
		(at 194.759204 143.980796)
		(size 0.35)
		(drill 0.15)
		(layers "F.Cu" "B.Cu")
		(remove_unused_layers yes)
		(keep_end_layers yes)
		(zone_layer_connections)
		(net 84)
	)
	(via
		(at 204.499 127.5)
		(size 0.35)
		(drill 0.15)
		(layers "F.Cu" "B.Cu")
		(remove_unused_layers yes)
		(keep_end_layers yes)
		(zone_layer_connections)
		(net 84)
	)
	(segment
		(start 194.561962 146.090294)
		(end 195.958046 146.090294)
		(width 0.09)
		(layer "In11.Cu")
		(net 84)
	)
	(segment
		(start 205.899706 151.27)
		(end 206.799706 150.37)
		(width 0.09)
		(layer "In11.Cu")
		(net 84)
	)
	(segment
		(start 194.770796 143.980796)
		(end 194.99 144.2)
		(width 0.09)
		(layer "In11.Cu")
		(net 84)
	)
	(segment
		(start 194.99 144.2)
		(end 194.99 144.763375)
		(width 0.09)
		(layer "In11.Cu")
		(net 84)
	)
	(segment
		(start 194.743081 145.730294)
		(end 195.958046 145.730294)
		(width 0.09)
		(layer "In11.Cu")
		(net 84)
	)
	(segment
		(start 194.99 147.209706)
		(end 195.77809 147.997796)
		(width 0.09)
		(layer "In11.Cu")
		(net 84)
	)
	(segment
		(start 208.82 136.425294)
		(end 208.52 136.125294)
		(width 0.09)
		(layer "In11.Cu")
		(net 84)
	)
	(segment
		(start 206.799706 150.37)
		(end 208.199706 150.37)
		(width 0.09)
		(layer "In11.Cu")
		(net 84)
	)
	(segment
		(start 197.862674 148.713355)
		(end 197.475147 149.100883)
		(width 0.09)
		(layer "In11.Cu")
		(net 84)
	)
	(segment
		(start 208.199706 150.37)
		(end 208.82 149.749706)
		(width 0.09)
		(layer "In11.Cu")
		(net 84)
	)
	(segment
		(start 205.431549 127.18)
		(end 205.166451 127.18)
		(width 0.09)
		(layer "In11.Cu")
		(net 84)
	)
	(segment
		(start 208.82 149.749706)
		(end 208.82 136.425294)
		(width 0.09)
		(layer "In11.Cu")
		(net 84)
	)
	(segment
		(start 196.802018 148.076955)
		(end 196.626619 148.252355)
		(width 0.09)
		(layer "In11.Cu")
		(net 84)
	)
	(segment
		(start 194.863081 144.890294)
		(end 194.743081 144.890294)
		(width 0.09)
		(layer "In11.Cu")
		(net 84)
	)
	(segment
		(start 205.511549 127.26)
		(end 205.431549 127.18)
		(width 0.09)
		(layer "In11.Cu")
		(net 84)
	)
	(segment
		(start 196.626619 148.252355)
		(end 196.626619 148.252354)
		(width 0.09)
		(layer "In11.Cu")
		(net 84)
	)
	(segment
		(start 196.626618 148.846324)
		(end 196.626618 148.846323)
		(width 0.09)
		(layer "In11.Cu")
		(net 84)
	)
	(segment
		(start 208.52 129.470294)
		(end 206.309706 127.26)
		(width 0.09)
		(layer "In11.Cu")
		(net 84)
	)
	(segment
		(start 197.220587 148.846324)
		(end 197.608115 148.458796)
		(width 0.09)
		(layer "In11.Cu")
		(net 84)
	)
	(segment
		(start 197.862674 148.458797)
		(end 197.862673 148.458796)
		(width 0.09)
		(layer "In11.Cu")
		(net 84)
	)
	(segment
		(start 205.166451 127.18)
		(end 205.086451 127.26)
		(width 0.09)
		(layer "In11.Cu")
		(net 84)
	)
	(segment
		(start 196.802018 147.822396)
		(end 196.802019 147.822396)
		(width 0.09)
		(layer "In11.Cu")
		(net 84)
	)
	(segment
		(start 208.52 136.125294)
		(end 208.52 129.470294)
		(width 0.09)
		(layer "In11.Cu")
		(net 84)
	)
	(segment
		(start 197.475147 149.100883)
		(end 197.475147 149.100882)
		(width 0.09)
		(layer "In11.Cu")
		(net 84)
	)
	(segment
		(start 197.475147 149.694852)
		(end 199.050294 151.27)
		(width 0.09)
		(layer "In11.Cu")
		(net 84)
	)
	(segment
		(start 194.759204 143.980796)
		(end 194.770796 143.980796)
		(width 0.09)
		(layer "In11.Cu")
		(net 84)
	)
	(segment
		(start 205.086451 127.26)
		(end 204.739 127.26)
		(width 0.09)
		(layer "In11.Cu")
		(net 84)
	)
	(segment
		(start 194.376162 145.257213)
		(end 194.376162 145.363375)
		(width 0.09)
		(layer "In11.Cu")
		(net 84)
	)
	(segment
		(start 194.99 147.110294)
		(end 194.99 147.209706)
		(width 0.09)
		(layer "In11.Cu")
		(net 84)
	)
	(segment
		(start 199.050294 151.27)
		(end 205.899706 151.27)
		(width 0.09)
		(layer "In11.Cu")
		(net 84)
	)
	(segment
		(start 206.309706 127.26)
		(end 205.511549 127.26)
		(width 0.09)
		(layer "In11.Cu")
		(net 84)
	)
	(segment
		(start 194.561962 146.930294)
		(end 194.81 146.930294)
		(width 0.09)
		(layer "In11.Cu")
		(net 84)
	)
	(segment
		(start 196.626619 148.846324)
		(end 196.626618 148.846324)
		(width 0.09)
		(layer "In11.Cu")
		(net 84)
	)
	(segment
		(start 204.739 127.26)
		(end 204.499 127.5)
		(width 0.09)
		(layer "In11.Cu")
		(net 84)
	)
	(segment
		(start 196.372059 147.997795)
		(end 196.547459 147.822395)
		(width 0.09)
		(layer "In11.Cu")
		(net 84)
	)
	(arc
		(start 194.141962 146.510294)
		(mid 194.264977 146.807279)
		(end 194.561962 146.930294)
		(width 0.09)
		(layer "In11.Cu")
		(net 84)
	)
	(arc
		(start 197.475147 149.100882)
		(mid 197.352132 149.397867)
		(end 197.475147 149.694852)
		(width 0.09)
		(layer "In11.Cu")
		(net 84)
	)
	(arc
		(start 194.743081 144.890294)
		(mid 194.48363 144.997762)
		(end 194.376162 145.257213)
		(width 0.09)
		(layer "In11.Cu")
		(net 84)
	)
	(arc
		(start 196.626618 148.846323)
		(mid 196.923602 148.969339)
		(end 197.220587 148.846324)
		(width 0.09)
		(layer "In11.Cu")
		(net 84)
	)
	(arc
		(start 196.626619 148.252354)
		(mid 196.503604 148.549339)
		(end 196.626619 148.846324)
		(width 0.09)
		(layer "In11.Cu")
		(net 84)
	)
	(arc
		(start 194.99 144.763375)
		(mid 194.952826 144.85312)
		(end 194.863081 144.890294)
		(width 0.09)
		(layer "In11.Cu")
		(net 84)
	)
	(arc
		(start 196.547459 147.822395)
		(mid 196.674739 147.769675)
		(end 196.802018 147.822396)
		(width 0.09)
		(layer "In11.Cu")
		(net 84)
	)
	(arc
		(start 196.802019 147.822396)
		(mid 196.854739 147.949676)
		(end 196.802018 148.076955)
		(width 0.09)
		(layer "In11.Cu")
		(net 84)
	)
	(arc
		(start 195.958046 145.730294)
		(mid 196.085325 145.783015)
		(end 196.138046 145.910294)
		(width 0.09)
		(layer "In11.Cu")
		(net 84)
	)
	(arc
		(start 197.862673 148.458796)
		(mid 197.915394 148.586075)
		(end 197.862674 148.713355)
		(width 0.09)
		(layer "In11.Cu")
		(net 84)
	)
	(arc
		(start 194.81 146.930294)
		(mid 194.937279 146.983015)
		(end 194.99 147.110294)
		(width 0.09)
		(layer "In11.Cu")
		(net 84)
	)
	(arc
		(start 197.608115 148.458796)
		(mid 197.735395 148.406076)
		(end 197.862674 148.458797)
		(width 0.09)
		(layer "In11.Cu")
		(net 84)
	)
	(arc
		(start 195.77809 147.997796)
		(mid 196.075075 148.120811)
		(end 196.372059 147.997795)
		(width 0.09)
		(layer "In11.Cu")
		(net 84)
	)
	(arc
		(start 196.138046 145.910294)
		(mid 196.085325 146.037573)
		(end 195.958046 146.090294)
		(width 0.09)
		(layer "In11.Cu")
		(net 84)
	)
	(arc
		(start 194.376162 145.363375)
		(mid 194.48363 145.622826)
		(end 194.743081 145.730294)
		(width 0.09)
		(layer "In11.Cu")
		(net 84)
	)
	(arc
		(start 194.561962 146.090294)
		(mid 194.264977 146.213309)
		(end 194.141962 146.510294)
		(width 0.09)
		(layer "In11.Cu")
		(net 84)
	)
	(segment
		(start 223.425716 146.977)
		(end 223.555865 146.977)
		(width 0.09)
		(layer "F.Cu")
		(net 85)
	)
	(segment
		(start 223.102 144.082)
		(end 223.277284 144.082)
		(width 0.09)
		(layer "F.Cu")
		(net 85)
	)
	(segment
		(start 223.49 145.607716)
		(end 223.2865 145.811216)
		(width 0.09)
		(layer "F.Cu")
		(net 85)
	)
	(segment
		(start 223.49 144.294716)
		(end 223.49 145.607716)
		(width 0.09)
		(layer "F.Cu")
		(net 85)
	)
	(segment
		(start 222.66 143.64)
		(end 223.102 144.082)
		(width 0.09)
		(layer "F.Cu")
		(net 85)
	)
	(segment
		(start 223.277284 144.082)
		(end 223.49 144.294716)
		(width 0.09)
		(layer "F.Cu")
		(net 85)
	)
	(segment
		(start 223.2865 145.811216)
		(end 223.2865 146.837784)
		(width 0.09)
		(layer "F.Cu")
		(net 85)
	)
	(segment
		(start 223.555865 146.977)
		(end 224.2015 147.622635)
		(width 0.09)
		(layer "F.Cu")
		(net 85)
	)
	(segment
		(start 224.2015 147.622635)
		(end 224.2015 147.817)
		(width 0.09)
		(layer "F.Cu")
		(net 85)
	)
	(segment
		(start 223.2865 146.837784)
		(end 223.425716 146.977)
		(width 0.09)
		(layer "F.Cu")
		(net 85)
	)
	(via
		(at 222.66 143.64)
		(size 0.35)
		(drill 0.15)
		(layers "F.Cu" "B.Cu")
		(remove_unused_layers yes)
		(keep_end_layers yes)
		(zone_layer_connections)
		(net 85)
	)
	(segment
		(start 222.66 143.64)
		(end 222.74 143.64)
		(width 0.09)
		(layer "B.Cu")
		(net 85)
	)
	(segment
		(start 222.74 143.64)
		(end 223.06 143.96)
		(width 0.09)
		(layer "B.Cu")
		(net 85)
	)
	(via
		(at 193.9725 144)
		(size 0.35)
		(drill 0.15)
		(layers "F.Cu" "B.Cu")
		(remove_unused_layers yes)
		(keep_end_layers yes)
		(zone_layer_connections)
		(net 86)
	)
	(via
		(at 205.299 126.701)
		(size 0.35)
		(drill 0.15)
		(layers "F.Cu" "B.Cu")
		(remove_unused_layers yes)
		(keep_end_layers yes)
		(zone_layer_connections)
		(net 86)
	)
	(segment
		(start 210.220871 143.778406)
		(end 210.22703 143.784565)
		(width 0.09)
		(layer "In11.Cu")
		(net 86)
	)
	(segment
		(start 210.474517 143.784566)
		(end 210.474518 143.784565)
		(width 0.09)
		(layer "In11.Cu")
		(net 86)
	)
	(segment
		(start 211.565 138.134706)
		(end 208.98 135.549706)
		(width 0.09)
		(layer "In11.Cu")
		(net 86)
	)
	(segment
		(start 208.587636 150.636395)
		(end 208.587637 150.636396)
		(width 0.09)
		(layer "In11.Cu")
		(net 86)
	)
	(segment
		(start 209.979541 144.032052)
		(end 209.973383 144.025894)
		(width 0.09)
		(layer "In11.Cu")
		(net 86)
	)
	(segment
		(start 205.019 126.260706)
		(end 205.019 126.421)
		(width 0.09)
		(layer "In11.Cu")
		(net 86)
	)
	(segment
		(start 208.98 128.669706)
		(end 206.440294 126.13)
		(width 0.09)
		(layer "In11.Cu")
		(net 86)
	)
	(segment
		(start 209.97954 144.032054)
		(end 209.979541 144.032052)
		(width 0.09)
		(layer "In11.Cu")
		(net 86)
	)
	(segment
		(start 210.715785 143.283371)
		(end 210.722005 143.289591)
		(width 0.09)
		(layer "In11.Cu")
		(net 86)
	)
	(segment
		(start 208.215294 151.255)
		(end 208.340147 151.130147)
		(width 0.09)
		(layer "In11.Cu")
		(net 86)
	)
	(segment
		(start 209.79 149.680294)
		(end 209.79 144.46908)
		(width 0.09)
		(layer "In11.Cu")
		(net 86)
	)
	(segment
		(start 206.450294 151.255)
		(end 208.215294 151.255)
		(width 0.09)
		(layer "In11.Cu")
		(net 86)
	)
	(segment
		(start 193.9725 144)
		(end 193.86 144)
		(width 0.09)
		(layer "In11.Cu")
		(net 86)
	)
	(segment
		(start 210.969492 143.28959)
		(end 210.969493 143.28959)
		(width 0.09)
		(layer "In11.Cu")
		(net 86)
	)
	(segment
		(start 208.835123 150.388877)
		(end 208.835124 150.388875)
		(width 0.09)
		(layer "In11.Cu")
		(net 86)
	)
	(segment
		(start 209.082612 150.141389)
		(end 209.082611 150.141389)
		(width 0.09)
		(layer "In11.Cu")
		(net 86)
	)
	(segment
		(start 210.468299 143.28337)
		(end 210.468297 143.283371)
		(width 0.09)
		(layer "In11.Cu")
		(net 86)
	)
	(segment
		(start 210.969493 143.28959)
		(end 211.565 142.69408)
		(width 0.09)
		(layer "In11.Cu")
		(net 86)
	)
	(segment
		(start 208.835123 150.142581)
		(end 208.836317 150.141388)
		(width 0.09)
		(layer "In11.Cu")
		(net 86)
	)
	(segment
		(start 205.149706 126.13)
		(end 205.019 126.260706)
		(width 0.09)
		(layer "In11.Cu")
		(net 86)
	)
	(segment
		(start 208.835125 150.14258)
		(end 208.835123 150.142581)
		(width 0.09)
		(layer "In11.Cu")
		(net 86)
	)
	(segment
		(start 208.340147 150.637619)
		(end 208.341372 150.636395)
		(width 0.09)
		(layer "In11.Cu")
		(net 86)
	)
	(segment
		(start 193.81 146.690294)
		(end 198.849706 151.73)
		(width 0.09)
		(layer "In11.Cu")
		(net 86)
	)
	(segment
		(start 210.474516 143.537078)
		(end 210.474517 143.537076)
		(width 0.09)
		(layer "In11.Cu")
		(net 86)
	)
	(segment
		(start 211.565 142.69408)
		(end 211.565 138.134706)
		(width 0.09)
		(layer "In11.Cu")
		(net 86)
	)
	(segment
		(start 208.833901 150.636396)
		(end 208.835123 150.635171)
		(width 0.09)
		(layer "In11.Cu")
		(net 86)
	)
	(segment
		(start 193.86 144)
		(end 193.81 144.05)
		(width 0.09)
		(layer "In11.Cu")
		(net 86)
	)
	(segment
		(start 198.849706 151.73)
		(end 205.975294 151.73)
		(width 0.09)
		(layer "In11.Cu")
		(net 86)
	)
	(segment
		(start 209.973382 143.778407)
		(end 209.973383 143.778406)
		(width 0.09)
		(layer "In11.Cu")
		(net 86)
	)
	(segment
		(start 193.81 144.05)
		(end 193.81 146.690294)
		(width 0.09)
		(layer "In11.Cu")
		(net 86)
	)
	(segment
		(start 209.328906 150.14139)
		(end 209.79 149.680294)
		(width 0.09)
		(layer "In11.Cu")
		(net 86)
	)
	(segment
		(start 206.440294 126.13)
		(end 205.149706 126.13)
		(width 0.09)
		(layer "In11.Cu")
		(net 86)
	)
	(segment
		(start 209.79 144.46908)
		(end 209.97954 144.27954)
		(width 0.09)
		(layer "In11.Cu")
		(net 86)
	)
	(segment
		(start 205.019 126.421)
		(end 205.299 126.701)
		(width 0.09)
		(layer "In11.Cu")
		(net 86)
	)
	(segment
		(start 205.975294 151.73)
		(end 206.450294 151.255)
		(width 0.09)
		(layer "In11.Cu")
		(net 86)
	)
	(segment
		(start 210.474518 143.784565)
		(end 210.474516 143.784564)
		(width 0.09)
		(layer "In11.Cu")
		(net 86)
	)
	(segment
		(start 210.474517 143.537076)
		(end 210.468298 143.530857)
		(width 0.09)
		(layer "In11.Cu")
		(net 86)
	)
	(segment
		(start 208.98 135.549706)
		(end 208.98 128.669706)
		(width 0.09)
		(layer "In11.Cu")
		(net 86)
	)
	(arc
		(start 209.082611 150.141389)
		(mid 209.205759 150.192398)
		(end 209.328906 150.14139)
		(width 0.09)
		(layer "In11.Cu")
		(net 86)
	)
	(arc
		(start 208.587637 150.636396)
		(mid 208.710768 150.6874)
		(end 208.833901 150.636396)
		(width 0.09)
		(layer "In11.Cu")
		(net 86)
	)
	(arc
		(start 209.973383 144.025894)
		(mid 209.922126 143.902151)
		(end 209.973382 143.778407)
		(width 0.09)
		(layer "In11.Cu")
		(net 86)
	)
	(arc
		(start 210.474516 143.784564)
		(mid 210.525773 143.66082)
		(end 210.474516 143.537078)
		(width 0.09)
		(layer "In11.Cu")
		(net 86)
	)
	(arc
		(start 208.341372 150.636395)
		(mid 208.464503 150.585393)
		(end 208.587636 150.636395)
		(width 0.09)
		(layer "In11.Cu")
		(net 86)
	)
	(arc
		(start 210.468297 143.283371)
		(mid 210.592041 143.232115)
		(end 210.715785 143.283371)
		(width 0.09)
		(layer "In11.Cu")
		(net 86)
	)
	(arc
		(start 209.97954 144.27954)
		(mid 210.030797 144.155796)
		(end 209.97954 144.032054)
		(width 0.09)
		(layer "In11.Cu")
		(net 86)
	)
	(arc
		(start 209.973383 143.778406)
		(mid 210.097127 143.72715)
		(end 210.220871 143.778406)
		(width 0.09)
		(layer "In11.Cu")
		(net 86)
	)
	(arc
		(start 210.468298 143.530857)
		(mid 210.417042 143.407113)
		(end 210.468299 143.28337)
		(width 0.09)
		(layer "In11.Cu")
		(net 86)
	)
	(arc
		(start 208.340147 150.883883)
		(mid 208.289145 150.76075)
		(end 208.340147 150.637619)
		(width 0.09)
		(layer "In11.Cu")
		(net 86)
	)
	(arc
		(start 208.835124 150.388875)
		(mid 208.784114 150.265728)
		(end 208.835125 150.14258)
		(width 0.09)
		(layer "In11.Cu")
		(net 86)
	)
	(arc
		(start 210.722005 143.289591)
		(mid 210.845749 143.340847)
		(end 210.969492 143.28959)
		(width 0.09)
		(layer "In11.Cu")
		(net 86)
	)
	(arc
		(start 208.836317 150.141388)
		(mid 208.959464 150.09038)
		(end 209.082612 150.141389)
		(width 0.09)
		(layer "In11.Cu")
		(net 86)
	)
	(arc
		(start 208.340147 151.130147)
		(mid 208.391151 151.007014)
		(end 208.340147 150.883883)
		(width 0.09)
		(layer "In11.Cu")
		(net 86)
	)
	(arc
		(start 208.835123 150.635171)
		(mid 208.886132 150.512024)
		(end 208.835123 150.388877)
		(width 0.09)
		(layer "In11.Cu")
		(net 86)
	)
	(arc
		(start 210.22703 143.784565)
		(mid 210.350773 143.835822)
		(end 210.474517 143.784566)
		(width 0.09)
		(layer "In11.Cu")
		(net 86)
	)
	(via
		(at 193.335 144)
		(size 0.35)
		(drill 0.15)
		(layers "F.Cu" "B.Cu")
		(remove_unused_layers yes)
		(keep_end_layers yes)
		(zone_layer_connections)
		(net 87)
	)
	(via
		(at 204.499 126.701)
		(size 0.35)
		(drill 0.15)
		(layers "F.Cu" "B.Cu")
		(remove_unused_layers yes)
		(keep_end_layers yes)
		(zone_layer_connections)
		(net 87)
	)
	(segment
		(start 211.835 138.065294)
		(end 209.22 135.450294)
		(width 0.09)
		(layer "In11.Cu")
		(net 87)
	)
	(segment
		(start 209.22 128.570294)
		(end 206.539706 125.89)
		(width 0.09)
		(layer "In11.Cu")
		(net 87)
	)
	(segment
		(start 210.03 144.61092)
		(end 211.835 142.80592)
		(width 0.09)
		(layer "In11.Cu")
		(net 87)
	)
	(segment
		(start 198.750294 151.97)
		(end 206.074706 151.97)
		(width 0.09)
		(layer "In11.Cu")
		(net 87)
	)
	(segment
		(start 193.335 144)
		(end 193.52 144)
		(width 0.09)
		(layer "In11.Cu")
		(net 87)
	)
	(segment
		(start 206.539706 125.89)
		(end 205.050294 125.89)
		(width 0.09)
		(layer "In11.Cu")
		(net 87)
	)
	(segment
		(start 206.074706 151.97)
		(end 206.549706 151.495)
		(width 0.09)
		(layer "In11.Cu")
		(net 87)
	)
	(segment
		(start 209.22 135.450294)
		(end 209.22 128.570294)
		(width 0.09)
		(layer "In11.Cu")
		(net 87)
	)
	(segment
		(start 193.52 144)
		(end 193.57 144.05)
		(width 0.09)
		(layer "In11.Cu")
		(net 87)
	)
	(segment
		(start 208.314706 151.495)
		(end 210.03 149.779706)
		(width 0.09)
		(layer "In11.Cu")
		(net 87)
	)
	(segment
		(start 193.57 146.789706)
		(end 198.750294 151.97)
		(width 0.09)
		(layer "In11.Cu")
		(net 87)
	)
	(segment
		(start 206.549706 151.495)
		(end 208.314706 151.495)
		(width 0.09)
		(layer "In11.Cu")
		(net 87)
	)
	(segment
		(start 193.57 144.05)
		(end 193.57 146.789706)
		(width 0.09)
		(layer "In11.Cu")
		(net 87)
	)
	(segment
		(start 210.03 149.779706)
		(end 210.03 144.61092)
		(width 0.09)
		(layer "In11.Cu")
		(net 87)
	)
	(segment
		(start 205.050294 125.89)
		(end 204.779 126.161294)
		(width 0.09)
		(layer "In11.Cu")
		(net 87)
	)
	(segment
		(start 211.835 142.80592)
		(end 211.835 138.065294)
		(width 0.09)
		(layer "In11.Cu")
		(net 87)
	)
	(segment
		(start 204.779 126.421)
		(end 204.499 126.701)
		(width 0.09)
		(layer "In11.Cu")
		(net 87)
	)
	(segment
		(start 204.779 126.161294)
		(end 204.779 126.421)
		(width 0.09)
		(layer "In11.Cu")
		(net 87)
	)
	(segment
		(start 192.835 144.055)
		(end 192.83 144.06)
		(width 0.09)
		(layer "F.Cu")
		(net 88)
	)
	(segment
		(start 192.835 144)
		(end 192.835 144.055)
		(width 0.09)
		(layer "F.Cu")
		(net 88)
	)
	(segment
		(start 192.835 143.995)
		(end 192.84 143.99)
		(width 0.09)
		(layer "F.Cu")
		(net 88)
	)
	(segment
		(start 192.835 144)
		(end 192.835 143.995)
		(width 0.09)
		(layer "F.Cu")
		(net 88)
	)
	(via
		(at 192.83 144.06)
		(size 0.35)
		(drill 0.15)
		(layers "F.Cu" "B.Cu")
		(net 88)
	)
	(via
		(at 203.699 134.7)
		(size 0.35)
		(drill 0.15)
		(layers "F.Cu" "B.Cu")
		(remove_unused_layers yes)
		(keep_end_layers yes)
		(zone_layer_connections)
		(net 88)
	)
	(segment
		(start 191.38 142.470294)
		(end 191.810294 142.04)
		(width 0.09)
		(layer "In11.Cu")
		(net 88)
	)
	(segment
		(start 191.38 143.58)
		(end 191.38 142.470294)
		(width 0.09)
		(layer "In11.Cu")
		(net 88)
	)
	(segment
		(start 197.622083 144.342033)
		(end 197.699864 144.419814)
		(width 0.09)
		(layer "In11.Cu")
		(net 88)
	)
	(segment
		(start 197.841286 144.419814)
		(end 198.109986 144.151113)
		(width 0.09)
		(layer "In11.Cu")
		(net 88)
	)
	(segment
		(start 192.06 144.26)
		(end 191.38 143.58)
		(width 0.09)
		(layer "In11.Cu")
		(net 88)
	)
	(segment
		(start 197.501877 143.062171)
		(end 197.501875 143.06217)
		(width 0.09)
		(layer "In11.Cu")
		(net 88)
	)
	(segment
		(start 197.643299 143.062172)
		(end 198.018064 142.687404)
		(width 0.09)
		(layer "In11.Cu")
		(net 88)
	)
	(segment
		(start 196.954853 142.015147)
		(end 197.25 142.310294)
		(width 0.09)
		(layer "In11.Cu")
		(net 88)
	)
	(segment
		(start 198.576678 143.246018)
		(end 198.201912 143.620785)
		(width 0.09)
		(layer "In11.Cu")
		(net 88)
	)
	(segment
		(start 198.046347 143.776347)
		(end 197.890784 143.931911)
		(width 0.09)
		(layer "In11.Cu")
		(net 88)
	)
	(segment
		(start 195.048908 142.98)
		(end 195.158908 142.98)
		(width 0.09)
		(layer "In11.Cu")
		(net 88)
	)
	(segment
		(start 192.511593 144.06)
		(end 192.311593 144.26)
		(width 0.09)
		(layer "In11.Cu")
		(net 88)
	)
	(segment
		(start 199.93 145.830294)
		(end 199.93 146.810294)
		(width 0.09)
		(layer "In11.Cu")
		(net 88)
	)
	(segment
		(start 192.311593 144.26)
		(end 192.06 144.26)
		(width 0.09)
		(layer "In11.Cu")
		(net 88)
	)
	(segment
		(start 193.270294 141.86)
		(end 193.508908 141.86)
		(width 0.09)
		(layer "In11.Cu")
		(net 88)
	)
	(segment
		(start 198.187768 145.331981)
		(end 198.265549 145.409762)
		(width 0.09)
		(layer "In11.Cu")
		(net 88)
	)
	(segment
		(start 193.848908 142.2)
		(end 193.848908 142.88)
		(width 0.09)
		(layer "In11.Cu")
		(net 88)
	)
	(segment
		(start 199.64 145.540294)
		(end 199.93 145.830294)
		(width 0.09)
		(layer "In11.Cu")
		(net 88)
	)
	(segment
		(start 195.708908 141.86)
		(end 196.799706 141.86)
		(width 0.09)
		(layer "In11.Cu")
		(net 88)
	)
	(segment
		(start 199.446419 145.006713)
		(end 199.64 145.200294)
		(width 0.09)
		(layer "In11.Cu")
		(net 88)
	)
	(segment
		(start 198.406971 145.409762)
		(end 198.887803 144.928929)
		(width 0.09)
		(layer "In11.Cu")
		(net 88)
	)
	(segment
		(start 197.25 142.310294)
		(end 197.25 142.810294)
		(width 0.09)
		(layer "In11.Cu")
		(net 88)
	)
	(segment
		(start 197.890784 143.931911)
		(end 197.622083 144.200611)
		(width 0.09)
		(layer "In11.Cu")
		(net 88)
	)
	(segment
		(start 194.498908 141.86)
		(end 194.608908 141.86)
		(width 0.09)
		(layer "In11.Cu")
		(net 88)
	)
	(segment
		(start 198.668601 144.709728)
		(end 198.187768 145.19056)
		(width 0.09)
		(layer "In11.Cu")
		(net 88)
	)
	(segment
		(start 206.92 134.819706)
		(end 206.560294 134.46)
		(width 0.09)
		(layer "In11.Cu")
		(net 88)
	)
	(segment
		(start 198.046348 143.776349)
		(end 198.046347 143.776347)
		(width 0.09)
		(layer "In11.Cu")
		(net 88)
	)
	(segment
		(start 191.810294 142.04)
		(end 193.090294 142.04)
		(width 0.09)
		(layer "In11.Cu")
		(net 88)
	)
	(segment
		(start 206.32 134.46)
		(end 206.29 134.43)
		(width 0.09)
		(layer "In11.Cu")
		(net 88)
	)
	(segment
		(start 199.368636 144.928929)
		(end 199.446419 145.006713)
		(width 0.09)
		(layer "In11.Cu")
		(net 88)
	)
	(segment
		(start 194.158908 142.88)
		(end 194.158908 142.2)
		(width 0.09)
		(layer "In11.Cu")
		(net 88)
	)
	(segment
		(start 195.258908 142.88)
		(end 195.258908 142.2)
		(width 0.09)
		(layer "In11.Cu")
		(net 88)
	)
	(segment
		(start 192.83 144.06)
		(end 192.511593 144.06)
		(width 0.09)
		(layer "In11.Cu")
		(net 88)
	)
	(segment
		(start 196.799706 141.86)
		(end 196.954853 142.015147)
		(width 0.09)
		(layer "In11.Cu")
		(net 88)
	)
	(segment
		(start 205.319706 148.52)
		(end 205.829706 149.03)
		(width 0.09)
		(layer "In11.Cu")
		(net 88)
	)
	(segment
		(start 195.598908 141.86)
		(end 195.708908 141.86)
		(width 0.09)
		(layer "In11.Cu")
		(net 88)
	)
	(segment
		(start 206.490294 149.03)
		(end 206.92 148.600294)
		(width 0.09)
		(layer "In11.Cu")
		(net 88)
	)
	(segment
		(start 198.498898 142.687405)
		(end 198.576679 142.765186)
		(width 0.09)
		(layer "In11.Cu")
		(net 88)
	)
	(segment
		(start 206.92 148.600294)
		(end 206.92 134.819706)
		(width 0.09)
		(layer "In11.Cu")
		(net 88)
	)
	(segment
		(start 200.479706 147.36)
		(end 201.559706 147.36)
		(width 0.09)
		(layer "In11.Cu")
		(net 88)
	)
	(segment
		(start 193.948908 142.98)
		(end 194.058908 142.98)
		(width 0.09)
		(layer "In11.Cu")
		(net 88)
	)
	(segment
		(start 193.090294 142.04)
		(end 193.270294 141.86)
		(width 0.09)
		(layer "In11.Cu")
		(net 88)
	)
	(segment
		(start 201.95 148.230294)
		(end 202.239706 148.52)
		(width 0.09)
		(layer "In11.Cu")
		(net 88)
	)
	(segment
		(start 199.93 146.810294)
		(end 200.479706 147.36)
		(width 0.09)
		(layer "In11.Cu")
		(net 88)
	)
	(segment
		(start 203.969 134.43)
		(end 203.699 134.7)
		(width 0.09)
		(layer "In11.Cu")
		(net 88)
	)
	(segment
		(start 206.29 134.43)
		(end 203.969 134.43)
		(width 0.09)
		(layer "In11.Cu")
		(net 88)
	)
	(segment
		(start 202.239706 148.52)
		(end 205.319706 148.52)
		(width 0.09)
		(layer "In11.Cu")
		(net 88)
	)
	(segment
		(start 198.590819 144.151113)
		(end 198.668601 144.228896)
		(width 0.09)
		(layer "In11.Cu")
		(net 88)
	)
	(segment
		(start 198.201912 143.620785)
		(end 198.046348 143.776349)
		(width 0.09)
		(layer "In11.Cu")
		(net 88)
	)
	(segment
		(start 201.559706 147.36)
		(end 201.95 147.750294)
		(width 0.09)
		(layer "In11.Cu")
		(net 88)
	)
	(segment
		(start 199.64 145.200294)
		(end 199.64 145.540294)
		(width 0.09)
		(layer "In11.Cu")
		(net 88)
	)
	(segment
		(start 197.25 142.810294)
		(end 197.501877 143.062171)
		(width 0.09)
		(layer "In11.Cu")
		(net 88)
	)
	(segment
		(start 206.560294 134.46)
		(end 206.32 134.46)
		(width 0.09)
		(layer "In11.Cu")
		(net 88)
	)
	(segment
		(start 201.95 147.750294)
		(end 201.95 148.230294)
		(width 0.09)
		(layer "In11.Cu")
		(net 88)
	)
	(segment
		(start 205.829706 149.03)
		(end 206.490294 149.03)
		(width 0.09)
		(layer "In11.Cu")
		(net 88)
	)
	(segment
		(start 194.948908 142.2)
		(end 194.948908 142.88)
		(width 0.09)
		(layer "In11.Cu")
		(net 88)
	)
	(arc
		(start 198.887803 144.928929)
		(mid 199.128219 144.829345)
		(end 199.368636 144.928929)
		(width 0.09)
		(layer "In11.Cu")
		(net 88)
	)
	(arc
		(start 194.608908 141.86)
		(mid 194.849324 141.959584)
		(end 194.948908 142.2)
		(width 0.09)
		(layer "In11.Cu")
		(net 88)
	)
	(arc
		(start 198.018064 142.687404)
		(mid 198.25848 142.58782)
		(end 198.498898 142.687405)
		(width 0.09)
		(layer "In11.Cu")
		(net 88)
	)
	(arc
		(start 197.501875 143.06217)
		(mid 197.572588 143.091461)
		(end 197.643299 143.062172)
		(width 0.09)
		(layer "In11.Cu")
		(net 88)
	)
	(arc
		(start 197.622083 144.200611)
		(mid 197.592794 144.271322)
		(end 197.622083 144.342033)
		(width 0.09)
		(layer "In11.Cu")
		(net 88)
	)
	(arc
		(start 194.948908 142.88)
		(mid 194.978197 142.950711)
		(end 195.048908 142.98)
		(width 0.09)
		(layer "In11.Cu")
		(net 88)
	)
	(arc
		(start 195.158908 142.98)
		(mid 195.229619 142.950711)
		(end 195.258908 142.88)
		(width 0.09)
		(layer "In11.Cu")
		(net 88)
	)
	(arc
		(start 197.699864 144.419814)
		(mid 197.770575 144.449103)
		(end 197.841286 144.419814)
		(width 0.09)
		(layer "In11.Cu")
		(net 88)
	)
	(arc
		(start 198.576679 142.765186)
		(mid 198.676262 143.005603)
		(end 198.576678 143.246018)
		(width 0.09)
		(layer "In11.Cu")
		(net 88)
	)
	(arc
		(start 194.058908 142.98)
		(mid 194.129619 142.950711)
		(end 194.158908 142.88)
		(width 0.09)
		(layer "In11.Cu")
		(net 88)
	)
	(arc
		(start 193.848908 142.88)
		(mid 193.878197 142.950711)
		(end 193.948908 142.98)
		(width 0.09)
		(layer "In11.Cu")
		(net 88)
	)
	(arc
		(start 194.158908 142.2)
		(mid 194.258492 141.959584)
		(end 194.498908 141.86)
		(width 0.09)
		(layer "In11.Cu")
		(net 88)
	)
	(arc
		(start 198.109986 144.151113)
		(mid 198.350402 144.051529)
		(end 198.590819 144.151113)
		(width 0.09)
		(layer "In11.Cu")
		(net 88)
	)
	(arc
		(start 198.265549 145.409762)
		(mid 198.33626 145.439051)
		(end 198.406971 145.409762)
		(width 0.09)
		(layer "In11.Cu")
		(net 88)
	)
	(arc
		(start 193.508908 141.86)
		(mid 193.749324 141.959584)
		(end 193.848908 142.2)
		(width 0.09)
		(layer "In11.Cu")
		(net 88)
	)
	(arc
		(start 195.258908 142.2)
		(mid 195.358492 141.959584)
		(end 195.598908 141.86)
		(width 0.09)
		(layer "In11.Cu")
		(net 88)
	)
	(arc
		(start 198.668601 144.228896)
		(mid 198.768185 144.469312)
		(end 198.668601 144.709728)
		(width 0.09)
		(layer "In11.Cu")
		(net 88)
	)
	(arc
		(start 198.187768 145.19056)
		(mid 198.158479 145.26127)
		(end 198.187768 145.331981)
		(width 0.09)
		(layer "In11.Cu")
		(net 88)
	)
	(segment
		(start 192.1975 144)
		(end 192.1975 143.9825)
		(width 0.09)
		(layer "F.Cu")
		(net 89)
	)
	(segment
		(start 192.1975 143.9825)
		(end 192.29 143.89)
		(width 0.09)
		(layer "F.Cu")
		(net 89)
	)
	(segment
		(start 192.1975 144)
		(end 192.1975 143.8725)
		(width 0.09)
		(layer "F.Cu")
		(net 89)
	)
	(segment
		(start 192.1975 143.8725)
		(end 192.23 143.84)
		(width 0.09)
		(layer "F.Cu")
		(net 89)
	)
	(via
		(at 192.23 143.84)
		(size 0.35)
		(drill 0.15)
		(layers "F.Cu" "B.Cu")
		(net 89)
	)
	(via
		(at 203.699 133.9)
		(size 0.35)
		(drill 0.15)
		(layers "F.Cu" "B.Cu")
		(remove_unused_layers yes)
		(keep_end_layers yes)
		(zone_layer_connections)
		(net 89)
	)
	(segment
		(start 195.598908 142.1)
		(end 195.708908 142.1)
		(width 0.09)
		(layer "In11.Cu")
		(net 89)
	)
	(segment
		(start 197.01 142.909706)
		(end 197.332171 143.231877)
		(width 0.09)
		(layer "In11.Cu")
		(net 89)
	)
	(segment
		(start 192.48 143.84)
		(end 192.53 143.79)
		(width 0.09)
		(layer "In11.Cu")
		(net 89)
	)
	(segment
		(start 199.69 145.929706)
		(end 199.69 146.909706)
		(width 0.09)
		(layer "In11.Cu")
		(net 89)
	)
	(segment
		(start 197.452378 144.511738)
		(end 197.530159 144.589519)
		(width 0.09)
		(layer "In11.Cu")
		(net 89)
	)
	(segment
		(start 194.708908 142.2)
		(end 194.708908 142.88)
		(width 0.09)
		(layer "In11.Cu")
		(net 89)
	)
	(segment
		(start 199.4 145.299706)
		(end 199.4 145.540294)
		(width 0.09)
		(layer "In11.Cu")
		(net 89)
	)
	(segment
		(start 198.329191 142.85711)
		(end 198.406972 142.934891)
		(width 0.09)
		(layer "In11.Cu")
		(net 89)
	)
	(segment
		(start 199.4 145.639706)
		(end 199.69 145.929706)
		(width 0.09)
		(layer "In11.Cu")
		(net 89)
	)
	(segment
		(start 192.46 143.48)
		(end 191.71 143.48)
		(width 0.09)
		(layer "In11.Cu")
		(net 89)
	)
	(segment
		(start 206.589706 149.27)
		(end 207.16 148.699706)
		(width 0.09)
		(layer "In11.Cu")
		(net 89)
	)
	(segment
		(start 206.659706 134.22)
		(end 206.29 134.22)
		(width 0.09)
		(layer "In11.Cu")
		(net 89)
	)
	(segment
		(start 197.721078 143.762205)
		(end 197.452378 144.030906)
		(width 0.09)
		(layer "In11.Cu")
		(net 89)
	)
	(segment
		(start 197.813004 143.231877)
		(end 198.187769 142.857109)
		(width 0.09)
		(layer "In11.Cu")
		(net 89)
	)
	(segment
		(start 191.909706 142.28)
		(end 193.189706 142.28)
		(width 0.09)
		(layer "In11.Cu")
		(net 89)
	)
	(segment
		(start 192.53 143.79)
		(end 192.53 143.55)
		(width 0.09)
		(layer "In11.Cu")
		(net 89)
	)
	(segment
		(start 195.048908 143.22)
		(end 195.158908 143.22)
		(width 0.09)
		(layer "In11.Cu")
		(net 89)
	)
	(segment
		(start 199.69 146.909706)
		(end 200.380294 147.6)
		(width 0.09)
		(layer "In11.Cu")
		(net 89)
	)
	(segment
		(start 201.71 147.849706)
		(end 201.71 148.329706)
		(width 0.09)
		(layer "In11.Cu")
		(net 89)
	)
	(segment
		(start 193.369706 142.1)
		(end 193.508908 142.1)
		(width 0.09)
		(layer "In11.Cu")
		(net 89)
	)
	(segment
		(start 199.19893 145.098636)
		(end 199.276713 145.176419)
		(width 0.09)
		(layer "In11.Cu")
		(net 89)
	)
	(segment
		(start 193.608908 142.2)
		(end 193.608908 142.88)
		(width 0.09)
		(layer "In11.Cu")
		(net 89)
	)
	(segment
		(start 197.876642 143.606642)
		(end 197.721078 143.762205)
		(width 0.09)
		(layer "In11.Cu")
		(net 89)
	)
	(segment
		(start 206.26 134.25)
		(end 204.049 134.25)
		(width 0.09)
		(layer "In11.Cu")
		(net 89)
	)
	(segment
		(start 198.576677 145.579469)
		(end 199.057509 145.098636)
		(width 0.09)
		(layer "In11.Cu")
		(net 89)
	)
	(segment
		(start 199.276713 145.176419)
		(end 199.4 145.299706)
		(width 0.09)
		(layer "In11.Cu")
		(net 89)
	)
	(segment
		(start 196.785147 142.184853)
		(end 197.01 142.409706)
		(width 0.09)
		(layer "In11.Cu")
		(net 89)
	)
	(segment
		(start 196.700294 142.1)
		(end 196.785147 142.184853)
		(width 0.09)
		(layer "In11.Cu")
		(net 89)
	)
	(segment
		(start 200.380294 147.6)
		(end 201.460294 147.6)
		(width 0.09)
		(layer "In11.Cu")
		(net 89)
	)
	(segment
		(start 193.189706 142.28)
		(end 193.369706 142.1)
		(width 0.09)
		(layer "In11.Cu")
		(net 89)
	)
	(segment
		(start 192.53 143.55)
		(end 192.46 143.48)
		(width 0.09)
		(layer "In11.Cu")
		(net 89)
	)
	(segment
		(start 191.62 143.39)
		(end 191.62 142.569706)
		(width 0.09)
		(layer "In11.Cu")
		(net 89)
	)
	(segment
		(start 198.406972 143.076313)
		(end 198.032204 143.451078)
		(width 0.09)
		(layer "In11.Cu")
		(net 89)
	)
	(segment
		(start 197.87664 143.606642)
		(end 197.876642 143.606642)
		(width 0.09)
		(layer "In11.Cu")
		(net 89)
	)
	(segment
		(start 198.018063 145.501688)
		(end 198.095844 145.579469)
		(width 0.09)
		(layer "In11.Cu")
		(net 89)
	)
	(segment
		(start 204.049 134.25)
		(end 203.699 133.9)
		(width 0.09)
		(layer "In11.Cu")
		(net 89)
	)
	(segment
		(start 201.460294 147.6)
		(end 201.71 147.849706)
		(width 0.09)
		(layer "In11.Cu")
		(net 89)
	)
	(segment
		(start 198.421113 144.320818)
		(end 198.498896 144.398601)
		(width 0.09)
		(layer "In11.Cu")
		(net 89)
	)
	(segment
		(start 197.332171 143.231877)
		(end 197.33217 143.231875)
		(width 0.09)
		(layer "In11.Cu")
		(net 89)
	)
	(segment
		(start 194.498908 142.1)
		(end 194.608908 142.1)
		(width 0.09)
		(layer "In11.Cu")
		(net 89)
	)
	(segment
		(start 201.71 148.329706)
		(end 202.140294 148.76)
		(width 0.09)
		(layer "In11.Cu")
		(net 89)
	)
	(segment
		(start 207.16 148.699706)
		(end 207.16 134.720294)
		(width 0.09)
		(layer "In11.Cu")
		(net 89)
	)
	(segment
		(start 192.23 143.84)
		(end 192.48 143.84)
		(width 0.09)
		(layer "In11.Cu")
		(net 89)
	)
	(segment
		(start 205.730294 149.27)
		(end 206.589706 149.27)
		(width 0.09)
		(layer "In11.Cu")
		(net 89)
	)
	(segment
		(start 197.01 142.409706)
		(end 197.01 142.909706)
		(width 0.09)
		(layer "In11.Cu")
		(net 89)
	)
	(segment
		(start 191.71 143.48)
		(end 191.62 143.39)
		(width 0.09)
		(layer "In11.Cu")
		(net 89)
	)
	(segment
		(start 207.16 134.720294)
		(end 206.659706 134.22)
		(width 0.09)
		(layer "In11.Cu")
		(net 89)
	)
	(segment
		(start 198.010992 144.589519)
		(end 198.279692 144.320818)
		(width 0.09)
		(layer "In11.Cu")
		(net 89)
	)
	(segment
		(start 198.498896 144.540023)
		(end 198.018063 145.020855)
		(width 0.09)
		(layer "In11.Cu")
		(net 89)
	)
	(segment
		(start 194.398908 142.88)
		(end 194.398908 142.2)
		(width 0.09)
		(layer "In11.Cu")
		(net 89)
	)
	(segment
		(start 195.498908 142.88)
		(end 195.498908 142.2)
		(width 0.09)
		(layer "In11.Cu")
		(net 89)
	)
	(segment
		(start 205.220294 148.76)
		(end 205.730294 149.27)
		(width 0.09)
		(layer "In11.Cu")
		(net 89)
	)
	(segment
		(start 206.29 134.22)
		(end 206.26 134.25)
		(width 0.09)
		(layer "In11.Cu")
		(net 89)
	)
	(segment
		(start 198.032204 143.451078)
		(end 197.87664 143.606642)
		(width 0.09)
		(layer "In11.Cu")
		(net 89)
	)
	(segment
		(start 193.948908 143.22)
		(end 194.058908 143.22)
		(width 0.09)
		(layer "In11.Cu")
		(net 89)
	)
	(segment
		(start 202.140294 148.76)
		(end 205.220294 148.76)
		(width 0.09)
		(layer "In11.Cu")
		(net 89)
	)
	(segment
		(start 195.708908 142.1)
		(end 196.700294 142.1)
		(width 0.09)
		(layer "In11.Cu")
		(net 89)
	)
	(segment
		(start 191.62 142.569706)
		(end 191.909706 142.28)
		(width 0.09)
		(layer "In11.Cu")
		(net 89)
	)
	(segment
		(start 199.4 145.540294)
		(end 199.4 145.639706)
		(width 0.09)
		(layer "In11.Cu")
		(net 89)
	)
	(arc
		(start 197.530159 144.589519)
		(mid 197.770576 144.689102)
		(end 198.010992 144.589519)
		(width 0.09)
		(layer "In11.Cu")
		(net 89)
	)
	(arc
		(start 198.187769 142.857109)
		(mid 198.25848 142.827821)
		(end 198.329191 142.85711)
		(width 0.09)
		(layer "In11.Cu")
		(net 89)
	)
	(arc
		(start 193.608908 142.88)
		(mid 193.708492 143.120416)
		(end 193.948908 143.22)
		(width 0.09)
		(layer "In11.Cu")
		(net 89)
	)
	(arc
		(start 198.406972 142.934891)
		(mid 198.436261 143.005602)
		(end 198.406972 143.076313)
		(width 0.09)
		(layer "In11.Cu")
		(net 89)
	)
	(arc
		(start 197.33217 143.231875)
		(mid 197.572588 143.331461)
		(end 197.813004 143.231877)
		(width 0.09)
		(layer "In11.Cu")
		(net 89)
	)
	(arc
		(start 195.498908 142.2)
		(mid 195.528197 142.129289)
		(end 195.598908 142.1)
		(width 0.09)
		(layer "In11.Cu")
		(net 89)
	)
	(arc
		(start 199.057509 145.098636)
		(mid 199.128219 145.069347)
		(end 199.19893 145.098636)
		(width 0.09)
		(layer "In11.Cu")
		(net 89)
	)
	(arc
		(start 198.095844 145.579469)
		(mid 198.336261 145.679052)
		(end 198.576677 145.579469)
		(width 0.09)
		(layer "In11.Cu")
		(net 89)
	)
	(arc
		(start 197.452378 144.030906)
		(mid 197.352794 144.271322)
		(end 197.452378 144.511738)
		(width 0.09)
		(layer "In11.Cu")
		(net 89)
	)
	(arc
		(start 198.498896 144.398601)
		(mid 198.528185 144.469312)
		(end 198.498896 144.540023)
		(width 0.09)
		(layer "In11.Cu")
		(net 89)
	)
	(arc
		(start 194.398908 142.2)
		(mid 194.428197 142.129289)
		(end 194.498908 142.1)
		(width 0.09)
		(layer "In11.Cu")
		(net 89)
	)
	(arc
		(start 198.279692 144.320818)
		(mid 198.350402 144.291529)
		(end 198.421113 144.320818)
		(width 0.09)
		(layer "In11.Cu")
		(net 89)
	)
	(arc
		(start 198.018063 145.020855)
		(mid 197.918479 145.261271)
		(end 198.018063 145.501688)
		(width 0.09)
		(layer "In11.Cu")
		(net 89)
	)
	(arc
		(start 194.708908 142.88)
		(mid 194.808492 143.120416)
		(end 195.048908 143.22)
		(width 0.09)
		(layer "In11.Cu")
		(net 89)
	)
	(arc
		(start 194.058908 143.22)
		(mid 194.299324 143.120416)
		(end 194.398908 142.88)
		(width 0.09)
		(layer "In11.Cu")
		(net 89)
	)
	(arc
		(start 193.508908 142.1)
		(mid 193.579619 142.129289)
		(end 193.608908 142.2)
		(width 0.09)
		(layer "In11.Cu")
		(net 89)
	)
	(arc
		(start 194.608908 142.1)
		(mid 194.679619 142.129289)
		(end 194.708908 142.2)
		(width 0.09)
		(layer "In11.Cu")
		(net 89)
	)
	(arc
		(start 195.158908 143.22)
		(mid 195.399324 143.120416)
		(end 195.498908 142.88)
		(width 0.09)
		(layer "In11.Cu")
		(net 89)
	)
	(segment
		(start 180.44 138.4)
		(end 180.44 138.36)
		(width 0.174)
		(layer "F.Cu")
		(net 90)
	)
	(segment
		(start 180.8 138.76)
		(end 180.8 139.8375)
		(width 0.174)
		(layer "F.Cu")
		(net 90)
	)
	(segment
		(start 179.564 140.9875)
		(end 178.725 140.9875)
		(width 0.174)
		(layer "F.Cu")
		(net 90)
	)
	(segment
		(start 184.77 120.07)
		(end 185.45 120.75)
		(width 0.15)
		(layer "F.Cu")
		(net 90)
	)
	(segment
		(start 180.44 138.36)
		(end 179.9125 137.8325)
		(width 0.174)
		(layer "F.Cu")
		(net 90)
	)
	(segment
		(start 180.44 138.4)
		(end 180.8 138.76)
		(width 0.174)
		(layer "F.Cu")
		(net 90)
	)
	(segment
		(start 180.8 143.0715)
		(end 180.616 142.8875)
		(width 0.174)
		(layer "F.Cu")
		(net 90)
	)
	(segment
		(start 184.77 118.49)
		(end 184.77 120.07)
		(width 0.15)
		(layer "F.Cu")
		(net 90)
	)
	(segment
		(start 179.584 140.9675)
		(end 179.564 140.9875)
		(width 0.174)
		(layer "F.Cu")
		(net 90)
	)
	(segment
		(start 181.525 140.9875)
		(end 180.616 140.9875)
		(width 0.174)
		(layer "F.Cu")
		(net 90)
	)
	(segment
		(start 179.584 142.8875)
		(end 178.725 142.8875)
		(width 0.174)
		(layer "F.Cu")
		(net 90)
	)
	(segment
		(start 179.9125 137.8325)
		(end 179.731 137.8325)
		(width 0.174)
		(layer "F.Cu")
		(net 90)
	)
	(segment
		(start 184.75 118.47)
		(end 184.77 118.49)
		(width 0.15)
		(layer "F.Cu")
		(net 90)
	)
	(segment
		(start 180.8 144.0375)
		(end 180.8 143.0715)
		(width 0.174)
		(layer "F.Cu")
		(net 90)
	)
	(segment
		(start 181.525 142.8875)
		(end 180.616 142.8875)
		(width 0.174)
		(layer "F.Cu")
		(net 90)
	)
	(via
		(at 180.334404 146.854531)
		(size 0.35)
		(drill 0.15)
		(layers "F.Cu" "B.Cu")
		(remove_unused_layers yes)
		(keep_end_layers yes)
		(zone_layer_connections "In9.Cu" "In11.Cu")
		(net 90)
	)
	(via
		(at 193.302 116.46)
		(size 0.35)
		(drill 0.15)
		(layers "F.Cu" "B.Cu")
		(remove_unused_layers yes)
		(keep_end_layers yes)
		(zone_layer_connections "In9.Cu")
		(net 90)
	)
	(via
		(at 182.55 146.15)
		(size 0.35)
		(drill 0.15)
		(layers "F.Cu" "B.Cu")
		(remove_unused_layers yes)
		(keep_end_layers yes)
		(zone_layer_connections "In9.Cu" "In11.Cu")
		(net 90)
	)
	(via
		(at 183.48 146.65)
		(size 0.35)
		(drill 0.15)
		(layers "F.Cu" "B.Cu")
		(remove_unused_layers yes)
		(keep_end_layers yes)
		(zone_layer_connections "In9.Cu" "In11.Cu")
		(net 90)
	)
	(via
		(at 194.122 116.479)
		(size 0.35)
		(drill 0.15)
		(layers "F.Cu" "B.Cu")
		(remove_unused_layers yes)
		(keep_end_layers yes)
		(zone_layer_connections "In9.Cu")
		(net 90)
	)
	(via
		(at 179.584404 148.154531)
		(size 0.35)
		(drill 0.15)
		(layers "F.Cu" "B.Cu")
		(remove_unused_layers yes)
		(keep_end_layers yes)
		(zone_layer_connections "In9.Cu" "In11.Cu")
		(net 90)
	)
	(via
		(at 192.922 116.945)
		(size 0.35)
		(drill 0.15)
		(layers "F.Cu" "B.Cu")
		(remove_unused_layers yes)
		(keep_end_layers yes)
		(zone_layer_connections "In9.Cu")
		(net 90)
	)
	(via
		(at 178.046001 140.9875)
		(size 0.35)
		(drill 0.15)
		(layers "F.Cu" "B.Cu")
		(remove_unused_layers yes)
		(keep_end_layers yes)
		(zone_layer_connections "In6.Cu" "In9.Cu")
		(net 90)
	)
	(via
		(at 178.046 142.881611)
		(size 0.35)
		(drill 0.15)
		(layers "F.Cu" "B.Cu")
		(remove_unused_layers yes)
		(keep_end_layers yes)
		(zone_layer_connections "In6.Cu" "In9.Cu")
		(net 90)
	)
	(via
		(at 192.124 116.945)
		(size 0.35)
		(drill 0.15)
		(layers "F.Cu" "B.Cu")
		(remove_unused_layers yes)
		(keep_end_layers yes)
		(zone_layer_connections "In9.Cu")
		(net 90)
	)
	(via
		(at 187.4 139.15)
		(size 0.35)
		(drill 0.15)
		(layers "F.Cu" "B.Cu")
		(remove_unused_layers yes)
		(keep_end_layers yes)
		(zone_layer_connections "In9.Cu")
		(net 90)
	)
	(via
		(at 180.075 142.8625)
		(size 0.35)
		(drill 0.15)
		(layers "F.Cu" "B.Cu")
		(remove_unused_layers yes)
		(keep_end_layers yes)
		(zone_layer_connections "In6.Cu" "In9.Cu")
		(net 90)
	)
	(via
		(at 182.154 142.8875)
		(size 0.35)
		(drill 0.15)
		(layers "F.Cu" "B.Cu")
		(remove_unused_layers yes)
		(keep_end_layers yes)
		(zone_layer_connections "In6.Cu" "In9.Cu")
		(net 90)
	)
	(via
		(at 228.675 124.999999)
		(size 0.35)
		(drill 0.15)
		(layers "F.Cu" "B.Cu")
		(remove_unused_layers yes)
		(keep_end_layers yes)
		(zone_layer_connections "In11.Cu")
		(net 90)
	)
	(via
		(at 179.584 142.8875)
		(size 0.35)
		(drill 0.15)
		(layers "F.Cu" "B.Cu")
		(remove_unused_layers yes)
		(keep_end_layers yes)
		(zone_layer_connections "In6.Cu" "In9.Cu")
		(net 90)
	)
	(via
		(at 212.4 139.2)
		(size 0.35)
		(drill 0.15)
		(layers "F.Cu" "B.Cu")
		(remove_unused_layers yes)
		(keep_end_layers yes)
		(zone_layer_connections "In11.Cu")
		(net 90)
	)
	(via
		(at 183.18 146.21)
		(size 0.35)
		(drill 0.15)
		(layers "F.Cu" "B.Cu")
		(remove_unused_layers yes)
		(keep_end_layers yes)
		(zone_layer_connections "In9.Cu" "In11.Cu")
		(net 90)
	)
	(via
		(at 193.719 116.945)
		(size 0.35)
		(drill 0.15)
		(layers "F.Cu" "B.Cu")
		(remove_unused_layers yes)
		(keep_end_layers yes)
		(zone_layer_connections "In9.Cu")
		(net 90)
	)
	(via
		(at 182.154 140.9875)
		(size 0.35)
		(drill 0.15)
		(layers "F.Cu" "B.Cu")
		(remove_unused_layers yes)
		(keep_end_layers yes)
		(zone_layer_connections "In6.Cu" "In9.Cu")
		(net 90)
	)
	(via
		(at 180.713955 143.286045)
		(size 0.35)
		(drill 0.15)
		(layers "F.Cu" "B.Cu")
		(remove_unused_layers yes)
		(keep_end_layers yes)
		(zone_layer_connections "In6.Cu" "In9.Cu")
		(net 90)
	)
	(via
		(at 192.505 116.46)
		(size 0.35)
		(drill 0.15)
		(layers "F.Cu" "B.Cu")
		(remove_unused_layers yes)
		(keep_end_layers yes)
		(zone_layer_connections "In9.Cu")
		(net 90)
	)
	(via
		(at 184.75 118.47)
		(size 0.35)
		(drill 0.15)
		(layers "F.Cu" "B.Cu")
		(remove_unused_layers yes)
		(keep_end_layers yes)
		(zone_layer_connections)
		(net 90)
	)
	(via
		(at 179.634404 147.054531)
		(size 0.35)
		(drill 0.15)
		(layers "F.Cu" "B.Cu")
		(remove_unused_layers yes)
		(keep_end_layers yes)
		(zone_layer_connections "In9.Cu" "In11.Cu")
		(net 90)
	)
	(via
		(at 180.44 138.4)
		(size 0.35)
		(drill 0.15)
		(layers "F.Cu" "B.Cu")
		(remove_unused_layers yes)
		(keep_end_layers yes)
		(zone_layer_connections "In9.Cu")
		(net 90)
	)
	(via
		(at 180.74 139.71)
		(size 0.35)
		(drill 0.15)
		(layers "F.Cu" "B.Cu")
		(remove_unused_layers yes)
		(keep_end_layers yes)
		(zone_layer_connections "In6.Cu" "In9.Cu")
		(net 90)
	)
	(via
		(at 180.616 142.8875)
		(size 0.35)
		(drill 0.15)
		(layers "F.Cu" "B.Cu")
		(remove_unused_layers yes)
		(keep_end_layers yes)
		(zone_layer_connections "In6.Cu" "In9.Cu")
		(net 90)
	)
	(via
		(at 179.634404 149.204531)
		(size 0.35)
		(drill 0.15)
		(layers "F.Cu" "B.Cu")
		(remove_unused_layers yes)
		(keep_end_layers yes)
		(zone_layer_connections "In9.Cu" "In11.Cu")
		(net 90)
	)
	(via
		(at 179.450359 147.659391)
		(size 0.35)
		(drill 0.15)
		(layers "F.Cu" "B.Cu")
		(remove_unused_layers yes)
		(keep_end_layers yes)
		(zone_layer_connections "In9.Cu" "In11.Cu")
		(net 90)
	)
	(via
		(at 182.82 146.55)
		(size 0.35)
		(drill 0.15)
		(layers "F.Cu" "B.Cu")
		(remove_unused_layers yes)
		(keep_end_layers yes)
		(zone_layer_connections "In9.Cu" "In11.Cu")
		(net 90)
	)
	(via
		(at 180.075 140.9625)
		(size 0.35)
		(drill 0.15)
		(layers "F.Cu" "B.Cu")
		(remove_unused_layers yes)
		(keep_end_layers yes)
		(zone_layer_connections "In6.Cu" "In9.Cu")
		(net 90)
	)
	(via
		(at 187.85 154.925)
		(size 0.35)
		(drill 0.15)
		(layers "F.Cu" "B.Cu")
		(remove_unused_layers yes)
		(keep_end_layers yes)
		(zone_layer_connections "In9.Cu" "In11.Cu")
		(net 90)
	)
	(via
		(at 180.616 140.9875)
		(size 0.35)
		(drill 0.15)
		(layers "F.Cu" "B.Cu")
		(remove_unused_layers yes)
		(keep_end_layers yes)
		(zone_layer_connections "In6.Cu" "In9.Cu")
		(net 90)
	)
	(via
		(at 181.490096 153.898958)
		(size 0.35)
		(drill 0.15)
		(layers "F.Cu" "B.Cu")
		(remove_unused_layers yes)
		(keep_end_layers yes)
		(zone_layer_connections "In9.Cu" "In11.Cu")
		(net 90)
	)
	(via
		(at 179.450359 148.659391)
		(size 0.35)
		(drill 0.15)
		(layers "F.Cu" "B.Cu")
		(remove_unused_layers yes)
		(keep_end_layers yes)
		(zone_layer_connections "In9.Cu" "In11.Cu")
		(net 90)
	)
	(via
		(at 179.584 140.9675)
		(size 0.35)
		(drill 0.15)
		(layers "F.Cu" "B.Cu")
		(remove_unused_layers yes)
		(keep_end_layers yes)
		(zone_layer_connections "In6.Cu" "In9.Cu")
		(net 90)
	)
	(via
		(at 180.8 140.2875)
		(size 0.35)
		(drill 0.15)
		(layers "F.Cu" "B.Cu")
		(remove_unused_layers yes)
		(keep_end_layers yes)
		(zone_layer_connections "In6.Cu" "In9.Cu")
		(net 90)
	)
	(via
		(at 186.9 139.4)
		(size 0.35)
		(drill 0.15)
		(layers "F.Cu" "B.Cu")
		(remove_unused_layers yes)
		(keep_end_layers yes)
		(zone_layer_connections "In9.Cu")
		(net 90)
	)
	(segment
		(start 198.619237 145.974086)
		(end 198.619237 146.830763)
		(width 0.2)
		(layer "B.Cu")
		(net 90)
	)
	(segment
		(start 180.261312 145.561312)
		(end 180.4725 145.561312)
		(width 0.2)
		(layer "B.Cu")
		(net 90)
	)
	(segment
		(start 180.848812 145.185)
		(end 181.360808 145.185)
		(width 0.2)
		(layer "B.Cu")
		(net 90)
	)
	(segment
		(start 180.4725 145.561312)
		(end 180.848812 145.185)
		(width 0.2)
		(layer "B.Cu")
		(net 90)
	)
	(segment
		(start 187.38 154.455)
		(end 187.85 154.925)
		(width 0.1)
		(layer "B.Cu")
		(net 90)
	)
	(segment
		(start 192.523 117.461)
		(end 192.523 116.478)
		(width 0.174)
		(layer "B.Cu")
		(net 90)
	)
	(segment
		(start 193.32 117.461)
		(end 193.32 116.478)
		(width 0.174)
		(layer "B.Cu")
		(net 90)
	)
	(segment
		(start 194.122 117.461)
		(end 194.122 116.479)
		(width 0.174)
		(layer "B.Cu")
		(net 90)
	)
	(segment
		(start 197.795151 145.15)
		(end 198.619237 145.974086)
		(width 0.8)
		(layer "B.Cu")
		(net 90)
	)
	(segment
		(start 197.19898 147.9)
		(end 196.355636 148.743344)
		(width 0.2)
		(layer "B.Cu")
		(net 90)
	)
	(segment
		(start 193.32 116.478)
		(end 193.302 116.46)
		(width 0.174)
		(layer "B.Cu")
		(net 90)
	)
	(segment
		(start 181.360808 145.185)
		(end 182.325808 146.15)
		(width 0.2)
		(layer "B.Cu")
		(net 90)
	)
	(segment
		(start 197.55 147.9)
		(end 197.19898 147.9)
		(width 0.2)
		(layer "B.Cu")
		(net 90)
	)
	(segment
		(start 187.875 154.9)
		(end 187.85 154.925)
		(width 0.2)
		(layer "B.Cu")
		(net 90)
	)
	(segment
		(start 198.619237 146.830763)
		(end 197.55 147.9)
		(width 0.2)
		(layer "B.Cu")
		(net 90)
	)
	(segment
		(start 187.38 152.485)
		(end 187.38 154.455)
		(width 0.1)
		(layer "B.Cu")
		(net 90)
	)
	(segment
		(start 187.875 151.99)
		(end 187.38 152.485)
		(width 0.1)
		(layer "B.Cu")
		(net 90)
	)
	(segment
		(start 179.77 145.07)
		(end 180.261312 145.561312)
		(width 0.2)
		(layer "B.Cu")
		(net 90)
	)
	(segment
		(start 182.325808 146.15)
		(end 182.55 146.15)
		(width 0.2)
		(layer "B.Cu")
		(net 90)
	)
	(segment
		(start 197.75 145.15)
		(end 197.795151 145.15)
		(width 0.8)
		(layer "B.Cu")
		(net 90)
	)
	(segment
		(start 179.75 145.07)
		(end 179.77 145.07)
		(width 0.2)
		(layer "B.Cu")
		(net 90)
	)
	(segment
		(start 192.523 116.478)
		(end 192.505 116.46)
		(width 0.174)
		(layer "B.Cu")
		(net 90)
	)
	(via
		(at 194.099 141.101)
		(size 0.35)
		(drill 0.15)
		(layers "F.Cu" "B.Cu")
		(remove_unused_layers yes)
		(keep_end_layers yes)
		(zone_layer_connections)
		(net 91)
	)
	(segment
		(start 194.1515 141.502053)
		(end 194.2515 141.502053)
		(width 0.125)
		(layer "B.Cu")
		(net 91)
	)
	(segment
		(start 194.099 141.101)
		(end 194.049723 141.150277)
		(width 0.125)
		(layer "B.Cu")
		(net 91)
	)
	(segment
		(start 195.55 143.1)
		(end 195.68 143.1)
		(width 0.125)
		(layer "B.Cu")
		(net 91)
	)
	(segment
		(start 194.64423 142.667434)
		(end 194.644229 142.667435)
		(width 0.125)
		(layer "B.Cu")
		(net 91)
	)
	(segment
		(start 195.100109 143.2425)
		(end 195.303947 143.2425)
		(width 0.125)
		(layer "B.Cu")
		(net 91)
	)
	(segment
		(start 194.962426 142.794714)
		(end 194.962427 142.794713)
		(width 0.125)
		(layer "B.Cu")
		(net 91)
	)
	(segment
		(start 194.2515 141.852053)
		(end 194.1515 141.852053)
		(width 0.125)
		(layer "B.Cu")
		(net 91)
	)
	(segment
		(start 194.962427 142.794713)
		(end 194.852779 142.904362)
		(width 0.125)
		(layer "B.Cu")
		(net 91)
	)
	(segment
		(start 194.049238 142.295182)
		(end 194.442014 142.687958)
		(width 0.125)
		(layer "B.Cu")
		(net 91)
	)
	(segment
		(start 193.9765 142.1)
		(end 193.976014 142.100486)
		(width 0.125)
		(layer "B.Cu")
		(net 91)
	)
	(segment
		(start 194.866968 143.112911)
		(end 194.866967 143.112911)
		(width 0.125)
		(layer "B.Cu")
		(net 91)
	)
	(segment
		(start 194.64423 142.667434)
		(end 194.623703 142.68796)
		(width 0.125)
		(layer "B.Cu")
		(net 91)
	)
	(segment
		(start 194.866967 143.112911)
		(end 194.923333 143.169277)
		(width 0.125)
		(layer "B.Cu")
		(net 91)
	)
	(segment
		(start 194.644229 142.667435)
		(end 194.739689 142.571976)
		(width 0.125)
		(layer "B.Cu")
		(net 91)
	)
	(segment
		(start 195.480724 143.169276)
		(end 195.55 143.1)
		(width 0.125)
		(layer "B.Cu")
		(net 91)
	)
	(segment
		(start 194.962427 142.571976)
		(end 194.962427 142.571975)
		(width 0.125)
		(layer "B.Cu")
		(net 91)
	)
	(segment
		(start 193.9765 142.027053)
		(end 193.9765 142.1)
		(width 0.125)
		(layer "B.Cu")
		(net 91)
	)
	(segment
		(start 193.976014 142.100486)
		(end 193.976014 142.118405)
		(width 0.125)
		(layer "B.Cu")
		(net 91)
	)
	(segment
		(start 194.866968 143.112911)
		(end 194.852814 143.098767)
		(width 0.125)
		(layer "B.Cu")
		(net 91)
	)
	(arc
		(start 194.049723 141.150277)
		(mid 193.99553 141.231383)
		(end 193.9765 141.327053)
		(width 0.125)
		(layer "B.Cu")
		(net 91)
	)
	(arc
		(start 194.739689 142.571976)
		(mid 194.851058 142.525845)
		(end 194.962427 142.571976)
		(width 0.125)
		(layer "B.Cu")
		(net 91)
	)
	(arc
		(start 194.4265 141.677053)
		(mid 194.375244 141.800797)
		(end 194.2515 141.852053)
		(width 0.125)
		(layer "B.Cu")
		(net 91)
	)
	(arc
		(start 194.442014 142.687958)
		(mid 194.532858 142.725587)
		(end 194.623703 142.68796)
		(width 0.125)
		(layer "B.Cu")
		(net 91)
	)
	(arc
		(start 195.480724 143.169276)
		(mid 195.399618 143.223469)
		(end 195.303947 143.2425)
		(width 0.125)
		(layer "B.Cu")
		(net 91)
	)
	(arc
		(start 194.1515 141.852053)
		(mid 194.027756 141.903309)
		(end 193.9765 142.027053)
		(width 0.125)
		(layer "B.Cu")
		(net 91)
	)
	(arc
		(start 193.976014 142.118405)
		(mid 193.995045 142.214076)
		(end 194.049238 142.295182)
		(width 0.125)
		(layer "B.Cu")
		(net 91)
	)
	(arc
		(start 194.962427 142.571975)
		(mid 195.008557 142.683345)
		(end 194.962426 142.794714)
		(width 0.125)
		(layer "B.Cu")
		(net 91)
	)
	(arc
		(start 194.852779 142.904362)
		(mid 194.812524 143.001572)
		(end 194.852814 143.098767)
		(width 0.125)
		(layer "B.Cu")
		(net 91)
	)
	(arc
		(start 194.2515 141.502053)
		(mid 194.375244 141.553309)
		(end 194.4265 141.677053)
		(width 0.125)
		(layer "B.Cu")
		(net 91)
	)
	(arc
		(start 194.923333 143.169277)
		(mid 195.004439 143.22347)
		(end 195.100109 143.2425)
		(width 0.125)
		(layer "B.Cu")
		(net 91)
	)
	(arc
		(start 193.9765 141.327053)
		(mid 194.027756 141.450797)
		(end 194.1515 141.502053)
		(width 0.125)
		(layer "B.Cu")
		(net 91)
	)
	(segment
		(start 181.3 145.9)
		(end 179.67 145.9)
		(width 0.15)
		(layer "F.Cu")
		(net 92)
	)
	(segment
		(start 204.499 123.249)
		(end 203.35 122.1)
		(width 0.1)
		(layer "F.Cu")
		(net 92)
	)
	(segment
		(start 181.42981 145.77019)
		(end 181.3 145.9)
		(width 0.15)
		(layer "F.Cu")
		(net 92)
	)
	(segment
		(start 179.45 145.3375)
		(end 179.45 144.0375)
		(width 0.15)
		(layer "F.Cu")
		(net 92)
	)
	(segment
		(start 204.499 124.3)
		(end 204.499 123.249)
		(width 0.1)
		(layer "F.Cu")
		(net 92)
	)
	(segment
		(start 179.67 145.9)
		(end 179.45 145.68)
		(width 0.15)
		(layer "F.Cu")
		(net 92)
	)
	(segment
		(start 203.35 122.1)
		(end 203.35 121.23)
		(width 0.1)
		(layer "F.Cu")
		(net 92)
	)
	(segment
		(start 177.45 148.149999)
		(end 178.25 148.15)
		(width 0.15)
		(layer "F.Cu")
		(net 92)
	)
	(segment
		(start 179.45 145.68)
		(end 179.45 145.3375)
		(width 0.15)
		(layer "F.Cu")
		(net 92)
	)
	(via
		(at 183.860904 147.831531)
		(size 0.35)
		(drill 0.15)
		(layers "F.Cu" "B.Cu")
		(remove_unused_layers yes)
		(keep_end_layers yes)
		(zone_layer_connections)
		(net 92)
	)
	(via
		(at 181.42981 145.77019)
		(size 0.35)
		(drill 0.15)
		(layers "F.Cu" "B.Cu")
		(remove_unused_layers yes)
		(keep_end_layers yes)
		(zone_layer_connections)
		(net 92)
	)
	(via
		(at 204.499 124.3)
		(size 0.35)
		(drill 0.15)
		(layers "F.Cu" "B.Cu")
		(remove_unused_layers yes)
		(keep_end_layers yes)
		(zone_layer_connections)
		(net 92)
	)
	(via
		(at 178.25 148.15)
		(size 0.35)
		(drill 0.15)
		(layers "F.Cu" "B.Cu")
		(remove_unused_layers yes)
		(keep_end_layers yes)
		(zone_layer_connections)
		(net 92)
	)
	(segment
		(start 202.45 122.6)
		(end 201.98 122.6)
		(width 0.1)
		(layer "B.Cu")
		(net 92)
	)
	(segment
		(start 181.42981 145.77981)
		(end 182.55 146.9)
		(width 0.15)
		(layer "B.Cu")
		(net 92)
	)
	(segment
		(start 181.42981 145.77019)
		(end 181.42981 145.77981)
		(width 0.15)
		(layer "B.Cu")
		(net 92)
	)
	(segment
		(start 203.8 123.95)
		(end 202.45 122.6)
		(width 0.1)
		(layer "B.Cu")
		(net 92)
	)
	(segment
		(start 182.55 146.9)
		(end 182.929373 146.9)
		(width 0.15)
		(layer "B.Cu")
		(net 92)
	)
	(segment
		(start 204.15862 124.3)
		(end 203.80862 123.95)
		(width 0.1)
		(layer "B.Cu")
		(net 92)
	)
	(segment
		(start 204.499 124.3)
		(end 204.15862 124.3)
		(width 0.1)
		(layer "B.Cu")
		(net 92)
	)
	(segment
		(start 182.929373 146.9)
		(end 183.860904 147.831531)
		(width 0.15)
		(layer "B.Cu")
		(net 92)
	)
	(segment
		(start 203.80862 123.95)
		(end 203.8 123.95)
		(width 0.1)
		(layer "B.Cu")
		(net 92)
	)
	(segment
		(start 176.18 150.55)
		(end 180.55 150.55)
		(width 0.1)
		(layer "In7.Cu")
		(net 92)
	)
	(segment
		(start 180.95 150.15)
		(end 183.141808 150.15)
		(width 0.1)
		(layer "In7.Cu")
		(net 92)
	)
	(segment
		(start 180.55 150.55)
		(end 180.95 150.15)
		(width 0.1)
		(layer "In7.Cu")
		(net 92)
	)
	(segment
		(start 183.860904 149.430904)
		(end 183.860904 147.831531)
		(width 0.1)
		(layer "In7.Cu")
		(net 92)
	)
	(segment
		(start 176.18 148.87)
		(end 175.74 149.31)
		(width 0.1)
		(layer "In7.Cu")
		(net 92)
	)
	(segment
		(start 178.25 148.15)
		(end 177.97 148.43)
		(width 0.1)
		(layer "In7.Cu")
		(net 92)
	)
	(segment
		(start 177.25 148.43)
		(end 176.81 148.87)
		(width 0.1)
		(layer "In7.Cu")
		(net 92)
	)
	(segment
		(start 175.74 150.11)
		(end 176.18 150.55)
		(width 0.1)
		(layer "In7.Cu")
		(net 92)
	)
	(segment
		(start 177.97 148.43)
		(end 177.25 148.43)
		(width 0.1)
		(layer "In7.Cu")
		(net 92)
	)
	(segment
		(start 176.81 148.87)
		(end 176.18 148.87)
		(width 0.1)
		(layer "In7.Cu")
		(net 92)
	)
	(segment
		(start 175.74 149.31)
		(end 175.74 150.11)
		(width 0.1)
		(layer "In7.Cu")
		(net 92)
	)
	(segment
		(start 183.141808 150.15)
		(end 183.860904 149.430904)
		(width 0.1)
		(layer "In7.Cu")
		(net 92)
	)
	(segment
		(start 194.23362 131.826)
		(end 194.11338 131.826)
		(width 0.1)
		(layer "In11.Cu")
		(net 92)
	)
	(segment
		(start 193.774 132.276)
		(end 193.2 132.85)
		(width 0.1)
		(layer "In11.Cu")
		(net 92)
	)
	(segment
		(start 195.375 130.775)
		(end 195.05 131.1)
		(width 0.1)
		(layer "In11.Cu")
		(net 92)
	)
	(segment
		(start 189.8 135.85)
		(end 189 135.85)
		(width 0.1)
		(layer "In11.Cu")
		(net 92)
	)
	(segment
		(start 204.174 123.975)
		(end 203.41538 123.975)
		(width 0.1)
		(layer "In11.Cu")
		(net 92)
	)
	(segment
		(start 194.8 131.1)
		(end 194.424 131.476)
		(width 0.1)
		(layer "In11.Cu")
		(net 92)
	)
	(segment
		(start 203 124.725)
		(end 202.66638 124.725)
		(width 0.1)
		(layer "In11.Cu")
		(net 92)
	)
	(segment
		(start 203.3 124.425)
		(end 203 124.725)
		(width 0.1)
		(layer "In11.Cu")
		(net 92)
	)
	(segment
		(start 180.55 144.03188)
		(end 180.55 145.85)
		(width 0.1)
		(layer "In11.Cu")
		(net 92)
	)
	(segment
		(start 180.55 145.85)
		(end 180.7875 146.0875)
		(width 0.1)
		(layer "In11.Cu")
		(net 92)
	)
	(segment
		(start 203.3 124.09038)
		(end 203.3 124.425)
		(width 0.1)
		(layer "In11.Cu")
		(net 92)
	)
	(segment
		(start 202.5 124.89138)
		(end 202.5 125.4)
		(width 0.1)
		(layer "In11.Cu")
		(net 92)
	)
	(segment
		(start 184.09 142.86)
		(end 183.7925 142.5625)
		(width 0.1)
		(layer "In11.Cu")
		(net 92)
	)
	(segment
		(start 197.31062 128.75)
		(end 195.76062 130.3)
		(width 0.1)
		(layer "In11.Cu")
		(net 92)
	)
	(segment
		(start 192.8 132.85)
		(end 189.8 135.85)
		(width 0.1)
		(layer "In11.Cu")
		(net 92)
	)
	(segment
		(start 195.76062 130.3)
		(end 195.6 130.3)
		(width 0.1)
		(layer "In11.Cu")
		(net 92)
	)
	(segment
		(start 201.725 125.675)
		(end 201.725 128.33462)
		(width 0.1)
		(layer "In11.Cu")
		(net 92)
	)
	(segment
		(start 181.1125 146.0875)
		(end 181.42981 145.77019)
		(width 0.1)
		(layer "In11.Cu")
		(net 92)
	)
	(segment
		(start 201.30962 128.75)
		(end 197.31062 128.75)
		(width 0.1)
		(layer "In11.Cu")
		(net 92)
	)
	(segment
		(start 194.11338 131.826)
		(end 193.774 132.16538)
		(width 0.1)
		(layer "In11.Cu")
		(net 92)
	)
	(segment
		(start 202.66638 124.725)
		(end 202.5 124.89138)
		(width 0.1)
		(layer "In11.Cu")
		(net 92)
	)
	(segment
		(start 185.575 142.36312)
		(end 185.07812 142.86)
		(width 0.1)
		(layer "In11.Cu")
		(net 92)
	)
	(segment
		(start 194.424 131.476)
		(end 194.424 131.63562)
		(width 0.1)
		(layer "In11.Cu")
		(net 92)
	)
	(segment
		(start 194.424 131.63562)
		(end 194.23362 131.826)
		(width 0.1)
		(layer "In11.Cu")
		(net 92)
	)
	(segment
		(start 202.4 125.5)
		(end 201.9 125.5)
		(width 0.1)
		(layer "In11.Cu")
		(net 92)
	)
	(segment
		(start 183.7925 142.5625)
		(end 182.01938 142.5625)
		(width 0.1)
		(layer "In11.Cu")
		(net 92)
	)
	(segment
		(start 202.5 125.4)
		(end 202.4 125.5)
		(width 0.1)
		(layer "In11.Cu")
		(net 92)
	)
	(segment
		(start 201.9 125.5)
		(end 201.725 125.675)
		(width 0.1)
		(layer "In11.Cu")
		(net 92)
	)
	(segment
		(start 195.375 130.525)
		(end 195.375 130.775)
		(width 0.1)
		(layer "In11.Cu")
		(net 92)
	)
	(segment
		(start 193.774 132.16538)
		(end 193.774 132.276)
		(width 0.1)
		(layer "In11.Cu")
		(net 92)
	)
	(segment
		(start 180.7875 146.0875)
		(end 181.1125 146.0875)
		(width 0.1)
		(layer "In11.Cu")
		(net 92)
	)
	(segment
		(start 203.41538 123.975)
		(end 203.3 124.09038)
		(width 0.1)
		(layer "In11.Cu")
		(net 92)
	)
	(segment
		(start 195.6 130.3)
		(end 195.375 130.525)
		(width 0.1)
		(layer "In11.Cu")
		(net 92)
	)
	(segment
		(start 204.499 124.3)
		(end 204.174 123.975)
		(width 0.1)
		(layer "In11.Cu")
		(net 92)
	)
	(segment
		(start 182.01938 142.5625)
		(end 180.55 144.03188)
		(width 0.1)
		(layer "In11.Cu")
		(net 92)
	)
	(segment
		(start 195.05 131.1)
		(end 194.8 131.1)
		(width 0.1)
		(layer "In11.Cu")
		(net 92)
	)
	(segment
		(start 189 135.85)
		(end 185.575 139.275)
		(width 0.1)
		(layer "In11.Cu")
		(net 92)
	)
	(segment
		(start 193.2 132.85)
		(end 192.8 132.85)
		(width 0.1)
		(layer "In11.Cu")
		(net 92)
	)
	(segment
		(start 201.725 128.33462)
		(end 201.30962 128.75)
		(width 0.1)
		(layer "In11.Cu")
		(net 92)
	)
	(segment
		(start 185.07812 142.86)
		(end 184.09 142.86)
		(width 0.1)
		(layer "In11.Cu")
		(net 92)
	)
	(segment
		(start 185.575 139.275)
		(end 185.575 142.36312)
		(width 0.1)
		(layer "In11.Cu")
		(net 92)
	)
	(via
		(at 195.7 140.3)
		(size 0.35)
		(drill 0.15)
		(layers "F.Cu" "B.Cu")
		(remove_unused_layers yes)
		(keep_end_layers yes)
		(zone_layer_connections)
		(net 93)
	)
	(segment
		(start 195.057835 141.636584)
		(end 195.303922 141.390497)
		(width 0.125)
		(layer "B.Cu")
		(net 93)
	)
	(segment
		(start 195.3625 141.249076)
		(end 195.3625 140.720343)
		(width 0.125)
		(layer "B.Cu")
		(net 93)
	)
	(segment
		(start 194.999256 142.126413)
		(end 194.999256 141.778006)
		(width 0.125)
		(layer "B.Cu")
		(net 93)
	)
	(segment
		(start 195.491422 142.541421)
		(end 195.479415 142.529414)
		(width 0.125)
		(layer "B.Cu")
		(net 93)
	)
	(segment
		(start 195.68 142.600001)
		(end 195.632842 142.600001)
		(width 0.125)
		(layer "B.Cu")
		(net 93)
	)
	(segment
		(start 195.260835 142.470835)
		(end 195.057834 142.267834)
		(width 0.125)
		(layer "B.Cu")
		(net 93)
	)
	(segment
		(start 195.421079 140.578921)
		(end 195.7 140.3)
		(width 0.125)
		(layer "B.Cu")
		(net 93)
	)
	(segment
		(start 195.337993 142.470835)
		(end 195.260835 142.470835)
		(width 0.125)
		(layer "B.Cu")
		(net 93)
	)
	(arc
		(start 194.999256 142.126413)
		(mid 195.01448 142.202949)
		(end 195.057834 142.267834)
		(width 0.125)
		(layer "B.Cu")
		(net 93)
	)
	(arc
		(start 195.303922 141.390497)
		(mid 195.347276 141.325612)
		(end 195.3625 141.249076)
		(width 0.125)
		(layer "B.Cu")
		(net 93)
	)
	(arc
		(start 195.337993 142.470835)
		(mid 195.41453 142.486059)
		(end 195.479415 142.529414)
		(width 0.125)
		(layer "B.Cu")
		(net 93)
	)
	(arc
		(start 195.421079 140.578921)
		(mid 195.377724 140.643806)
		(end 195.3625 140.720343)
		(width 0.125)
		(layer "B.Cu")
		(net 93)
	)
	(arc
		(start 195.491422 142.541421)
		(mid 195.556306 142.584776)
		(end 195.632842 142.600001)
		(width 0.125)
		(layer "B.Cu")
		(net 93)
	)
	(arc
		(start 195.057835 141.636584)
		(mid 195.01448 141.701469)
		(end 194.999256 141.778006)
		(width 0.125)
		(layer "B.Cu")
		(net 93)
	)
	(segment
		(start 201.701481 117.868519)
		(end 202.52 117.05)
		(width 0.1)
		(layer "F.Cu")
		(net 94)
	)
	(segment
		(start 201.701481 119.268101)
		(end 201.701481 117.868519)
		(width 0.1)
		(layer "F.Cu")
		(net 94)
	)
	(segment
		(start 202.70338 120.27)
		(end 201.701481 119.268101)
		(width 0.1)
		(layer "F.Cu")
		(net 94)
	)
	(segment
		(start 203.35 120.27)
		(end 202.70338 120.27)
		(width 0.1)
		(layer "F.Cu")
		(net 94)
	)
	(via
		(at 202.52 117.05)
		(size 0.35)
		(drill 0.15)
		(layers "F.Cu" "B.Cu")
		(remove_unused_layers yes)
		(keep_end_layers yes)
		(zone_layer_connections)
		(net 94)
	)
	(via
		(at 195.7 141.101)
		(size 0.35)
		(drill 0.15)
		(layers "F.Cu" "B.Cu")
		(remove_unused_layers yes)
		(keep_end_layers yes)
		(zone_layer_connections)
		(net 95)
	)
	(segment
		(start 195.991421 140.826421)
		(end 195.973578 140.808578)
		(width 0.125)
		(layer "B.Cu")
		(net 95)
	)
	(segment
		(start 196.05 141.206447)
		(end 196.05 140.967843)
		(width 0.125)
		(layer "B.Cu")
		(net 95)
	)
	(segment
		(start 195.685581 141.52)
		(end 195.736447 141.52)
		(width 0.125)
		(layer "B.Cu")
		(net 95)
	)
	(segment
		(start 195.735355 140.764645)
		(end 195.714644 140.785356)
		(width 0.125)
		(layer "B.Cu")
		(net 95)
	)
	(segment
		(start 195.68 142.1)
		(end 195.550001 142.100001)
		(width 0.125)
		(layer "B.Cu")
		(net 95)
	)
	(segment
		(start 195.550001 142.100001)
		(end 195.422146 142.227856)
		(width 0.125)
		(layer "B.Cu")
		(net 95)
	)
	(segment
		(start 195.38679 142.242501)
		(end 195.362533 142.2425)
		(width 0.125)
		(layer "B.Cu")
		(net 95)
	)
	(segment
		(start 195.7 140.820711)
		(end 195.7 141.101)
		(width 0.125)
		(layer "B.Cu")
		(net 95)
	)
	(segment
		(start 195.214256 142.01138)
		(end 195.214256 141.991325)
		(width 0.125)
		(layer "B.Cu")
		(net 95)
	)
	(segment
		(start 195.28748 141.814548)
		(end 195.508805 141.593223)
		(width 0.125)
		(layer "B.Cu")
		(net 95)
	)
	(segment
		(start 195.913224 141.446776)
		(end 195.976777 141.383223)
		(width 0.125)
		(layer "B.Cu")
		(net 95)
	)
	(segment
		(start 195.832157 140.75)
		(end 195.770711 140.75)
		(width 0.125)
		(layer "B.Cu")
		(net 95)
	)
	(segment
		(start 195.327178 142.227855)
		(end 195.287479 142.188156)
		(width 0.125)
		(layer "B.Cu")
		(net 95)
	)
	(arc
		(start 195.736447 141.52)
		(mid 195.832118 141.50097)
		(end 195.913224 141.446776)
		(width 0.125)
		(layer "B.Cu")
		(net 95)
	)
	(arc
		(start 195.422146 142.227856)
		(mid 195.405925 142.238695)
		(end 195.38679 142.242501)
		(width 0.125)
		(layer "B.Cu")
		(net 95)
	)
	(arc
		(start 195.327178 142.227855)
		(mid 195.343399 142.238694)
		(end 195.362533 142.2425)
		(width 0.125)
		(layer "B.Cu")
		(net 95)
	)
	(arc
		(start 195.685581 141.52)
		(mid 195.58991 141.53903)
		(end 195.508805 141.593223)
		(width 0.125)
		(layer "B.Cu")
		(net 95)
	)
	(arc
		(start 195.770711 140.75)
		(mid 195.751577 140.753806)
		(end 195.735355 140.764645)
		(width 0.125)
		(layer "B.Cu")
		(net 95)
	)
	(arc
		(start 196.05 140.967843)
		(mid 196.034776 140.891306)
		(end 195.991421 140.826421)
		(width 0.125)
		(layer "B.Cu")
		(net 95)
	)
	(arc
		(start 195.7 140.820711)
		(mid 195.703806 140.801577)
		(end 195.714644 140.785356)
		(width 0.125)
		(layer "B.Cu")
		(net 95)
	)
	(arc
		(start 195.832157 140.75)
		(mid 195.908693 140.765224)
		(end 195.973578 140.808578)
		(width 0.125)
		(layer "B.Cu")
		(net 95)
	)
	(arc
		(start 195.28748 141.814548)
		(mid 195.233287 141.895654)
		(end 195.214256 141.991325)
		(width 0.125)
		(layer "B.Cu")
		(net 95)
	)
	(arc
		(start 195.287479 142.188156)
		(mid 195.233286 142.10705)
		(end 195.214256 142.01138)
		(width 0.125)
		(layer "B.Cu")
		(net 95)
	)
	(arc
		(start 196.05 141.206447)
		(mid 196.03097 141.302118)
		(end 195.976777 141.383223)
		(width 0.125)
		(layer "B.Cu")
		(net 95)
	)
	(segment
		(start 176.576 149.434849)
		(end 176.576 148.776)
		(width 0.1)
		(layer "F.Cu")
		(net 96)
	)
	(segment
		(start 209.077 152.138)
		(end 209.077 151.227)
		(width 0.256)
		(layer "F.Cu")
		(net 96)
	)
	(segment
		(start 208.57 144.825)
		(end 209.2 144.825)
		(width 0.35)
		(layer "F.Cu")
		(net 96)
	)
	(segment
		(start 208.57 150.75)
		(end 208.57 148.75)
		(width 0.4)
		(layer "F.Cu")
		(net 96)
	)
	(segment
		(start 176.48096 149.529889)
		(end 176.576 149.434849)
		(width 0.1)
		(layer "F.Cu")
		(net 96)
	)
	(segment
		(start 208.545 152.67)
		(end 209.077 152.138)
		(width 0.256)
		(layer "F.Cu")
		(net 96)
	)
	(segment
		(start 176.576 148.776)
		(end 176.45 148.65)
		(width 0.1)
		(layer "F.Cu")
		(net 96)
	)
	(segment
		(start 208.57 148.75)
		(end 209.3385 148.75)
		(width 0.35)
		(layer "F.Cu")
		(net 96)
	)
	(segment
		(start 208.57 147.775)
		(end 209.3385 147.775)
		(width 0.35)
		(layer "F.Cu")
		(net 96)
	)
	(segment
		(start 209.077 151.227)
		(end 208.57 150.72)
		(width 0.256)
		(layer "F.Cu")
		(net 96)
	)
	(via
		(at 209.3385 147.775)
		(size 0.35)
		(drill 0.15)
		(layers "F.Cu" "B.Cu")
		(remove_unused_layers yes)
		(keep_end_layers yes)
		(zone_layer_connections)
		(net 96)
	)
	(via
		(at 186.3 141.95)
		(size 0.35)
		(drill 0.15)
		(layers "F.Cu" "B.Cu")
		(remove_unused_layers yes)
		(keep_end_layers yes)
		(free yes)
		(zone_layer_connections)
		(net 96)
	)
	(via
		(at 209.2 144.825)
		(size 0.35)
		(drill 0.15)
		(layers "F.Cu" "B.Cu")
		(remove_unused_layers yes)
		(keep_end_layers yes)
		(zone_layer_connections)
		(net 96)
	)
	(via
		(at 186.3 143.3)
		(size 0.35)
		(drill 0.15)
		(layers "F.Cu" "B.Cu")
		(remove_unused_layers yes)
		(keep_end_layers yes)
		(free yes)
		(zone_layer_connections)
		(net 96)
	)
	(via
		(at 182.05 145.15)
		(size 0.35)
		(drill 0.15)
		(layers "F.Cu" "B.Cu")
		(remove_unused_layers yes)
		(keep_end_layers yes)
		(free yes)
		(zone_layer_connections)
		(net 96)
	)
	(via
		(at 176.48096 149.529889)
		(size 0.35)
		(drill 0.15)
		(layers "F.Cu" "B.Cu")
		(remove_unused_layers yes)
		(keep_end_layers yes)
		(zone_layer_connections)
		(net 96)
	)
	(via
		(at 209.3385 148.75)
		(size 0.35)
		(drill 0.15)
		(layers "F.Cu" "B.Cu")
		(remove_unused_layers yes)
		(keep_end_layers yes)
		(zone_layer_connections)
		(net 96)
	)
	(via
		(at 186.3 142.4)
		(size 0.35)
		(drill 0.15)
		(layers "F.Cu" "B.Cu")
		(remove_unused_layers yes)
		(keep_end_layers yes)
		(free yes)
		(zone_layer_connections)
		(net 96)
	)
	(via
		(at 186.3 142.85)
		(size 0.35)
		(drill 0.15)
		(layers "F.Cu" "B.Cu")
		(remove_unused_layers yes)
		(keep_end_layers yes)
		(free yes)
		(zone_layer_connections)
		(net 96)
	)
	(segment
		(start 184.516421 144.741421)
		(end 184.291421 144.741421)
		(width 0.1)
		(layer "B.Cu")
		(net 96)
	)
	(segment
		(start 184.819975 145.044975)
		(end 184.516421 144.741421)
		(width 0.1)
		(layer "B.Cu")
		(net 96)
	)
	(segment
		(start 183.81 145.222842)
		(end 183.81 145.374006)
		(width 0.1)
		(layer "B.Cu")
		(net 96)
	)
	(segment
		(start 183.358006 145.826)
		(end 182.726 145.826)
		(width 0.1)
		(layer "B.Cu")
		(net 96)
	)
	(segment
		(start 182.726 145.826)
		(end 182.05 145.15)
		(width 0.1)
		(layer "B.Cu")
		(net 96)
	)
	(segment
		(start 184.291421 144.741421)
		(end 183.81 145.222842)
		(width 0.1)
		(layer "B.Cu")
		(net 96)
	)
	(segment
		(start 183.81 145.374006)
		(end 183.358006 145.826)
		(width 0.1)
		(layer "B.Cu")
		(net 96)
	)
	(segment
		(start 209.025 144.825)
		(end 208.70831 145.14169)
		(width 0.35)
		(layer "In6.Cu")
		(net 96)
	)
	(segment
		(start 201.43 147.47)
		(end 201.8 147.1)
		(width 0.4)
		(layer "In6.Cu")
		(net 96)
	)
	(segment
		(start 205.9615 149.2615)
		(end 208.22181 149.2615)
		(width 0.4)
		(layer "In6.Cu")
		(net 96)
	)
	(segment
		(start 204.5 145.5)
		(end 205 146)
		(width 0.4)
		(layer "In6.Cu")
		(net 96)
	)
	(segment
		(start 185.575 141.95)
		(end 185.575 142.85)
		(width 0.4)
		(layer "In6.Cu")
		(net 96)
	)
	(segment
		(start 185.3 146.696752)
		(end 185.633248 147.03)
		(width 0.4)
		(layer "In6.Cu")
		(net 96)
	)
	(segment
		(start 191.615026 145.48)
		(end 196.32 145.48)
		(width 0.4)
		(layer "In6.Cu")
		(net 96)
	)
	(segment
		(start 205 146)
		(end 205 148.3)
		(width 0.4)
		(layer "In6.Cu")
		(net 96)
	)
	(segment
		(start 202 145.5)
		(end 204.5 145.5)
		(width 0.4)
		(layer "In6.Cu")
		(net 96)
	)
	(segment
		(start 186.3 142.85)
		(end 185.575 142.85)
		(width 0.4)
		(layer "In6.Cu")
		(net 96)
	)
	(segment
		(start 200.2 147.47)
		(end 201.43 147.47)
		(width 0.4)
		(layer "In6.Cu")
		(net 96)
	)
	(segment
		(start 185.575 144.300732)
		(end 185.3 144.575732)
		(width 0.4)
		(layer "In6.Cu")
		(net 96)
	)
	(segment
		(start 196.32 145.48)
		(end 196.47 145.33)
		(width 0.4)
		(layer "In6.Cu")
		(net 96)
	)
	(segment
		(start 209.2 144.825)
		(end 209.025 144.825)
		(width 0.35)
		(layer "In6.Cu")
		(net 96)
	)
	(segment
		(start 186.3 143.3)
		(end 186.3 141.95)
		(width 0.4)
		(layer "In6.Cu")
		(net 96)
	)
	(segment
		(start 198.06 145.33)
		(end 200.2 147.47)
		(width 0.4)
		(layer "In6.Cu")
		(net 96)
	)
	(segment
		(start 208.73331 148.75)
		(end 208.70831 148.775)
		(width 0.4)
		(layer "In6.Cu")
		(net 96)
	)
	(segment
		(start 185.575 142.85)
		(end 185.575 144.300732)
		(width 0.4)
		(layer "In6.Cu")
		(net 96)
	)
	(segment
		(start 191.297999 146.274531)
		(end 191.297999 145.797027)
		(width 0.4)
		(layer "In6.Cu")
		(net 96)
	)
	(segment
		(start 208.75831 147.775)
		(end 208.70831 147.825)
		(width 0.4)
		(layer "In6.Cu")
		(net 96)
	)
	(segment
		(start 185.633248 147.03)
		(end 190.54253 147.03)
		(width 0.4)
		(layer "In6.Cu")
		(net 96)
	)
	(segment
		(start 205 148.3)
		(end 205.9615 149.2615)
		(width 0.4)
		(layer "In6.Cu")
		(net 96)
	)
	(segment
		(start 196.47 145.33)
		(end 198.06 145.33)
		(width 0.4)
		(layer "In6.Cu")
		(net 96)
	)
	(segment
		(start 186.3 141.95)
		(end 185.575 141.95)
		(width 0.4)
		(layer "In6.Cu")
		(net 96)
	)
	(segment
		(start 185.3 144.575732)
		(end 185.3 146.696752)
		(width 0.4)
		(layer "In6.Cu")
		(net 96)
	)
	(segment
		(start 201.8 147.1)
		(end 201.8 145.7)
		(width 0.4)
		(layer "In6.Cu")
		(net 96)
	)
	(segment
		(start 208.70831 145.14169)
		(end 208.70831 147.825)
		(width 0.35)
		(layer "In6.Cu")
		(net 96)
	)
	(segment
		(start 191.297999 145.797027)
		(end 191.615026 145.48)
		(width 0.4)
		(layer "In6.Cu")
		(net 96)
	)
	(segment
		(start 201.8 145.7)
		(end 202 145.5)
		(width 0.4)
		(layer "In6.Cu")
		(net 96)
	)
	(segment
		(start 208.70831 147.825)
		(end 208.70831 148.775)
		(width 0.4)
		(layer "In6.Cu")
		(net 96)
	)
	(segment
		(start 209.3385 148.75)
		(end 208.73331 148.75)
		(width 0.35)
		(layer "In6.Cu")
		(net 96)
	)
	(segment
		(start 209.3385 147.775)
		(end 208.75831 147.775)
		(width 0.35)
		(layer "In6.Cu")
		(net 96)
	)
	(segment
		(start 208.22181 149.2615)
		(end 208.70831 148.775)
		(width 0.4)
		(layer "In6.Cu")
		(net 96)
	)
	(segment
		(start 190.54253 147.03)
		(end 191.297999 146.274531)
		(width 0.4)
		(layer "In6.Cu")
		(net 96)
	)
	(segment
		(start 182.05 145.15)
		(end 181.974 145.074)
		(width 0.1)
		(layer "In7.Cu")
		(net 96)
	)
	(segment
		(start 178.95 147.1)
		(end 178.95 148.84944)
		(width 0.1)
		(layer "In7.Cu")
		(net 96)
	)
	(segment
		(start 176.799128 149.848057)
		(end 176.48096 149.529889)
		(width 0.1)
		(layer "In7.Cu")
		(net 96)
	)
	(segment
		(start 177.664 149.286)
		(end 177.101943 149.848057)
		(width 0.1)
		(layer "In7.Cu")
		(net 96)
	)
	(segment
		(start 180.976 145.074)
		(end 178.95 147.1)
		(width 0.1)
		(layer "In7.Cu")
		(net 96)
	)
	(segment
		(start 177.101943 149.848057)
		(end 176.799128 149.848057)
		(width 0.1)
		(layer "In7.Cu")
		(net 96)
	)
	(segment
		(start 178.95 148.84944)
		(end 178.51344 149.286)
		(width 0.1)
		(layer "In7.Cu")
		(net 96)
	)
	(segment
		(start 181.974 145.074)
		(end 180.976 145.074)
		(width 0.1)
		(layer "In7.Cu")
		(net 96)
	)
	(segment
		(start 178.51344 149.286)
		(end 177.664 149.286)
		(width 0.1)
		(layer "In7.Cu")
		(net 96)
	)
	(segment
		(start 197.1963 147.37)
		(end 197.0163 147.55)
		(width 0.1)
		(layer "F.Cu")
		(net 97)
	)
	(segment
		(start 197.0163 147.55)
		(end 196.64 147.55)
		(width 0.1)
		(layer "F.Cu")
		(net 97)
	)
	(via
		(at 197.1963 147.37)
		(size 0.35)
		(drill 0.15)
		(layers "F.Cu" "B.Cu")
		(remove_unused_layers yes)
		(keep_end_layers yes)
		(zone_layer_connections)
		(net 97)
	)
	(via
		(at 198.486195 153.423805)
		(size 0.35)
		(drill 0.15)
		(layers "F.Cu" "B.Cu")
		(remove_unused_layers yes)
		(keep_end_layers yes)
		(zone_layer_connections)
		(net 97)
	)
	(segment
		(start 198.922 151.461)
		(end 198.922 152.988)
		(width 0.15)
		(layer "B.Cu")
		(net 97)
	)
	(segment
		(start 198.922 152.988)
		(end 198.486195 153.423805)
		(width 0.15)
		(layer "B.Cu")
		(net 97)
	)
	(segment
		(start 191.31 154.31)
		(end 197.71 154.31)
		(width 0.1)
		(layer "In9.Cu")
		(net 97)
	)
	(segment
		(start 195.949078 148.617222)
		(end 190.866433 148.617222)
		(width 0.1)
		(layer "In9.Cu")
		(net 97)
	)
	(segment
		(start 190.866433 148.617222)
		(end 190.67 148.813655)
		(width 0.1)
		(layer "In9.Cu")
		(net 97)
	)
	(segment
		(start 198.486195 153.533805)
		(end 198.486195 153.423805)
		(width 0.1)
		(layer "In9.Cu")
		(net 97)
	)
	(segment
		(start 197.1963 147.37)
		(end 195.949078 148.617222)
		(width 0.1)
		(layer "In9.Cu")
		(net 97)
	)
	(segment
		(start 190.67 148.813655)
		(end 190.67 153.67)
		(width 0.1)
		(layer "In9.Cu")
		(net 97)
	)
	(segment
		(start 190.67 153.67)
		(end 191.31 154.31)
		(width 0.1)
		(layer "In9.Cu")
		(net 97)
	)
	(segment
		(start 197.71 154.31)
		(end 198.486195 153.533805)
		(width 0.1)
		(layer "In9.Cu")
		(net 97)
	)
	(segment
		(start 190.143955 119.126398)
		(end 190.398398 119.126398)
		(width 0.256)
		(layer "F.Cu")
		(net 98)
	)
	(segment
		(start 190.538589 119.229411)
		(end 190.52 119.248)
		(width 0.15)
		(layer "F.Cu")
		(net 98)
	)
	(segment
		(start 192.380589 119.229411)
		(end 190.538589 119.229411)
		(width 0.15)
		(layer "F.Cu")
		(net 98)
	)
	(segment
		(start 190.398398 119.126398)
		(end 190.52 119.248)
		(width 0.256)
		(layer "F.Cu")
		(net 98)
	)
	(via
		(at 190.143955 119.126398)
		(size 0.35)
		(drill 0.15)
		(layers "F.Cu" "B.Cu")
		(remove_unused_layers yes)
		(keep_end_layers yes)
		(zone_layer_connections)
		(net 98)
	)
	(segment
		(start 190.143955 119.126398)
		(end 190.522 118.748353)
		(width 0.15)
		(layer "B.Cu")
		(net 98)
	)
	(segment
		(start 190.522 118.748353)
		(end 190.522 117.461)
		(width 0.15)
		(layer "B.Cu")
		(net 98)
	)
	(via
		(at 205.7245 153.2555)
		(size 0.35)
		(drill 0.15)
		(layers "F.Cu" "B.Cu")
		(remove_unused_layers yes)
		(keep_end_layers yes)
		(zone_layer_connections)
		(net 99)
	)
	(via
		(at 202.399 150.001)
		(size 0.35)
		(drill 0.15)
		(layers "F.Cu" "B.Cu")
		(remove_unused_layers yes)
		(keep_end_layers yes)
		(zone_layer_connections)
		(net 99)
	)
	(segment
		(start 206.422 151.776)
		(end 206.422 152.769422)
		(width 0.11)
		(layer "B.Cu")
		(net 99)
	)
	(segment
		(start 205.85175 153.12825)
		(end 205.7245 153.2555)
		(width 0.11)
		(layer "B.Cu")
		(net 99)
	)
	(segment
		(start 206.522 151.676)
		(end 206.422 151.776)
		(width 0.11)
		(layer "B.Cu")
		(net 99)
	)
	(segment
		(start 206.522 151.461)
		(end 206.522 151.676)
		(width 0.11)
		(layer "B.Cu")
		(net 99)
	)
	(segment
		(start 206.063172 153.12825)
		(end 205.85175 153.12825)
		(width 0.11)
		(layer "B.Cu")
		(net 99)
	)
	(segment
		(start 206.422 152.769422)
		(end 206.063172 153.12825)
		(width 0.11)
		(layer "B.Cu")
		(net 99)
	)
	(segment
		(start 204.365 151.290648)
		(end 204.241951 151.413697)
		(width 0.09)
		(layer "In2.Cu")
		(net 99)
	)
	(segment
		(start 205.621541 153.152541)
		(end 205.7245 153.2555)
		(width 0.09)
		(layer "In2.Cu")
		(net 99)
	)
	(segment
		(start 202.411317 150.013317)
		(end 202.410982 150.013652)
		(width 0.09)
		(layer "In2.Cu")
		(net 99)
	)
	(segment
		(start 205.29571 151.949938)
		(end 204.990312 152.255336)
		(width 0.09)
		(layer "In2.Cu")
		(net 99)
	)
	(segment
		(start 204.759091 151.885261)
		(end 204.990063 151.654289)
		(width 0.09)
		(layer "In2.Cu")
		(net 99)
	)
	(segment
		(start 203.14965 151.151872)
		(end 203.21 151.151872)
		(width 0.09)
		(layer "In2.Cu")
		(net 99)
	)
	(segment
		(start 202.410982 150.013652)
		(end 202.410982 150.32834)
		(width 0.09)
		(layer "In2.Cu")
		(net 99)
	)
	(segment
		(start 204.365 151.250773)
		(end 204.365 151.290648)
		(width 0.09)
		(layer "In2.Cu")
		(net 99)
	)
	(segment
		(start 203.802159 150.646511)
		(end 203.897824 150.742176)
		(width 0.09)
		(layer "In2.Cu")
		(net 99)
	)
	(segment
		(start 204.165 151.599473)
		(end 204.165 151.645259)
		(width 0.09)
		(layer "In2.Cu")
		(net 99)
	)
	(segment
		(start 203.64965 150.617221)
		(end 203.731448 150.617221)
		(width 0.09)
		(layer "In2.Cu")
		(net 99)
	)
	(segment
		(start 204.180666 151.025018)
		(end 204.335711 151.180063)
		(width 0.09)
		(layer "In2.Cu")
		(net 99)
	)
	(segment
		(start 204.969982 152.934334)
		(end 205.108419 153.072771)
		(width 0.09)
		(layer "In2.Cu")
		(net 99)
	)
	(segment
		(start 203.524825 150.837047)
		(end 203.524825 150.742046)
		(width 0.09)
		(layer "In2.Cu")
		(net 99)
	)
	(segment
		(start 202.484783 150.50651)
		(end 202.535493 150.55722)
		(width 0.09)
		(layer "In2.Cu")
		(net 99)
	)
	(segment
		(start 202.411317 150.013317)
		(end 202.399 150.001)
		(width 0.11)
		(layer "In2.Cu")
		(net 99)
	)
	(segment
		(start 203.897824 150.954308)
		(end 203.968534 151.025018)
		(width 0.09)
		(layer "In2.Cu")
		(net 99)
	)
	(segment
		(start 204.466342 151.955)
		(end 204.590726 151.955)
		(width 0.09)
		(layer "In2.Cu")
		(net 99)
	)
	(segment
		(start 205.325 151.770773)
		(end 205.325 151.879227)
		(width 0.09)
		(layer "In2.Cu")
		(net 99)
	)
	(segment
		(start 205.249938 151.65429)
		(end 205.295711 151.700063)
		(width 0.09)
		(layer "In2.Cu")
		(net 99)
	)
	(segment
		(start 202.680349 150.617221)
		(end 202.71 150.617221)
		(width 0.09)
		(layer "In2.Cu")
		(net 99)
	)
	(segment
		(start 205.060773 151.625)
		(end 205.179227 151.625)
		(width 0.09)
		(layer "In2.Cu")
		(net 99)
	)
	(segment
		(start 205.230288 153.123251)
		(end 205.55083 153.123251)
		(width 0.09)
		(layer "In2.Cu")
		(net 99)
	)
	(segment
		(start 204.925 152.413014)
		(end 204.925 152.825738)
		(width 0.09)
		(layer "In2.Cu")
		(net 99)
	)
	(segment
		(start 203.897823 150.848243)
		(end 203.897824 150.848242)
		(width 0.09)
		(layer "In2.Cu")
		(net 99)
	)
	(segment
		(start 202.834825 150.742046)
		(end 202.834825 150.837047)
		(width 0.09)
		(layer "In2.Cu")
		(net 99)
	)
	(segment
		(start 204.231534 151.805886)
		(end 204.320053 151.894405)
		(width 0.09)
		(layer "In2.Cu")
		(net 99)
	)
	(arc
		(start 202.535493 150.55722)
		(mid 202.601954 150.601627)
		(end 202.680349 150.617221)
		(width 0.09)
		(layer "In2.Cu")
		(net 99)
	)
	(arc
		(start 202.484783 150.50651)
		(mid 202.430163 150.424765)
		(end 202.410982 150.32834)
		(width 0.09)
		(layer "In2.Cu")
		(net 99)
	)
	(arc
		(start 204.320053 151.894405)
		(mid 204.387171 151.939252)
		(end 204.466342 151.955)
		(width 0.09)
		(layer "In2.Cu")
		(net 99)
	)
	(arc
		(start 205.325 151.770773)
		(mid 205.317388 151.732505)
		(end 205.295711 151.700063)
		(width 0.09)
		(layer "In2.Cu")
		(net 99)
	)
	(arc
		(start 205.108419 153.072771)
		(mid 205.164333 153.110132)
		(end 205.230288 153.123251)
		(width 0.09)
		(layer "In2.Cu")
		(net 99)
	)
	(arc
		(start 205.249938 151.65429)
		(mid 205.217496 151.632612)
		(end 205.179227 151.625)
		(width 0.09)
		(layer "In2.Cu")
		(net 99)
	)
	(arc
		(start 204.365 151.250773)
		(mid 204.357388 151.212505)
		(end 204.335711 151.180063)
		(width 0.09)
		(layer "In2.Cu")
		(net 99)
	)
	(arc
		(start 203.524825 150.742046)
		(mid 203.561385 150.653781)
		(end 203.64965 150.617221)
		(width 0.09)
		(layer "In2.Cu")
		(net 99)
	)
	(arc
		(start 204.925 152.413014)
		(mid 204.941974 152.327679)
		(end 204.990312 152.255336)
		(width 0.09)
		(layer "In2.Cu")
		(net 99)
	)
	(arc
		(start 203.21 151.151872)
		(mid 203.432615 151.059662)
		(end 203.524825 150.837047)
		(width 0.09)
		(layer "In2.Cu")
		(net 99)
	)
	(arc
		(start 203.897824 150.742176)
		(mid 203.919791 150.79521)
		(end 203.897823 150.848243)
		(width 0.09)
		(layer "In2.Cu")
		(net 99)
	)
	(arc
		(start 204.0746 151.025018)
		(mid 204.127633 151.003051)
		(end 204.180666 151.025018)
		(width 0.09)
		(layer "In2.Cu")
		(net 99)
	)
	(arc
		(start 204.759091 151.885261)
		(mid 204.681844 151.936875)
		(end 204.590726 151.955)
		(width 0.09)
		(layer "In2.Cu")
		(net 99)
	)
	(arc
		(start 203.897824 150.848242)
		(mid 203.875857 150.901275)
		(end 203.897824 150.954308)
		(width 0.09)
		(layer "In2.Cu")
		(net 99)
	)
	(arc
		(start 203.802159 150.646511)
		(mid 203.769717 150.624833)
		(end 203.731448 150.617221)
		(width 0.09)
		(layer "In2.Cu")
		(net 99)
	)
	(arc
		(start 205.55083 153.123251)
		(mid 205.589099 153.130863)
		(end 205.621541 153.152541)
		(width 0.09)
		(layer "In2.Cu")
		(net 99)
	)
	(arc
		(start 204.969982 152.934334)
		(mid 204.93669 152.88451)
		(end 204.925 152.825738)
		(width 0.09)
		(layer "In2.Cu")
		(net 99)
	)
	(arc
		(start 204.990063 151.654289)
		(mid 205.022505 151.632612)
		(end 205.060773 151.625)
		(width 0.09)
		(layer "In2.Cu")
		(net 99)
	)
	(arc
		(start 203.968534 151.025018)
		(mid 204.021567 151.046985)
		(end 204.0746 151.025018)
		(width 0.09)
		(layer "In2.Cu")
		(net 99)
	)
	(arc
		(start 205.325 151.879227)
		(mid 205.317388 151.917496)
		(end 205.29571 151.949938)
		(width 0.09)
		(layer "In2.Cu")
		(net 99)
	)
	(arc
		(start 204.231534 151.805886)
		(mid 204.182292 151.73219)
		(end 204.165 151.645259)
		(width 0.09)
		(layer "In2.Cu")
		(net 99)
	)
	(arc
		(start 204.165 151.599473)
		(mid 204.184999 151.498932)
		(end 204.241951 151.413697)
		(width 0.09)
		(layer "In2.Cu")
		(net 99)
	)
	(arc
		(start 202.834825 150.837047)
		(mid 202.927035 151.059662)
		(end 203.14965 151.151872)
		(width 0.09)
		(layer "In2.Cu")
		(net 99)
	)
	(arc
		(start 202.71 150.617221)
		(mid 202.798265 150.653781)
		(end 202.834825 150.742046)
		(width 0.09)
		(layer "In2.Cu")
		(net 99)
	)
	(segment
		(start 205.299 124.3)
		(end 205.299 123.299)
		(width 0.1)
		(layer "F.Cu")
		(net 100)
	)
	(segment
		(start 180.72 145.3375)
		(end 180.65 145.3375)
		(width 0.15)
		(layer "F.Cu")
		(net 100)
	)
	(segment
		(start 204.35 122.35)
		(end 204.35 121.23)
		(width 0.1)
		(layer "F.Cu")
		(net 100)
	)
	(segment
		(start 180.65 145.3375)
		(end 179.9 144.5875)
		(width 0.15)
		(layer "F.Cu")
		(net 100)
	)
	(segment
		(start 177.450001 148.65)
		(end 177.45 148.649999)
		(width 0.15)
		(layer "F.Cu")
		(net 100)
	)
	(segment
		(start 179.9 144.5875)
		(end 179.9 144.0375)
		(width 0.15)
		(layer "F.Cu")
		(net 100)
	)
	(segment
		(start 205.299 123.299)
		(end 204.35 122.35)
		(width 0.1)
		(layer "F.Cu")
		(net 100)
	)
	(segment
		(start 178.25 148.65)
		(end 177.450001 148.65)
		(width 0.15)
		(layer "F.Cu")
		(net 100)
	)
	(via
		(at 205.299 124.3)
		(size 0.35)
		(drill 0.15)
		(layers "F.Cu" "B.Cu")
		(remove_unused_layers yes)
		(keep_end_layers yes)
		(zone_layer_connections)
		(net 100)
	)
	(via
		(at 183.358904 147.831531)
		(size 0.35)
		(drill 0.15)
		(layers "F.Cu" "B.Cu")
		(remove_unused_layers yes)
		(keep_end_layers yes)
		(zone_layer_connections)
		(net 100)
	)
	(via
		(at 178.25 148.65)
		(size 0.35)
		(drill 0.15)
		(layers "F.Cu" "B.Cu")
		(remove_unused_layers yes)
		(keep_end_layers yes)
		(zone_layer_connections)
		(net 100)
	)
	(via
		(at 181 145.55)
		(size 0.35)
		(drill 0.15)
		(layers "F.Cu" "B.Cu")
		(remove_unused_layers yes)
		(keep_end_layers yes)
		(zone_layer_connections)
		(net 100)
	)
	(segment
		(start 183.358904 147.795217)
		(end 183.358904 147.831531)
		(width 0.15)
		(layer "B.Cu")
		(net 100)
	)
	(segment
		(start 203.25 124.04519)
		(end 203.25 124.4)
		(width 0.1)
		(layer "B.Cu")
		(net 100)
	)
	(segment
		(start 202.80481 123.6)
		(end 203.25 124.04519)
		(width 0.1)
		(layer "B.Cu")
		(net 100)
	)
	(segment
		(start 204.899 124.7)
		(end 204.899 125.199)
		(width 0.1)
		(layer "B.Cu")
		(net 100)
	)
	(segment
		(start 182.763687 147.2)
		(end 183.358904 147.795217)
		(width 0.15)
		(layer "B.Cu")
		(net 100)
	)
	(segment
		(start 181 145.55)
		(end 181 145.85)
		(width 0.15)
		(layer "B.Cu")
		(net 100)
	)
	(segment
		(start 182.35 147.2)
		(end 182.763687 147.2)
		(width 0.15)
		(layer "B.Cu")
		(net 100)
	)
	(segment
		(start 203.25 124.4)
		(end 203.55 124.7)
		(width 0.1)
		(layer "B.Cu")
		(net 100)
	)
	(segment
		(start 201.98 123.6)
		(end 202.80481 123.6)
		(width 0.1)
		(layer "B.Cu")
		(net 100)
	)
	(segment
		(start 204.899 125.199)
		(end 204.9 125.2)
		(width 0.1)
		(layer "B.Cu")
		(net 100)
	)
	(segment
		(start 181 145.85)
		(end 182.35 147.2)
		(width 0.15)
		(layer "B.Cu")
		(net 100)
	)
	(segment
		(start 204.899 124.7)
		(end 205.299 124.3)
		(width 0.1)
		(layer "B.Cu")
		(net 100)
	)
	(segment
		(start 203.55 124.7)
		(end 204.899 124.7)
		(width 0.1)
		(layer "B.Cu")
		(net 100)
	)
	(segment
		(start 182.04 148.32)
		(end 182.870435 148.32)
		(width 0.1)
		(layer "In7.Cu")
		(net 100)
	)
	(segment
		(start 177.39 148.65)
		(end 176.91 149.13)
		(width 0.1)
		(layer "In7.Cu")
		(net 100)
	)
	(segment
		(start 182.870435 148.32)
		(end 183.358904 147.831531)
		(width 0.1)
		(layer "In7.Cu")
		(net 100)
	)
	(segment
		(start 176.29 149.13)
		(end 175.99 149.43)
		(width 0.1)
		(layer "In7.Cu")
		(net 100)
	)
	(segment
		(start 180.07 150.29)
		(end 182.04 148.32)
		(width 0.1)
		(layer "In7.Cu")
		(net 100)
	)
	(segment
		(start 175.99 149.43)
		(end 175.99 149.97)
		(width 0.1)
		(layer "In7.Cu")
		(net 100)
	)
	(segment
		(start 176.91 149.13)
		(end 176.29 149.13)
		(width 0.1)
		(layer "In7.Cu")
		(net 100)
	)
	(segment
		(start 176.31 150.29)
		(end 180.07 150.29)
		(width 0.1)
		(layer "In7.Cu")
		(net 100)
	)
	(segment
		(start 178.25 148.65)
		(end 177.39 148.65)
		(width 0.1)
		(layer "In7.Cu")
		(net 100)
	)
	(segment
		(start 175.99 149.97)
		(end 176.31 150.29)
		(width 0.1)
		(layer "In7.Cu")
		(net 100)
	)
	(segment
		(start 189.65 136.7)
		(end 192 134.35)
		(width 0.1)
		(layer "In11.Cu")
		(net 100)
	)
	(segment
		(start 198.63462 130.625)
		(end 199.75962 129.5)
		(width 0.1)
		(layer "In11.Cu")
		(net 100)
	)
	(segment
		(start 181 145.55)
		(end 181 144.08)
		(width 0.1)
		(layer "In11.Cu")
		(net 100)
	)
	(segment
		(start 185.925 139.675)
		(end 188.9 136.7)
		(width 0.1)
		(layer "In11.Cu")
		(net 100)
	)
	(segment
		(start 192.824 133.826)
		(end 193.95 132.7)
		(width 0.1)
		(layer "In11.Cu")
		(net 100)
	)
	(segment
		(start 192.824 134.03462)
		(end 192.824 133.826)
		(width 0.1)
		(layer "In11.Cu")
		(net 100)
	)
	(segment
		(start 199.75962 129.5)
		(end 201.35962 129.5)
		(width 0.1)
		(layer "In11.Cu")
		(net 100)
	)
	(segment
		(start 195.375 131.36638)
		(end 195.71538 131.026)
		(width 0.1)
		(layer "In11.Cu")
		(net 100)
	)
	(segment
		(start 195.375 131.63562)
		(end 195.375 131.36638)
		(width 0.1)
		(layer "In11.Cu")
		(net 100)
	)
	(segment
		(start 195.71538 131.026)
		(end 197.44462 131.026)
		(width 0.1)
		(layer "In11.Cu")
		(net 100)
	)
	(segment
		(start 203.024 125.5)
		(end 203.3 125.224)
		(width 0.1)
		(layer "In11.Cu")
		(net 100)
	)
	(segment
		(start 197.44462 131.026)
		(end 197.84562 130.625)
		(width 0.1)
		(layer "In11.Cu")
		(net 100)
	)
	(segment
		(start 203.3 124.97019)
		(end 203.57019 124.7)
		(width 0.1)
		(layer "In11.Cu")
		(net 100)
	)
	(segment
		(start 203.3 125.224)
		(end 203.3 124.97019)
		(width 0.1)
		(layer "In11.Cu")
		(net 100)
	)
	(segment
		(start 203.57019 124.7)
		(end 204.899 124.7)
		(width 0.1)
		(layer "In11.Cu")
		(net 100)
	)
	(segment
		(start 202.77069 125.5)
		(end 203.024 125.5)
		(width 0.1)
		(layer "In11.Cu")
		(net 100)
	)
	(segment
		(start 181.81 143.63)
		(end 182.07 143.89)
		(width 0.1)
		(layer "In11.Cu")
		(net 100)
	)
	(segment
		(start 194.55 132.30862)
		(end 194.55 132.19038)
		(width 0.1)
		(layer "In11.Cu")
		(net 100)
	)
	(segment
		(start 195.16062 131.85)
		(end 195.375 131.63562)
		(width 0.1)
		(layer "In11.Cu")
		(net 100)
	)
	(segment
		(start 183.885 143.89)
		(end 184.665 143.11)
		(width 0.1)
		(layer "In11.Cu")
		(net 100)
	)
	(segment
		(start 204.899 124.7)
		(end 205.299 124.3)
		(width 0.1)
		(layer "In11.Cu")
		(net 100)
	)
	(segment
		(start 192 134.35)
		(end 192.50862 134.35)
		(width 0.1)
		(layer "In11.Cu")
		(net 100)
	)
	(segment
		(start 194.15862 132.7)
		(end 194.55 132.30862)
		(width 0.1)
		(layer "In11.Cu")
		(net 100)
	)
	(segment
		(start 181 144.08)
		(end 181.45 143.63)
		(width 0.1)
		(layer "In11.Cu")
		(net 100)
	)
	(segment
		(start 185.45 143.11)
		(end 185.925 142.635)
		(width 0.1)
		(layer "In11.Cu")
		(net 100)
	)
	(segment
		(start 194.55 132.19038)
		(end 194.89038 131.85)
		(width 0.1)
		(layer "In11.Cu")
		(net 100)
	)
	(segment
		(start 182.07 143.89)
		(end 183.885 143.89)
		(width 0.1)
		(layer "In11.Cu")
		(net 100)
	)
	(segment
		(start 201.35962 129.5)
		(end 202.5 128.35962)
		(width 0.1)
		(layer "In11.Cu")
		(net 100)
	)
	(segment
		(start 194.89038 131.85)
		(end 195.16062 131.85)
		(width 0.1)
		(layer "In11.Cu")
		(net 100)
	)
	(segment
		(start 188.9 136.7)
		(end 189.65 136.7)
		(width 0.1)
		(layer "In11.Cu")
		(net 100)
	)
	(segment
		(start 184.665 143.11)
		(end 185.45 143.11)
		(width 0.1)
		(layer "In11.Cu")
		(net 100)
	)
	(segment
		(start 193.95 132.7)
		(end 194.15862 132.7)
		(width 0.1)
		(layer "In11.Cu")
		(net 100)
	)
	(segment
		(start 197.84562 130.625)
		(end 198.63462 130.625)
		(width 0.1)
		(layer "In11.Cu")
		(net 100)
	)
	(segment
		(start 202.5 128.35962)
		(end 202.5 125.77069)
		(width 0.1)
		(layer "In11.Cu")
		(net 100)
	)
	(segment
		(start 192.50862 134.35)
		(end 192.824 134.03462)
		(width 0.1)
		(layer "In11.Cu")
		(net 100)
	)
	(segment
		(start 202.5 125.77069)
		(end 202.77069 125.5)
		(width 0.1)
		(layer "In11.Cu")
		(net 100)
	)
	(segment
		(start 185.925 142.635)
		(end 185.925 139.675)
		(width 0.1)
		(layer "In11.Cu")
		(net 100)
	)
	(segment
		(start 181.45 143.63)
		(end 181.81 143.63)
		(width 0.1)
		(layer "In11.Cu")
		(net 100)
	)
	(segment
		(start 204.35 120.27)
		(end 203.710283 119.630283)
		(width 0.1)
		(layer "F.Cu")
		(net 101)
	)
	(segment
		(start 203.18738 119.630283)
		(end 202.411512 118.854415)
		(width 0.1)
		(layer "F.Cu")
		(net 101)
	)
	(segment
		(start 202.411512 118.854415)
		(end 202.411512 118.817095)
		(width 0.1)
		(layer "F.Cu")
		(net 101)
	)
	(segment
		(start 203.710283 119.630283)
		(end 203.18738 119.630283)
		(width 0.1)
		(layer "F.Cu")
		(net 101)
	)
	(via
		(at 202.411512 118.817095)
		(size 0.35)
		(drill 0.15)
		(layers "F.Cu" "B.Cu")
		(remove_unused_layers yes)
		(keep_end_layers yes)
		(zone_layer_connections)
		(net 101)
	)
	(segment
		(start 202.645 119.654)
		(end 202.52 119.779)
		(width 0.15)
		(layer "B.Cu")
		(net 101)
	)
	(segment
		(start 202.52 119.779)
		(end 202.52 120.171)
		(width 0.15)
		(layer "B.Cu")
		(net 101)
	)
	(segment
		(start 202.645 119.050583)
		(end 202.645 119.654)
		(width 0.15)
		(layer "B.Cu")
		(net 101)
	)
	(segment
		(start 202.411512 118.817095)
		(end 202.645 119.050583)
		(width 0.15)
		(layer "B.Cu")
		(net 101)
	)
	(via
		(at 201.305 139.51)
		(size 0.35)
		(drill 0.15)
		(layers "F.Cu" "B.Cu")
		(remove_unused_layers yes)
		(keep_end_layers yes)
		(zone_layer_connections)
		(net 102)
	)
	(via
		(at 206.572 154.9)
		(size 0.35)
		(drill 0.15)
		(layers "F.Cu" "B.Cu")
		(remove_unused_layers yes)
		(keep_end_layers yes)
		(zone_layer_connections)
		(net 102)
	)
	(segment
		(start 206.522 154.386)
		(end 206.4295 154.4785)
		(width 0.125)
		(layer "B.Cu")
		(net 102)
	)
	(segment
		(start 206.4295 154.4785)
		(end 206.4295 154.7575)
		(width 0.125)
		(layer "B.Cu")
		(net 102)
	)
	(segment
		(start 206.4295 154.7575)
		(end 206.572 154.9)
		(width 0.125)
		(layer "B.Cu")
		(net 102)
	)
	(segment
		(start 206.522 154.171)
		(end 206.522 154.386)
		(width 0.125)
		(layer "B.Cu")
		(net 102)
	)
	(segment
		(start 201.305 139.51)
		(end 201.325 139.49)
		(width 0.1)
		(layer "In4.Cu")
		(net 102)
	)
	(segment
		(start 201.41 142.431422)
		(end 199.41 144.431422)
		(width 0.1)
		(layer "In4.Cu")
		(net 102)
	)
	(segment
		(start 201.325 139.49)
		(end 201.325 139.2375)
		(width 0.1)
		(layer "In4.Cu")
		(net 102)
	)
	(segment
		(start 201.41 141.546003)
		(end 201.41 142.431422)
		(width 0.1)
		(layer "In4.Cu")
		(net 102)
	)
	(segment
		(start 199.95 145.988578)
		(end 199.95 153.518578)
		(width 0.1)
		(layer "In4.Cu")
		(net 102)
	)
	(segment
		(start 201.3875 139.175)
		(end 201.575 139.175)
		(width 0.1)
		(layer "In4.Cu")
		(net 102)
	)
	(segment
		(start 206.141422 154.16)
		(end 206.422 154.440578)
		(width 0.1)
		(layer "In4.Cu")
		(net 102)
	)
	(segment
		(start 206.422 154.75)
		(end 206.572 154.9)
		(width 0.1)
		(layer "In4.Cu")
		(net 102)
	)
	(segment
		(start 201.65 141.306003)
		(end 201.41 141.546003)
		(width 0.1)
		(layer "In4.Cu")
		(net 102)
	)
	(segment
		(start 199.41 144.431422)
		(end 199.41 145.448578)
		(width 0.1)
		(layer "In4.Cu")
		(net 102)
	)
	(segment
		(start 199.95 153.518578)
		(end 200.591422 154.16)
		(width 0.1)
		(layer "In4.Cu")
		(net 102)
	)
	(segment
		(start 201.325 139.2375)
		(end 201.3875 139.175)
		(width 0.1)
		(layer "In4.Cu")
		(net 102)
	)
	(segment
		(start 201.65 139.25)
		(end 201.65 141.306003)
		(width 0.1)
		(layer "In4.Cu")
		(net 102)
	)
	(segment
		(start 201.575 139.175)
		(end 201.65 139.25)
		(width 0.1)
		(layer "In4.Cu")
		(net 102)
	)
	(segment
		(start 199.41 145.448578)
		(end 199.95 145.988578)
		(width 0.1)
		(layer "In4.Cu")
		(net 102)
	)
	(segment
		(start 206.422 154.440578)
		(end 206.422 154.75)
		(width 0.1)
		(layer "In4.Cu")
		(net 102)
	)
	(segment
		(start 200.591422 154.16)
		(end 206.141422 154.16)
		(width 0.1)
		(layer "In4.Cu")
		(net 102)
	)
	(via
		(at 185.2 148.95)
		(size 0.35)
		(drill 0.15)
		(layers "F.Cu" "B.Cu")
		(remove_unused_layers yes)
		(keep_end_layers yes)
		(zone_layer_connections)
		(net 103)
	)
	(via
		(at 203.699 148.051)
		(size 0.35)
		(drill 0.15)
		(layers "F.Cu" "B.Cu")
		(remove_unused_layers yes)
		(keep_end_layers yes)
		(zone_layer_connections)
		(net 103)
	)
	(segment
		(start 203.7 148.725)
		(end 203.7 148.052)
		(width 0.201)
		(layer "B.Cu")
		(net 103)
	)
	(segment
		(start 203.7 148.052)
		(end 203.699 148.051)
		(width 0.201)
		(layer "B.Cu")
		(net 103)
	)
	(segment
		(start 185.719404 148.430596)
		(end 185.2 148.95)
		(width 0.4)
		(layer "In6.Cu")
		(net 103)
	)
	(segment
		(start 199.48 150.14)
		(end 199.48 147.83)
		(width 0.4)
		(layer "In6.Cu")
		(net 103)
	)
	(segment
		(start 185.95 147.625)
		(end 185.719404 147.855596)
		(width 0.4)
		(layer "In6.Cu")
		(net 103)
	)
	(segment
		(start 203.699 148.051)
		(end 203.699 150.022752)
		(width 0.4)
		(layer "In6.Cu")
		(net 103)
	)
	(segment
		(start 199.816 150.476)
		(end 199.48 150.14)
		(width 0.4)
		(layer "In6.Cu")
		(net 103)
	)
	(segment
		(start 185.719404 147.855596)
		(end 185.719404 148.430596)
		(width 0.4)
		(layer "In6.Cu")
		(net 103)
	)
	(segment
		(start 199.48 147.83)
		(end 197.505491 145.855491)
		(width 0.4)
		(layer "In6.Cu")
		(net 103)
	)
	(segment
		(start 197.505491 145.855491)
		(end 196.824509 145.855491)
		(width 0.4)
		(layer "In6.Cu")
		(net 103)
	)
	(segment
		(start 203.699 150.022752)
		(end 203.245752 150.476)
		(width 0.4)
		(layer "In6.Cu")
		(net 103)
	)
	(segment
		(start 196.64 146.04)
		(end 193.481752 146.04)
		(width 0.4)
		(layer "In6.Cu")
		(net 103)
	)
	(segment
		(start 196.824509 145.855491)
		(end 196.64 146.04)
		(width 0.4)
		(layer "In6.Cu")
		(net 103)
	)
	(segment
		(start 191.896752 147.625)
		(end 185.95 147.625)
		(width 0.4)
		(layer "In6.Cu")
		(net 103)
	)
	(segment
		(start 203.245752 150.476)
		(end 199.816 150.476)
		(width 0.4)
		(layer "In6.Cu")
		(net 103)
	)
	(segment
		(start 193.481752 146.04)
		(end 191.896752 147.625)
		(width 0.4)
		(layer "In6.Cu")
		(net 103)
	)
	(via
		(at 202.399 149.351)
		(size 0.35)
		(drill 0.15)
		(layers "F.Cu" "B.Cu")
		(remove_unused_layers yes)
		(keep_end_layers yes)
		(zone_layer_connections)
		(net 104)
	)
	(via
		(at 205.7245 152.801)
		(size 0.35)
		(drill 0.15)
		(layers "F.Cu" "B.Cu")
		(remove_unused_layers yes)
		(keep_end_layers yes)
		(zone_layer_connections)
		(net 104)
	)
	(segment
		(start 206.122 151.676)
		(end 206.222 151.776)
		(width 0.11)
		(layer "B.Cu")
		(net 104)
	)
	(segment
		(start 206.222 152.686578)
		(end 205.980328 152.92825)
		(width 0.11)
		(layer "B.Cu")
		(net 104)
	)
	(segment
		(start 205.85175 152.92825)
		(end 205.7245 152.801)
		(width 0.11)
		(layer "B.Cu")
		(net 104)
	)
	(segment
		(start 206.222 151.776)
		(end 206.222 152.686578)
		(width 0.11)
		(layer "B.Cu")
		(net 104)
	)
	(segment
		(start 206.122 151.461)
		(end 206.122 151.676)
		(width 0.11)
		(layer "B.Cu")
		(net 104)
	)
	(segment
		(start 205.980328 152.92825)
		(end 205.85175 152.92825)
		(width 0.11)
		(layer "B.Cu")
		(net 104)
	)
	(segment
		(start 205.462545 152.051807)
		(end 205.144289 152.370063)
		(width 0.09)
		(layer "In2.Cu")
		(net 104)
	)
	(segment
		(start 205.14429 152.839938)
		(end 205.208312 152.90396)
		(width 0.09)
		(layer "In2.Cu")
		(net 104)
	)
	(segment
		(start 203.923666 150.499314)
		(end 204.491406 151.067054)
		(width 0.09)
		(layer "In2.Cu")
		(net 104)
	)
	(segment
		(start 202.698203 150.427221)
		(end 202.71 150.427221)
		(width 0.09)
		(layer "In2.Cu")
		(net 104)
	)
	(segment
		(start 203.64965 150.427221)
		(end 203.749618 150.427221)
		(width 0.09)
		(layer "In2.Cu")
		(net 104)
	)
	(segment
		(start 204.355 151.610773)
		(end 204.355 151.619227)
		(width 0.09)
		(layer "In2.Cu")
		(net 104)
	)
	(segment
		(start 204.518005 151.406347)
		(end 204.384289 151.540063)
		(width 0.09)
		(layer "In2.Cu")
		(net 104)
	)
	(segment
		(start 205.033032 151.435)
		(end 205.22368 151.435)
		(width 0.09)
		(layer "In2.Cu")
		(net 104)
	)
	(segment
		(start 205.621541 152.903959)
		(end 205.7245 152.801)
		(width 0.09)
		(layer "In2.Cu")
		(net 104)
	)
	(segment
		(start 205.279022 152.933249)
		(end 205.55083 152.933249)
		(width 0.09)
		(layer "In2.Cu")
		(net 104)
	)
	(segment
		(start 204.555 151.220584)
		(end 204.555 151.317033)
		(width 0.09)
		(layer "In2.Cu")
		(net 104)
	)
	(segment
		(start 202.630982 150.27713)
		(end 202.630982 150.318579)
		(width 0.09)
		(layer "In2.Cu")
		(net 104)
	)
	(segment
		(start 205.35286 151.488508)
		(end 205.454188 151.589836)
		(width 0.09)
		(layer "In2.Cu")
		(net 104)
	)
	(segment
		(start 203.024825 150.742046)
		(end 203.024825 150.837047)
		(width 0.09)
		(layer "In2.Cu")
		(net 104)
	)
	(segment
		(start 202.724 149.717421)
		(end 202.724 150.10127)
		(width 0.09)
		(layer "In2.Cu")
		(net 104)
	)
	(segment
		(start 205.515 151.736648)
		(end 205.515 151.925169)
		(width 0.09)
		(layer "In2.Cu")
		(net 104)
	)
	(segment
		(start 204.38429 151.689938)
		(end 204.430063 151.735711)
		(width 0.09)
		(layer "In2.Cu")
		(net 104)
	)
	(segment
		(start 204.500773 151.765)
		(end 204.569227 151.765)
		(width 0.09)
		(layer "In2.Cu")
		(net 104)
	)
	(segment
		(start 205.115 152.440773)
		(end 205.115 152.769227)
		(width 0.09)
		(layer "In2.Cu")
		(net 104)
	)
	(segment
		(start 202.69471 150.171981)
		(end 202.660271 150.20642)
		(width 0.09)
		(layer "In2.Cu")
		(net 104)
	)
	(segment
		(start 202.399 149.351)
		(end 202.694711 149.646711)
		(width 0.09)
		(layer "In2.Cu")
		(net 104)
	)
	(segment
		(start 204.639938 151.73571)
		(end 204.875322 151.500326)
		(width 0.09)
		(layer "In2.Cu")
		(net 104)
	)
	(segment
		(start 202.660272 150.38929)
		(end 202.698203 150.427221)
		(width 0.09)
		(layer "In2.Cu")
		(net 104)
	)
	(segment
		(start 203.334825 150.837047)
		(end 203.334825 150.742046)
		(width 0.09)
		(layer "In2.Cu")
		(net 104)
	)
	(segment
		(start 203.14965 150.961872)
		(end 203.21 150.961872)
		(width 0.09)
		(layer "In2.Cu")
		(net 104)
	)
	(arc
		(start 205.14429 152.839938)
		(mid 205.122612 152.807496)
		(end 205.115 152.769227)
		(width 0.09)
		(layer "In2.Cu")
		(net 104)
	)
	(arc
		(start 205.144289 152.370063)
		(mid 205.122612 152.402505)
		(end 205.115 152.440773)
		(width 0.09)
		(layer "In2.Cu")
		(net 104)
	)
	(arc
		(start 205.279022 152.933249)
		(mid 205.240754 152.925637)
		(end 205.208312 152.90396)
		(width 0.09)
		(layer "In2.Cu")
		(net 104)
	)
	(arc
		(start 204.355 151.610773)
		(mid 204.362612 151.572505)
		(end 204.384289 151.540063)
		(width 0.09)
		(layer "In2.Cu")
		(net 104)
	)
	(arc
		(start 205.462545 152.051807)
		(mid 205.501367 151.993705)
		(end 205.515 151.925169)
		(width 0.09)
		(layer "In2.Cu")
		(net 104)
	)
	(arc
		(start 203.024825 150.837047)
		(mid 203.061385 150.925312)
		(end 203.14965 150.961872)
		(width 0.09)
		(layer "In2.Cu")
		(net 104)
	)
	(arc
		(start 204.875322 151.500326)
		(mid 204.94768 151.451978)
		(end 205.033032 151.435)
		(width 0.09)
		(layer "In2.Cu")
		(net 104)
	)
	(arc
		(start 202.724 149.717421)
		(mid 202.716388 149.679153)
		(end 202.694711 149.646711)
		(width 0.09)
		(layer "In2.Cu")
		(net 104)
	)
	(arc
		(start 204.569227 151.765)
		(mid 204.607496 151.757388)
		(end 204.639938 151.73571)
		(width 0.09)
		(layer "In2.Cu")
		(net 104)
	)
	(arc
		(start 202.71 150.427221)
		(mid 202.932615 150.519431)
		(end 203.024825 150.742046)
		(width 0.09)
		(layer "In2.Cu")
		(net 104)
	)
	(arc
		(start 203.923666 150.499314)
		(mid 203.843812 150.445957)
		(end 203.749618 150.427221)
		(width 0.09)
		(layer "In2.Cu")
		(net 104)
	)
	(arc
		(start 202.660272 150.38929)
		(mid 202.638594 150.356848)
		(end 202.630982 150.318579)
		(width 0.09)
		(layer "In2.Cu")
		(net 104)
	)
	(arc
		(start 203.334825 150.742046)
		(mid 203.427035 150.519431)
		(end 203.64965 150.427221)
		(width 0.09)
		(layer "In2.Cu")
		(net 104)
	)
	(arc
		(start 202.660271 150.20642)
		(mid 202.638594 150.238862)
		(end 202.630982 150.27713)
		(width 0.09)
		(layer "In2.Cu")
		(net 104)
	)
	(arc
		(start 204.555 151.317033)
		(mid 204.545385 151.365369)
		(end 204.518005 151.406347)
		(width 0.09)
		(layer "In2.Cu")
		(net 104)
	)
	(arc
		(start 205.454188 151.589836)
		(mid 205.499195 151.657194)
		(end 205.515 151.736648)
		(width 0.09)
		(layer "In2.Cu")
		(net 104)
	)
	(arc
		(start 204.491406 151.067054)
		(mid 204.538472 151.137494)
		(end 204.555 151.220584)
		(width 0.09)
		(layer "In2.Cu")
		(net 104)
	)
	(arc
		(start 203.21 150.961872)
		(mid 203.298265 150.925312)
		(end 203.334825 150.837047)
		(width 0.09)
		(layer "In2.Cu")
		(net 104)
	)
	(arc
		(start 205.55083 152.933249)
		(mid 205.589099 152.925637)
		(end 205.621541 152.903959)
		(width 0.09)
		(layer "In2.Cu")
		(net 104)
	)
	(arc
		(start 204.500773 151.765)
		(mid 204.462505 151.757388)
		(end 204.430063 151.735711)
		(width 0.09)
		(layer "In2.Cu")
		(net 104)
	)
	(arc
		(start 204.355 151.619227)
		(mid 204.362612 151.657496)
		(end 204.38429 151.689938)
		(width 0.09)
		(layer "In2.Cu")
		(net 104)
	)
	(arc
		(start 205.22368 151.435)
		(mid 205.293592 151.448906)
		(end 205.35286 151.488508)
		(width 0.09)
		(layer "In2.Cu")
		(net 104)
	)
	(arc
		(start 202.69471 150.171981)
		(mid 202.716388 150.139539)
		(end 202.724 150.10127)
		(width 0.09)
		(layer "In2.Cu")
		(net 104)
	)
	(via
		(at 201.295767 138.701539)
		(size 0.35)
		(drill 0.15)
		(layers "F.Cu" "B.Cu")
		(remove_unused_layers yes)
		(keep_end_layers yes)
		(zone_layer_connections)
		(net 105)
	)
	(via
		(at 206.072 154.9)
		(size 0.35)
		(drill 0.15)
		(layers "F.Cu" "B.Cu")
		(remove_unused_layers yes)
		(keep_end_layers yes)
		(zone_layer_connections)
		(net 105)
	)
	(segment
		(start 206.122 154.386)
		(end 206.2145 154.4785)
		(width 0.125)
		(layer "B.Cu")
		(net 105)
	)
	(segment
		(start 206.2145 154.4785)
		(end 206.2145 154.7575)
		(width 0.125)
		(layer "B.Cu")
		(net 105)
	)
	(segment
		(start 206.122 154.171)
		(end 206.122 154.386)
		(width 0.125)
		(layer "B.Cu")
		(net 105)
	)
	(segment
		(start 206.2145 154.7575)
		(end 206.072 154.9)
		(width 0.125)
		(layer "B.Cu")
		(net 105)
	)
	(segment
		(start 201.19 141.546003)
		(end 201.19 142.368578)
		(width 0.1)
		(layer "In4.Cu")
		(net 105)
	)
	(segment
		(start 206.058578 154.36)
		(end 206.222 154.523422)
		(width 0.1)
		(layer "In4.Cu")
		(net 105)
	)
	(segment
		(start 200.965 139.032306)
		(end 200.965 141.321003)
		(width 0.1)
		(layer "In4.Cu")
		(net 105)
	)
	(segment
		(start 206.222 154.75)
		(end 206.072 154.9)
		(width 0.1)
		(layer "In4.Cu")
		(net 105)
	)
	(segment
		(start 200.508578 154.36)
		(end 206.058578 154.36)
		(width 0.1)
		(layer "In4.Cu")
		(net 105)
	)
	(segment
		(start 199.21 145.531422)
		(end 199.75 146.071422)
		(width 0.1)
		(layer "In4.Cu")
		(net 105)
	)
	(segment
		(start 200.965 141.321003)
		(end 201.19 141.546003)
		(width 0.1)
		(layer "In4.Cu")
		(net 105)
	)
	(segment
		(start 201.19 142.368578)
		(end 199.21 144.348578)
		(width 0.1)
		(layer "In4.Cu")
		(net 105)
	)
	(segment
		(start 199.75 153.601422)
		(end 200.508578 154.36)
		(width 0.1)
		(layer "In4.Cu")
		(net 105)
	)
	(segment
		(start 199.75 146.071422)
		(end 199.75 153.601422)
		(width 0.1)
		(layer "In4.Cu")
		(net 105)
	)
	(segment
		(start 206.222 154.523422)
		(end 206.222 154.75)
		(width 0.1)
		(layer "In4.Cu")
		(net 105)
	)
	(segment
		(start 199.21 144.348578)
		(end 199.21 145.531422)
		(width 0.1)
		(layer "In4.Cu")
		(net 105)
	)
	(segment
		(start 201.295767 138.701539)
		(end 200.965 139.032306)
		(width 0.1)
		(layer "In4.Cu")
		(net 105)
	)
	(via
		(at 204.5245 153.2555)
		(size 0.35)
		(drill 0.15)
		(layers "F.Cu" "B.Cu")
		(remove_unused_layers yes)
		(keep_end_layers yes)
		(zone_layer_connections)
		(net 106)
	)
	(via
		(at 201.099 150.001)
		(size 0.35)
		(drill 0.15)
		(layers "F.Cu" "B.Cu")
		(remove_unused_layers yes)
		(keep_end_layers yes)
		(zone_layer_connections)
		(net 106)
	)
	(segment
		(start 205.322 151.676)
		(end 205.222 151.776)
		(width 0.11)
		(layer "B.Cu")
		(net 106)
	)
	(segment
		(start 205.322 151.461)
		(end 205.322 151.676)
		(width 0.11)
		(layer "B.Cu")
		(net 106)
	)
	(segment
		(start 205.222 151.776)
		(end 205.222 152.769422)
		(width 0.11)
		(layer "B.Cu")
		(net 106)
	)
	(segment
		(start 205.222 152.769422)
		(end 204.863172 153.12825)
		(width 0.11)
		(layer "B.Cu")
		(net 106)
	)
	(segment
		(start 204.863172 153.12825)
		(end 204.65175 153.12825)
		(width 0.11)
		(layer "B.Cu")
		(net 106)
	)
	(segment
		(start 204.65175 153.12825)
		(end 204.5245 153.2555)
		(width 0.11)
		(layer "B.Cu")
		(net 106)
	)
	(segment
		(start 203.311848 148.8962)
		(end 201.625021 148.8962)
		(width 0.09)
		(layer "In4.Cu")
		(net 106)
	)
	(segment
		(start 201.099 149.803549)
		(end 201.099 150.001)
		(width 0.09)
		(layer "In4.Cu")
		(net 106)
	)
	(segment
		(start 203.905 152.636)
		(end 203.905 149.489352)
		(width 0.09)
		(layer "In4.Cu")
		(net 106)
	)
	(segment
		(start 201.625021 148.8962)
		(end 201.419 149.102221)
		(width 0.09)
		(layer "In4.Cu")
		(net 106)
	)
	(segment
		(start 201.419 149.102221)
		(end 201.419 149.483549)
		(width 0.09)
		(layer "In4.Cu")
		(net 106)
	)
	(segment
		(start 204.5245 153.2555)
		(end 203.905 152.636)
		(width 0.09)
		(layer "In4.Cu")
		(net 106)
	)
	(segment
		(start 203.905 149.489352)
		(end 203.311848 148.8962)
		(width 0.09)
		(layer "In4.Cu")
		(net 106)
	)
	(segment
		(start 201.419 149.483549)
		(end 201.099 149.803549)
		(width 0.09)
		(layer "In4.Cu")
		(net 106)
	)
	(via
		(at 204.5245 152.801)
		(size 0.35)
		(drill 0.15)
		(layers "F.Cu" "B.Cu")
		(remove_unused_layers yes)
		(keep_end_layers yes)
		(zone_layer_connections)
		(net 107)
	)
	(via
		(at 201.099 149.351)
		(size 0.35)
		(drill 0.15)
		(layers "F.Cu" "B.Cu")
		(remove_unused_layers yes)
		(keep_end_layers yes)
		(zone_layer_connections)
		(net 107)
	)
	(segment
		(start 204.922 151.461)
		(end 204.922 151.676)
		(width 0.11)
		(layer "B.Cu")
		(net 107)
	)
	(segment
		(start 204.65175 152.92825)
		(end 204.5245 152.801)
		(width 0.11)
		(layer "B.Cu")
		(net 107)
	)
	(segment
		(start 204.780328 152.92825)
		(end 204.65175 152.92825)
		(width 0.11)
		(layer "B.Cu")
		(net 107)
	)
	(segment
		(start 205.022 151.776)
		(end 205.022 152.686578)
		(width 0.11)
		(layer "B.Cu")
		(net 107)
	)
	(segment
		(start 204.922 151.676)
		(end 205.022 151.776)
		(width 0.11)
		(layer "B.Cu")
		(net 107)
	)
	(segment
		(start 205.022 152.686578)
		(end 204.780328 152.92825)
		(width 0.11)
		(layer "B.Cu")
		(net 107)
	)
	(segment
		(start 202.79685 148.7062)
		(end 203.390552 148.7062)
		(width 0.09)
		(layer "In4.Cu")
		(net 107)
	)
	(segment
		(start 202.49685 148.419349)
		(end 202.51 148.419349)
		(width 0.09)
		(layer "In4.Cu")
		(net 107)
	)
	(segment
		(start 203.390552 148.7062)
		(end 204.095 149.410648)
		(width 0.09)
		(layer "In4.Cu")
		(net 107)
	)
	(segment
		(start 201.099 149.153549)
		(end 201.546349 148.7062)
		(width 0.09)
		(layer "In4.Cu")
		(net 107)
	)
	(segment
		(start 201.099 149.351)
		(end 201.099 149.153549)
		(width 0.09)
		(layer "In4.Cu")
		(net 107)
	)
	(segment
		(start 202.653425 148.562774)
		(end 202.653425 148.562775)
		(width 0.09)
		(layer "In4.Cu")
		(net 107)
	)
	(segment
		(start 204.095 152.557299)
		(end 204.338701 152.801)
		(width 0.09)
		(layer "In4.Cu")
		(net 107)
	)
	(segment
		(start 204.338701 152.801)
		(end 204.5245 152.801)
		(width 0.09)
		(layer "In4.Cu")
		(net 107)
	)
	(segment
		(start 202.353425 148.562775)
		(end 202.353425 148.562774)
		(width 0.09)
		(layer "In4.Cu")
		(net 107)
	)
	(segment
		(start 201.546349 148.7062)
		(end 201.61 148.7062)
		(width 0.09)
		(layer "In4.Cu")
		(net 107)
	)
	(segment
		(start 204.095 149.410648)
		(end 204.095 152.557299)
		(width 0.09)
		(layer "In4.Cu")
		(net 107)
	)
	(segment
		(start 202.06 148.463745)
		(end 202.06 148.5562)
		(width 0.09)
		(layer "In4.Cu")
		(net 107)
	)
	(segment
		(start 201.76 148.5562)
		(end 201.76 148.463745)
		(width 0.09)
		(layer "In4.Cu")
		(net 107)
	)
	(arc
		(start 202.21 148.7062)
		(mid 202.311417 148.664192)
		(end 202.353425 148.562775)
		(width 0.09)
		(layer "In4.Cu")
		(net 107)
	)
	(arc
		(start 201.91 148.313745)
		(mid 202.016066 148.357679)
		(end 202.06 148.463745)
		(width 0.09)
		(layer "In4.Cu")
		(net 107)
	)
	(arc
		(start 202.653425 148.562775)
		(mid 202.695433 148.664192)
		(end 202.79685 148.7062)
		(width 0.09)
		(layer "In4.Cu")
		(net 107)
	)
	(arc
		(start 201.76 148.463745)
		(mid 201.803934 148.357679)
		(end 201.91 148.313745)
		(width 0.09)
		(layer "In4.Cu")
		(net 107)
	)
	(arc
		(start 202.353425 148.562774)
		(mid 202.395433 148.461357)
		(end 202.49685 148.419349)
		(width 0.09)
		(layer "In4.Cu")
		(net 107)
	)
	(arc
		(start 202.06 148.5562)
		(mid 202.103934 148.662266)
		(end 202.21 148.7062)
		(width 0.09)
		(layer "In4.Cu")
		(net 107)
	)
	(arc
		(start 202.51 148.419349)
		(mid 202.611417 148.461357)
		(end 202.653425 148.562774)
		(width 0.09)
		(layer "In4.Cu")
		(net 107)
	)
	(arc
		(start 201.61 148.7062)
		(mid 201.716066 148.662266)
		(end 201.76 148.5562)
		(width 0.09)
		(layer "In4.Cu")
		(net 107)
	)
	(via
		(at 201.749 150.001)
		(size 0.35)
		(drill 0.15)
		(layers "F.Cu" "B.Cu")
		(remove_unused_layers yes)
		(keep_end_layers yes)
		(zone_layer_connections)
		(net 108)
	)
	(via
		(at 203.3245 153.2555)
		(size 0.35)
		(drill 0.15)
		(layers "F.Cu" "B.Cu")
		(remove_unused_layers yes)
		(keep_end_layers yes)
		(zone_layer_connections)
		(net 108)
	)
	(segment
		(start 203.663172 153.12825)
		(end 203.45175 153.12825)
		(width 0.11)
		(layer "B.Cu")
		(net 108)
	)
	(segment
		(start 203.45175 153.12825)
		(end 203.3245 153.2555)
		(width 0.11)
		(layer "B.Cu")
		(net 108)
	)
	(segment
		(start 204.022 151.776)
		(end 204.022 152.769422)
		(width 0.11)
		(layer "B.Cu")
		(net 108)
	)
	(segment
		(start 204.022 152.769422)
		(end 203.663172 153.12825)
		(width 0.11)
		(layer "B.Cu")
		(net 108)
	)
	(segment
		(start 204.122 151.461)
		(end 204.122 151.676)
		(width 0.11)
		(layer "B.Cu")
		(net 108)
	)
	(segment
		(start 204.122 151.676)
		(end 204.022 151.776)
		(width 0.11)
		(layer "B.Cu")
		(net 108)
	)
	(segment
		(start 203.672145 151.57429)
		(end 203.688465 151.59061)
		(width 0.09)
		(layer "In2.Cu")
		(net 108)
	)
	(segment
		(start 202.21 150.924558)
		(end 202.21 151.014227)
		(width 0.09)
		(layer "In2.Cu")
		(net 108)
	)
	(segment
		(start 202.18071 151.084938)
		(end 201.915199 151.350449)
		(width 0.09)
		(layer "In2.Cu")
		(net 108)
	)
	(segment
		(start 202.86439 151.545)
		(end 203.601434 151.545)
		(width 0.09)
		(layer "In2.Cu")
		(net 108)
	)
	(segment
		(start 203.136331 153.123251)
		(end 203.15083 153.123251)
		(width 0.09)
		(layer "In2.Cu")
		(net 108)
	)
	(segment
		(start 203.016454 153.201707)
		(end 203.065621 153.15254)
		(width 0.09)
		(layer "In2.Cu")
		(net 108)
	)
	(segment
		(start 201.809117 150.759215)
		(end 201.853981 150.804079)
		(width 0.09)
		(layer "In2.Cu")
		(net 108)
	)
	(segment
		(start 202.877727 151.887921)
		(end 202.554427 152.211221)
		(width 0.09)
		(layer "In2.Cu")
		(net 108)
	)
	(segment
		(start 203.221541 153.152541)
		(end 203.3245 153.2555)
		(width 0.09)
		(layer "In2.Cu")
		(net 108)
	)
	(segment
		(start 202.556386 153.150738)
		(end 202.596662 153.191014)
		(width 0.09)
		(layer "In2.Cu")
		(net 108)
	)
	(segment
		(start 201.853191 151.500149)
		(end 201.853191 151.651844)
		(width 0.09)
		(layer "In2.Cu")
		(net 108)
	)
	(segment
		(start 202.476037 151.891932)
		(end 202.793679 151.57429)
		(width 0.09)
		(layer "In2.Cu")
		(net 108)
	)
	(segment
		(start 202.811495 153.28)
		(end 202.827438 153.28)
		(width 0.09)
		(layer "In2.Cu")
		(net 108)
	)
	(segment
		(start 203.717754 151.66132)
		(end 203.717754 151.69985)
		(width 0.09)
		(layer "In2.Cu")
		(net 108)
	)
	(segment
		(start 202.089521 150.804079)
		(end 202.21 150.924558)
		(width 0.09)
		(layer "In2.Cu")
		(net 108)
	)
	(segment
		(start 201.906718 151.78107)
		(end 202.037535 151.911887)
		(width 0.09)
		(layer "In2.Cu")
		(net 108)
	)
	(segment
		(start 201.749 150.001)
		(end 201.749 150.37854)
		(width 0.09)
		(layer "In2.Cu")
		(net 108)
	)
	(segment
		(start 203.688464 151.770561)
		(end 203.673314 151.785711)
		(width 0.09)
		(layer "In2.Cu")
		(net 108)
	)
	(segment
		(start 201.809116 150.641446)
		(end 201.809117 150.641445)
		(width 0.09)
		(layer "In2.Cu")
		(net 108)
	)
	(segment
		(start 202.474188 152.404935)
		(end 202.474188 152.952296)
		(width 0.09)
		(layer "In2.Cu")
		(net 108)
	)
	(segment
		(start 202.201998 151.98001)
		(end 202.263396 151.98001)
		(width 0.09)
		(layer "In2.Cu")
		(net 108)
	)
	(segment
		(start 203.602604 151.815)
		(end 203.053774 151.815)
		(width 0.09)
		(layer "In2.Cu")
		(net 108)
	)
	(arc
		(start 202.596662 153.191014)
		(mid 202.695228 153.256874)
		(end 202.811495 153.28)
		(width 0.09)
		(layer "In2.Cu")
		(net 108)
	)
	(arc
		(start 202.263396 151.98001)
		(mid 202.378476 151.95712)
		(end 202.476037 151.891932)
		(width 0.09)
		(layer "In2.Cu")
		(net 108)
	)
	(arc
		(start 202.827438 153.28)
		(mid 202.929733 153.259652)
		(end 203.016454 153.201707)
		(width 0.09)
		(layer "In2.Cu")
		(net 108)
	)
	(arc
		(start 203.15083 153.123251)
		(mid 203.189099 153.130863)
		(end 203.221541 153.152541)
		(width 0.09)
		(layer "In2.Cu")
		(net 108)
	)
	(arc
		(start 201.853981 150.804079)
		(mid 201.912866 150.82847)
		(end 201.971751 150.804079)
		(width 0.09)
		(layer "In2.Cu")
		(net 108)
	)
	(arc
		(start 201.853191 151.651844)
		(mid 201.867102 151.721781)
		(end 201.906718 151.78107)
		(width 0.09)
		(layer "In2.Cu")
		(net 108)
	)
	(arc
		(start 203.065621 153.15254)
		(mid 203.098063 153.130863)
		(end 203.136331 153.123251)
		(width 0.09)
		(layer "In2.Cu")
		(net 108)
	)
	(arc
		(start 203.717754 151.69985)
		(mid 203.710142 151.738119)
		(end 203.688464 151.770561)
		(width 0.09)
		(layer "In2.Cu")
		(net 108)
	)
	(arc
		(start 201.809117 150.523675)
		(mid 201.833508 150.582561)
		(end 201.809116 150.641446)
		(width 0.09)
		(layer "In2.Cu")
		(net 108)
	)
	(arc
		(start 201.915199 151.350449)
		(mid 201.869307 151.419132)
		(end 201.853191 151.500149)
		(width 0.09)
		(layer "In2.Cu")
		(net 108)
	)
	(arc
		(start 203.673314 151.785711)
		(mid 203.640872 151.807388)
		(end 203.602604 151.815)
		(width 0.09)
		(layer "In2.Cu")
		(net 108)
	)
	(arc
		(start 202.554427 152.211221)
		(mid 202.495041 152.300098)
		(end 202.474188 152.404935)
		(width 0.09)
		(layer "In2.Cu")
		(net 108)
	)
	(arc
		(start 203.601434 151.545)
		(mid 203.639703 151.552612)
		(end 203.672145 151.57429)
		(width 0.09)
		(layer "In2.Cu")
		(net 108)
	)
	(arc
		(start 201.749 150.37854)
		(mid 201.764624 150.457087)
		(end 201.809117 150.523675)
		(width 0.09)
		(layer "In2.Cu")
		(net 108)
	)
	(arc
		(start 202.037535 151.911887)
		(mid 202.112991 151.962305)
		(end 202.201998 151.98001)
		(width 0.09)
		(layer "In2.Cu")
		(net 108)
	)
	(arc
		(start 203.053774 151.815)
		(mid 202.958498 151.833952)
		(end 202.877727 151.887921)
		(width 0.09)
		(layer "In2.Cu")
		(net 108)
	)
	(arc
		(start 202.793679 151.57429)
		(mid 202.826121 151.552612)
		(end 202.86439 151.545)
		(width 0.09)
		(layer "In2.Cu")
		(net 108)
	)
	(arc
		(start 202.474188 152.952296)
		(mid 202.495551 153.059692)
		(end 202.556386 153.150738)
		(width 0.09)
		(layer "In2.Cu")
		(net 108)
	)
	(arc
		(start 201.809117 150.641445)
		(mid 201.784726 150.70033)
		(end 201.809117 150.759215)
		(width 0.09)
		(layer "In2.Cu")
		(net 108)
	)
	(arc
		(start 202.21 151.014227)
		(mid 202.202388 151.052496)
		(end 202.18071 151.084938)
		(width 0.09)
		(layer "In2.Cu")
		(net 108)
	)
	(arc
		(start 201.971751 150.804079)
		(mid 202.030636 150.779688)
		(end 202.089521 150.804079)
		(width 0.09)
		(layer "In2.Cu")
		(net 108)
	)
	(arc
		(start 203.688465 151.59061)
		(mid 203.710142 151.623052)
		(end 203.717754 151.66132)
		(width 0.09)
		(layer "In2.Cu")
		(net 108)
	)
	(via
		(at 204.172 154.9)
		(size 0.35)
		(drill 0.15)
		(layers "F.Cu" "B.Cu")
		(remove_unused_layers yes)
		(keep_end_layers yes)
		(zone_layer_connections)
		(net 109)
	)
	(via
		(at 204.498 133.102)
		(size 0.35)
		(drill 0.15)
		(layers "F.Cu" "B.Cu")
		(remove_unused_layers yes)
		(keep_end_layers yes)
		(zone_layer_connections)
		(net 109)
	)
	(segment
		(start 204.122 154.171)
		(end 204.122 154.386)
		(width 0.11)
		(layer "B.Cu")
		(net 109)
	)
	(segment
		(start 204.022 154.486)
		(end 204.022 154.75)
		(width 0.11)
		(layer "B.Cu")
		(net 109)
	)
	(segment
		(start 204.122 154.386)
		(end 204.022 154.486)
		(width 0.11)
		(layer "B.Cu")
		(net 109)
	)
	(segment
		(start 204.022 154.75)
		(end 204.172 154.9)
		(width 0.11)
		(layer "B.Cu")
		(net 109)
	)
	(segment
		(start 204.017001 154.745001)
		(end 204.172 154.9)
		(width 0.09)
		(layer "In9.Cu")
		(net 109)
	)
	(segment
		(start 211.065 153.219352)
		(end 209.969352 154.315)
		(width 0.09)
		(layer "In9.Cu")
		(net 109)
	)
	(segment
		(start 207.519352 132.395)
		(end 208.995 133.870648)
		(width 0.09)
		(layer "In9.Cu")
		(net 109)
	)
	(segment
		(start 212.08 139.675648)
		(end 212.215 139.810648)
		(width 0.09)
		(layer "In9.Cu")
		(net 109)
	)
	(segment
		(start 212.215 145.890648)
		(end 212.755 146.430648)
		(width 0.09)
		(layer "In9.Cu")
		(net 109)
	)
	(segment
		(start 204.498 133.102)
		(end 204.84 132.76)
		(width 0.09)
		(layer "In9.Cu")
		(net 109)
	)
	(segment
		(start 212.755 146.430648)
		(end 212.755 149.789352)
		(width 0.09)
		(layer "In9.Cu")
		(net 109)
	)
	(segment
		(start 204.017001 154.607351)
		(end 204.017001 154.745001)
		(width 0.09)
		(layer "In9.Cu")
		(net 109)
	)
	(segment
		(start 212.755 149.789352)
		(end 211.065 151.479352)
		(width 0.09)
		(layer "In9.Cu")
		(net 109)
	)
	(segment
		(start 205.756346 132.395)
		(end 207.519352 132.395)
		(width 0.09)
		(layer "In9.Cu")
		(net 109)
	)
	(segment
		(start 211.065 151.479352)
		(end 211.065 153.219352)
		(width 0.09)
		(layer "In9.Cu")
		(net 109)
	)
	(segment
		(start 212.215 139.810648)
		(end 212.215 145.890648)
		(width 0.09)
		(layer "In9.Cu")
		(net 109)
	)
	(segment
		(start 212.08 138.365648)
		(end 212.08 139.675648)
		(width 0.09)
		(layer "In9.Cu")
		(net 109)
	)
	(segment
		(start 209.969352 154.315)
		(end 204.309352 154.315)
		(width 0.09)
		(layer "In9.Cu")
		(net 109)
	)
	(segment
		(start 205.391346 132.76)
		(end 205.756346 132.395)
		(width 0.09)
		(layer "In9.Cu")
		(net 109)
	)
	(segment
		(start 204.309352 154.315)
		(end 204.017001 154.607351)
		(width 0.09)
		(layer "In9.Cu")
		(net 109)
	)
	(segment
		(start 208.995 135.280648)
		(end 212.08 138.365648)
		(width 0.09)
		(layer "In9.Cu")
		(net 109)
	)
	(segment
		(start 204.84 132.76)
		(end 205.391346 132.76)
		(width 0.09)
		(layer "In9.Cu")
		(net 109)
	)
	(segment
		(start 208.995 133.870648)
		(end 208.995 135.280648)
		(width 0.09)
		(layer "In9.Cu")
		(net 109)
	)
	(via
		(at 203.3245 152.801)
		(size 0.35)
		(drill 0.15)
		(layers "F.Cu" "B.Cu")
		(remove_unused_layers yes)
		(keep_end_layers yes)
		(zone_layer_connections)
		(net 110)
	)
	(via
		(at 201.749 149.351)
		(size 0.35)
		(drill 0.15)
		(layers "F.Cu" "B.Cu")
		(remove_unused_layers yes)
		(keep_end_layers yes)
		(zone_layer_connections)
		(net 110)
	)
	(segment
		(start 203.722 151.461)
		(end 203.722 151.676)
		(width 0.11)
		(layer "B.Cu")
		(net 110)
	)
	(segment
		(start 203.722 151.676)
		(end 203.822 151.776)
		(width 0.11)
		(layer "B.Cu")
		(net 110)
	)
	(segment
		(start 203.45175 152.92825)
		(end 203.3245 152.801)
		(width 0.11)
		(layer "B.Cu")
		(net 110)
	)
	(segment
		(start 203.580328 152.92825)
		(end 203.45175 152.92825)
		(width 0.11)
		(layer "B.Cu")
		(net 110)
	)
	(segment
		(start 203.822 151.776)
		(end 203.822 152.686578)
		(width 0.11)
		(layer "B.Cu")
		(net 110)
	)
	(segment
		(start 203.822 152.686578)
		(end 203.580328 152.92825)
		(width 0.11)
		(layer "B.Cu")
		(net 110)
	)
	(segment
		(start 203.790864 151.936865)
		(end 203.847781 151.879948)
		(width 0.09)
		(layer "In2.Cu")
		(net 110)
	)
	(segment
		(start 201.939 150.357579)
		(end 201.939 150.30497)
		(width 0.09)
		(layer "In2.Cu")
		(net 110)
	)
	(segment
		(start 201.96829 150.234259)
		(end 202.039711 150.162838)
		(width 0.09)
		(layer "In2.Cu")
		(net 110)
	)
	(segment
		(start 202.03971 149.839161)
		(end 201.968289 149.76774)
		(width 0.09)
		(layer "In2.Cu")
		(net 110)
	)
	(segment
		(start 203.3245 152.801)
		(end 203.22154 152.90396)
		(width 0.09)
		(layer "In2.Cu")
		(net 110)
	)
	(segment
		(start 201.90971 149.51171)
		(end 201.749 149.351)
		(width 0.09)
		(layer "In2.Cu")
		(net 110)
	)
	(segment
		(start 203.070773 152.005)
		(end 203.626371 152.005)
		(width 0.09)
		(layer "In2.Cu")
		(net 110)
	)
	(segment
		(start 202.043191 151.607418)
		(end 202.043191 151.532582)
		(width 0.09)
		(layer "In2.Cu")
		(net 110)
	)
	(segment
		(start 203.633621 151.355)
		(end 202.857616 151.355)
		(width 0.09)
		(layer "In2.Cu")
		(net 110)
	)
	(segment
		(start 202.069 150.092128)
		(end 202.069 149.909872)
		(width 0.09)
		(layer "In2.Cu")
		(net 110)
	)
	(segment
		(start 202.072481 151.461871)
		(end 202.340505 151.193847)
		(width 0.09)
		(layer "In2.Cu")
		(net 110)
	)
	(segment
		(start 202.818036 153.09)
		(end 202.805773 153.09)
		(width 0.09)
		(layer "In2.Cu")
		(net 110)
	)
	(segment
		(start 202.268569 151.79001)
		(end 202.225783 151.79001)
		(width 0.09)
		(layer "In2.Cu")
		(net 110)
	)
	(segment
		(start 203.15083 152.933249)
		(end 203.125919 152.933249)
		(width 0.09)
		(layer "In2.Cu")
		(net 110)
	)
	(segment
		(start 203.842757 151.476198)
		(end 203.783741 151.417182)
		(width 0.09)
		(layer "In2.Cu")
		(net 110)
	)
	(segment
		(start 203.907754 151.735159)
		(end 203.907754 151.633113)
		(width 0.09)
		(layer "In2.Cu")
		(net 110)
	)
	(segment
		(start 202.665368 151.434632)
		(end 202.339279 151.760721)
		(width 0.09)
		(layer "In2.Cu")
		(net 110)
	)
	(segment
		(start 202.938631 153.010826)
		(end 202.888746 153.060711)
		(width 0.09)
		(layer "In2.Cu")
		(net 110)
	)
	(segment
		(start 202.4 151.050214)
		(end 202.4 150.901421)
		(width 0.09)
		(layer "In2.Cu")
		(net 110)
	)
	(segment
		(start 202.37071 150.83071)
		(end 201.968289 150.428289)
		(width 0.09)
		(layer "In2.Cu")
		(net 110)
	)
	(segment
		(start 202.693478 152.340874)
		(end 203.000063 152.034289)
		(width 0.09)
		(layer "In2.Cu")
		(net 110)
	)
	(segment
		(start 201.939 149.69703)
		(end 201.939 149.582421)
		(width 0.09)
		(layer "In2.Cu")
		(net 110)
	)
	(segment
		(start 202.735062 153.06071)
		(end 202.693477 153.019125)
		(width 0.09)
		(layer "In2.Cu")
		(net 110)
	)
	(segment
		(start 202.664188 152.948415)
		(end 202.664188 152.411585)
		(width 0.09)
		(layer "In2.Cu")
		(net 110)
	)
	(segment
		(start 202.155072 151.76072)
		(end 202.07248 151.678128)
		(width 0.09)
		(layer "In2.Cu")
		(net 110)
	)
	(arc
		(start 202.4 150.901421)
		(mid 202.392388 150.863152)
		(end 202.37071 150.83071)
		(width 0.09)
		(layer "In2.Cu")
		(net 110)
	)
	(arc
		(start 203.847781 151.879948)
		(mid 203.892168 151.813518)
		(end 203.907754 151.735159)
		(width 0.09)
		(layer "In2.Cu")
		(net 110)
	)
	(arc
		(start 202.805773 153.09)
		(mid 202.767504 153.082388)
		(end 202.735062 153.06071)
		(width 0.09)
		(layer "In2.Cu")
		(net 110)
	)
	(arc
		(start 201.939 150.30497)
		(mid 201.946612 150.266701)
		(end 201.96829 150.234259)
		(width 0.09)
		(layer "In2.Cu")
		(net 110)
	)
	(arc
		(start 201.939 149.582421)
		(mid 201.931388 149.544152)
		(end 201.90971 149.51171)
		(width 0.09)
		(layer "In2.Cu")
		(net 110)
	)
	(arc
		(start 202.665368 151.434632)
		(mid 202.753572 151.375696)
		(end 202.857616 151.355)
		(width 0.09)
		(layer "In2.Cu")
		(net 110)
	)
	(arc
		(start 203.22154 152.90396)
		(mid 203.189098 152.925637)
		(end 203.15083 152.933249)
		(width 0.09)
		(layer "In2.Cu")
		(net 110)
	)
	(arc
		(start 202.664188 152.411585)
		(mid 202.6718 152.373316)
		(end 202.693478 152.340874)
		(width 0.09)
		(layer "In2.Cu")
		(net 110)
	)
	(arc
		(start 203.626371 152.005)
		(mid 203.715394 151.987292)
		(end 203.790864 151.936865)
		(width 0.09)
		(layer "In2.Cu")
		(net 110)
	)
	(arc
		(start 202.888746 153.060711)
		(mid 202.856304 153.082388)
		(end 202.818036 153.09)
		(width 0.09)
		(layer "In2.Cu")
		(net 110)
	)
	(arc
		(start 202.039711 150.162838)
		(mid 202.061388 150.130396)
		(end 202.069 150.092128)
		(width 0.09)
		(layer "In2.Cu")
		(net 110)
	)
	(arc
		(start 201.968289 150.428289)
		(mid 201.946612 150.395847)
		(end 201.939 150.357579)
		(width 0.09)
		(layer "In2.Cu")
		(net 110)
	)
	(arc
		(start 203.000063 152.034289)
		(mid 203.032505 152.012612)
		(end 203.070773 152.005)
		(width 0.09)
		(layer "In2.Cu")
		(net 110)
	)
	(arc
		(start 203.783741 151.417182)
		(mid 203.714865 151.371161)
		(end 203.633621 151.355)
		(width 0.09)
		(layer "In2.Cu")
		(net 110)
	)
	(arc
		(start 203.125919 152.933249)
		(mid 203.02456 152.953411)
		(end 202.938631 153.010826)
		(width 0.09)
		(layer "In2.Cu")
		(net 110)
	)
	(arc
		(start 202.693477 153.019125)
		(mid 202.6718 152.986683)
		(end 202.664188 152.948415)
		(width 0.09)
		(layer "In2.Cu")
		(net 110)
	)
	(arc
		(start 203.907754 151.633113)
		(mid 203.890861 151.548191)
		(end 203.842757 151.476198)
		(width 0.09)
		(layer "In2.Cu")
		(net 110)
	)
	(arc
		(start 202.339279 151.760721)
		(mid 202.306837 151.782398)
		(end 202.268569 151.79001)
		(width 0.09)
		(layer "In2.Cu")
		(net 110)
	)
	(arc
		(start 202.340505 151.193847)
		(mid 202.384538 151.127948)
		(end 202.4 151.050214)
		(width 0.09)
		(layer "In2.Cu")
		(net 110)
	)
	(arc
		(start 202.069 149.909872)
		(mid 202.061388 149.871603)
		(end 202.03971 149.839161)
		(width 0.09)
		(layer "In2.Cu")
		(net 110)
	)
	(arc
		(start 202.043191 151.532582)
		(mid 202.050803 151.494313)
		(end 202.072481 151.461871)
		(width 0.09)
		(layer "In2.Cu")
		(net 110)
	)
	(arc
		(start 202.07248 151.678128)
		(mid 202.050803 151.645686)
		(end 202.043191 151.607418)
		(width 0.09)
		(layer "In2.Cu")
		(net 110)
	)
	(arc
		(start 202.225783 151.79001)
		(mid 202.187514 151.782398)
		(end 202.155072 151.76072)
		(width 0.09)
		(layer "In2.Cu")
		(net 110)
	)
	(arc
		(start 201.968289 149.76774)
		(mid 201.946612 149.735298)
		(end 201.939 149.69703)
		(width 0.09)
		(layer "In2.Cu")
		(net 110)
	)
	(via
		(at 203.672 154.9)
		(size 0.35)
		(drill 0.15)
		(layers "F.Cu" "B.Cu")
		(remove_unused_layers yes)
		(keep_end_layers yes)
		(zone_layer_connections)
		(net 111)
	)
	(via
		(at 205.298 133.102)
		(size 0.35)
		(drill 0.15)
		(layers "F.Cu" "B.Cu")
		(remove_unused_layers yes)
		(keep_end_layers yes)
		(zone_layer_connections)
		(net 111)
	)
	(segment
		(start 203.722 154.386)
		(end 203.822 154.486)
		(width 0.11)
		(layer "B.Cu")
		(net 111)
	)
	(segment
		(start 203.722 154.171)
		(end 203.722 154.386)
		(width 0.11)
		(layer "B.Cu")
		(net 111)
	)
	(segment
		(start 203.822 154.75)
		(end 203.672 154.9)
		(width 0.11)
		(layer "B.Cu")
		(net 111)
	)
	(segment
		(start 203.822 154.486)
		(end 203.822 154.75)
		(width 0.11)
		(layer "B.Cu")
		(net 111)
	)
	(segment
		(start 210.779292 137.333644)
		(end 208.805 135.359352)
		(width 0.09)
		(layer "In9.Cu")
		(net 111)
	)
	(segment
		(start 203.826999 154.528649)
		(end 204.230648 154.125)
		(width 0.09)
		(layer "In9.Cu")
		(net 111)
	)
	(segment
		(start 205.31805 133.102)
		(end 205.298 133.102)
		(width 0.09)
		(layer "In9.Cu")
		(net 111)
	)
	(segment
		(start 211.324621 138.273245)
		(end 211.415691 138.182175)
		(width 0.09)
		(layer "In9.Cu")
		(net 111)
	)
	(segment
		(start 203.826999 154.745001)
		(end 203.826999 154.528649)
		(width 0.09)
		(layer "In9.Cu")
		(net 111)
	)
	(segment
		(start 204.230648 154.125)
		(end 209.890648 154.125)
		(width 0.09)
		(layer "In9.Cu")
		(net 111)
	)
	(segment
		(start 207.440648 132.585)
		(end 205.83505 132.585)
		(width 0.09)
		(layer "In9.Cu")
		(net 111)
	)
	(segment
		(start 211.89 139.754352)
		(end 211.89 138.444352)
		(width 0.09)
		(layer "In9.Cu")
		(net 111)
	)
	(segment
		(start 208.805 133.949352)
		(end 207.440648 132.585)
		(width 0.09)
		(layer "In9.Cu")
		(net 111)
	)
	(segment
		(start 210.900357 137.848979)
		(end 210.991426 137.75791)
		(width 0.09)
		(layer "In9.Cu")
		(net 111)
	)
	(segment
		(start 211.203558 137.75791)
		(end 211.203559 137.757911)
		(width 0.09)
		(layer "In9.Cu")
		(net 111)
	)
	(segment
		(start 211.112488 138.061112)
		(end 211.203558 137.970042)
		(width 0.09)
		(layer "In9.Cu")
		(net 111)
	)
	(segment
		(start 212.025 145.969352)
		(end 212.025 139.889352)
		(width 0.09)
		(layer "In9.Cu")
		(net 111)
	)
	(segment
		(start 212.565 149.710648)
		(end 212.565 146.509352)
		(width 0.09)
		(layer "In9.Cu")
		(net 111)
	)
	(segment
		(start 209.890648 154.125)
		(end 210.875 153.140648)
		(width 0.09)
		(layer "In9.Cu")
		(net 111)
	)
	(segment
		(start 205.83505 132.585)
		(end 205.31805 133.102)
		(width 0.09)
		(layer "In9.Cu")
		(net 111)
	)
	(segment
		(start 210.875 153.140648)
		(end 210.875 151.400648)
		(width 0.09)
		(layer "In9.Cu")
		(net 111)
	)
	(segment
		(start 210.688224 137.636846)
		(end 210.779291 137.545776)
		(width 0.09)
		(layer "In9.Cu")
		(net 111)
	)
	(segment
		(start 210.688224 137.84898)
		(end 210.688223 137.848978)
		(width 0.09)
		(layer "In9.Cu")
		(net 111)
	)
	(segment
		(start 212.025 139.889352)
		(end 211.89 139.754352)
		(width 0.09)
		(layer "In9.Cu")
		(net 111)
	)
	(segment
		(start 210.779292 137.333643)
		(end 210.779292 137.333644)
		(width 0.09)
		(layer "In9.Cu")
		(net 111)
	)
	(segment
		(start 211.89 138.444352)
		(end 211.627824 138.182176)
		(width 0.09)
		(layer "In9.Cu")
		(net 111)
	)
	(segment
		(start 208.805 135.359352)
		(end 208.805 133.949352)
		(width 0.09)
		(layer "In9.Cu")
		(net 111)
	)
	(segment
		(start 210.875 151.400648)
		(end 212.565 149.710648)
		(width 0.09)
		(layer "In9.Cu")
		(net 111)
	)
	(segment
		(start 203.672 154.9)
		(end 203.826999 154.745001)
		(width 0.09)
		(layer "In9.Cu")
		(net 111)
	)
	(segment
		(start 212.565 146.509352)
		(end 212.025 145.969352)
		(width 0.09)
		(layer "In9.Cu")
		(net 111)
	)
	(segment
		(start 210.688222 137.636845)
		(end 210.688224 137.636846)
		(width 0.09)
		(layer "In9.Cu")
		(net 111)
	)
	(arc
		(start 210.688223 137.848978)
		(mid 210.644289 137.742913)
		(end 210.688222 137.636845)
		(width 0.09)
		(layer "In9.Cu")
		(net 111)
	)
	(arc
		(start 211.324621 138.273245)
		(mid 211.218555 138.317179)
		(end 211.112489 138.273245)
		(width 0.09)
		(layer "In9.Cu")
		(net 111)
	)
	(arc
		(start 210.779291 137.545776)
		(mid 210.823227 137.439711)
		(end 210.779292 137.333643)
		(width 0.09)
		(layer "In9.Cu")
		(net 111)
	)
	(arc
		(start 211.112489 138.273245)
		(mid 211.068553 138.167178)
		(end 211.112488 138.061112)
		(width 0.09)
		(layer "In9.Cu")
		(net 111)
	)
	(arc
		(start 211.203559 137.757911)
		(mid 211.097492 137.713975)
		(end 210.991426 137.75791)
		(width 0.09)
		(layer "In9.Cu")
		(net 111)
	)
	(arc
		(start 210.900357 137.848979)
		(mid 210.79429 137.892913)
		(end 210.688224 137.84898)
		(width 0.09)
		(layer "In9.Cu")
		(net 111)
	)
	(arc
		(start 211.627824 138.182176)
		(mid 211.521757 138.13824)
		(end 211.415691 138.182175)
		(width 0.09)
		(layer "In9.Cu")
		(net 111)
	)
	(arc
		(start 211.203558 137.970042)
		(mid 211.247492 137.863976)
		(end 211.203558 137.75791)
		(width 0.09)
		(layer "In9.Cu")
		(net 111)
	)
	(via
		(at 203.049 150.001)
		(size 0.35)
		(drill 0.15)
		(layers "F.Cu" "B.Cu")
		(remove_unused_layers yes)
		(keep_end_layers yes)
		(zone_layer_connections)
		(net 112)
	)
	(via
		(at 202.1195 153.2555)
		(size 0.35)
		(drill 0.15)
		(layers "F.Cu" "B.Cu")
		(remove_unused_layers yes)
		(keep_end_layers yes)
		(zone_layer_connections)
		(net 112)
	)
	(segment
		(start 202.817 152.769422)
		(end 202.458172 153.12825)
		(width 0.11)
		(layer "B.Cu")
		(net 112)
	)
	(segment
		(start 202.24675 153.12825)
		(end 202.1195 153.2555)
		(width 0.11)
		(layer "B.Cu")
		(net 112)
	)
	(segment
		(start 202.917 151.676)
		(end 202.817 151.776)
		(width 0.11)
		(layer "B.Cu")
		(net 112)
	)
	(segment
		(start 202.817 151.776)
		(end 202.817 152.769422)
		(width 0.11)
		(layer "B.Cu")
		(net 112)
	)
	(segment
		(start 202.917 151.461)
		(end 202.917 151.676)
		(width 0.11)
		(layer "B.Cu")
		(net 112)
	)
	(segment
		(start 202.458172 153.12825)
		(end 202.24675 153.12825)
		(width 0.11)
		(layer "B.Cu")
		(net 112)
	)
	(segment
		(start 202.745 150.589352)
		(end 203.049 150.285352)
		(width 0.09)
		(layer "In4.Cu")
		(net 112)
	)
	(segment
		(start 203.04325 151.345)
		(end 202.9 151.345)
		(width 0.09)
		(layer "In4.Cu")
		(net 112)
	)
	(segment
		(start 201.106751 151.035)
		(end 202.4 151.035)
		(width 0.09)
		(layer "In4.Cu")
		(net 112)
	)
	(segment
		(start 202.745 150.69)
		(end 202.745 150.589352)
		(width 0.09)
		(layer "In4.Cu")
		(net 112)
	)
	(segment
		(start 202.9 151.345)
		(end 201.106751 151.345)
		(width 0.09)
		(layer "In4.Cu")
		(net 112)
	)
	(segment
		(start 202.745 152.63)
		(end 202.745 152.19)
		(width 0.09)
		(layer "In4.Cu")
		(net 112)
	)
	(segment
		(start 203.049 150.285352)
		(end 203.049 150.001)
		(width 0.09)
		(layer "In4.Cu")
		(net 112)
	)
	(segment
		(start 202.1195 153.2555)
		(end 202.745 152.63)
		(width 0.09)
		(layer "In4.Cu")
		(net 112)
	)
	(segment
		(start 202.9 152.035)
		(end 203.04325 152.035)
		(width 0.09)
		(layer "In4.Cu")
		(net 112)
	)
	(arc
		(start 203.04325 152.035)
		(mid 203.287202 151.933952)
		(end 203.38825 151.69)
		(width 0.09)
		(layer "In4.Cu")
		(net 112)
	)
	(arc
		(start 201.106751 151.345)
		(mid 200.997149 151.299602)
		(end 200.951751 151.19)
		(width 0.09)
		(layer "In4.Cu")
		(net 112)
	)
	(arc
		(start 203.38825 151.69)
		(mid 203.287202 151.446048)
		(end 203.04325 151.345)
		(width 0.09)
		(layer "In4.Cu")
		(net 112)
	)
	(arc
		(start 202.4 151.035)
		(mid 202.643952 150.933952)
		(end 202.745 150.69)
		(width 0.09)
		(layer "In4.Cu")
		(net 112)
	)
	(arc
		(start 200.951751 151.19)
		(mid 200.997149 151.080398)
		(end 201.106751 151.035)
		(width 0.09)
		(layer "In4.Cu")
		(net 112)
	)
	(arc
		(start 202.745 152.19)
		(mid 202.790398 152.080398)
		(end 202.9 152.035)
		(width 0.09)
		(layer "In4.Cu")
		(net 112)
	)
	(via
		(at 206.11 133.05)
		(size 0.35)
		(drill 0.15)
		(layers "F.Cu" "B.Cu")
		(remove_unused_layers yes)
		(keep_end_layers yes)
		(zone_layer_connections)
		(net 113)
	)
	(via
		(at 202.967 154.9)
		(size 0.35)
		(drill 0.15)
		(layers "F.Cu" "B.Cu")
		(remove_unused_layers yes)
		(keep_end_layers yes)
		(zone_layer_connections)
		(net 113)
	)
	(segment
		(start 202.817 154.75)
		(end 202.967 154.9)
		(width 0.11)
		(layer "B.Cu")
		(net 113)
	)
	(segment
		(start 202.917 154.171)
		(end 202.917 154.386)
		(width 0.11)
		(layer "B.Cu")
		(net 113)
	)
	(segment
		(start 202.817 154.486)
		(end 202.817 154.75)
		(width 0.11)
		(layer "B.Cu")
		(net 113)
	)
	(segment
		(start 202.917 154.386)
		(end 202.817 154.486)
		(width 0.11)
		(layer "B.Cu")
		(net 113)
	)
	(segment
		(start 206.654851 133.430499)
		(end 206.881512 133.657161)
		(width 0.09)
		(layer "In9.Cu")
		(net 113)
	)
	(segment
		(start 208.211213 138.29)
		(end 208.762271 138.29)
		(width 0.09)
		(layer "In9.Cu")
		(net 113)
	)
	(segment
		(start 206.11 133.05)
		(end 206.11 133.111)
		(width 0.09)
		(layer "In9.Cu")
		(net 113)
	)
	(segment
		(start 207.832573 133.901114)
		(end 206.991113 134.742574)
		(width 0.09)
		(layer "In9.Cu")
		(net 113)
	)
	(segment
		(start 202.812001 152.172351)
		(end 202.812001 154.745001)
		(width 0.09)
		(layer "In9.Cu")
		(net 113)
	)
	(segment
		(start 208.762271 138.98)
		(end 208.66727 138.98)
		(width 0.09)
		(layer "In9.Cu")
		(net 113)
	)
	(segment
		(start 209.047573 137.568786)
		(end 209.047573 137.701214)
		(width 0.09)
		(layer "In9.Cu")
		(net 113)
	)
	(segment
		(start 210.125 143.620648)
		(end 210.125 149.939352)
		(width 0.09)
		(layer "In9.Cu")
		(net 113)
	)
	(segment
		(start 208.125 134.900648)
		(end 208.125 135.800648)
		(width 0.09)
		(layer "In9.Cu")
		(net 113)
	)
	(segment
		(start 208.768787 137.98)
		(end 208.211213 137.98)
		(width 0.09)
		(layer "In9.Cu")
		(net 113)
	)
	(segment
		(start 208.122427 138.068786)
		(end 208.122427 138.201214)
		(width 0.09)
		(layer "In9.Cu")
		(net 113)
	)
	(segment
		(start 208.529352 151.535)
		(end 203.449352 151.535)
		(width 0.09)
		(layer "In9.Cu")
		(net 113)
	)
	(segment
		(start 208.217729 137.29)
		(end 208.768787 137.29)
		(width 0.09)
		(layer "In9.Cu")
		(net 113)
	)
	(segment
		(start 208.585 136.260648)
		(end 208.585 136.66)
		(width 0.09)
		(layer "In9.Cu")
		(net 113)
	)
	(segment
		(start 207.942174 134.717823)
		(end 208.125 134.900648)
		(width 0.09)
		(layer "In9.Cu")
		(net 113)
	)
	(segment
		(start 202.812001 154.745001)
		(end 202.967 154.9)
		(width 0.09)
		(layer "In9.Cu")
		(net 113)
	)
	(segment
		(start 208.135459 137.01454)
		(end 208.135459 137.20773)
		(width 0.09)
		(layer "In9.Cu")
		(net 113)
	)
	(segment
		(start 207.210316 134.961775)
		(end 207.45427 134.717823)
		(width 0.09)
		(layer "In9.Cu")
		(net 113)
	)
	(segment
		(start 208.125 135.800648)
		(end 208.585 136.260648)
		(width 0.09)
		(layer "In9.Cu")
		(net 113)
	)
	(segment
		(start 210.125 149.939352)
		(end 208.529352 151.535)
		(width 0.09)
		(layer "In9.Cu")
		(net 113)
	)
	(segment
		(start 203.449352 151.535)
		(end 202.812001 152.172351)
		(width 0.09)
		(layer "In9.Cu")
		(net 113)
	)
	(segment
		(start 207.832573 133.413209)
		(end 207.832572 133.413209)
		(width 0.09)
		(layer "In9.Cu")
		(net 113)
	)
	(segment
		(start 208.31273 136.93227)
		(end 208.217729 136.93227)
		(width 0.09)
		(layer "In9.Cu")
		(net 113)
	)
	(segment
		(start 207.100714 133.657161)
		(end 207.344668 133.413208)
		(width 0.09)
		(layer "In9.Cu")
		(net 113)
	)
	(segment
		(start 209.034541 138.56227)
		(end 209.034541 138.70773)
		(width 0.09)
		(layer "In9.Cu")
		(net 113)
	)
	(segment
		(start 206.429499 133.430499)
		(end 206.654851 133.430499)
		(width 0.09)
		(layer "In9.Cu")
		(net 113)
	)
	(segment
		(start 206.11 133.111)
		(end 206.429499 133.430499)
		(width 0.09)
		(layer "In9.Cu")
		(net 113)
	)
	(segment
		(start 208.585 142.080648)
		(end 210.125 143.620648)
		(width 0.09)
		(layer "In9.Cu")
		(net 113)
	)
	(segment
		(start 208.585 139.06227)
		(end 208.585 142.080648)
		(width 0.09)
		(layer "In9.Cu")
		(net 113)
	)
	(arc
		(start 209.047573 137.701214)
		(mid 208.965918 137.898345)
		(end 208.768787 137.98)
		(width 0.09)
		(layer "In9.Cu")
		(net 113)
	)
	(arc
		(start 207.45427 134.717823)
		(mid 207.698222 134.616775)
		(end 207.942174 134.717823)
		(width 0.09)
		(layer "In9.Cu")
		(net 113)
	)
	(arc
		(start 206.991114 134.961775)
		(mid 207.100716 135.007174)
		(end 207.210316 134.961775)
		(width 0.09)
		(layer "In9.Cu")
		(net 113)
	)
	(arc
		(start 208.217729 136.93227)
		(mid 208.159555 136.956366)
		(end 208.135459 137.01454)
		(width 0.09)
		(layer "In9.Cu")
		(net 113)
	)
	(arc
		(start 206.991113 134.742574)
		(mid 206.945716 134.852176)
		(end 206.991114 134.961775)
		(width 0.09)
		(layer "In9.Cu")
		(net 113)
	)
	(arc
		(start 208.585 136.66)
		(mid 208.505254 136.852524)
		(end 208.31273 136.93227)
		(width 0.09)
		(layer "In9.Cu")
		(net 113)
	)
	(arc
		(start 208.66727 138.98)
		(mid 208.609096 139.004096)
		(end 208.585 139.06227)
		(width 0.09)
		(layer "In9.Cu")
		(net 113)
	)
	(arc
		(start 208.135459 137.20773)
		(mid 208.159555 137.265904)
		(end 208.217729 137.29)
		(width 0.09)
		(layer "In9.Cu")
		(net 113)
	)
	(arc
		(start 208.122427 138.201214)
		(mid 208.148432 138.263995)
		(end 208.211213 138.29)
		(width 0.09)
		(layer "In9.Cu")
		(net 113)
	)
	(arc
		(start 207.344668 133.413208)
		(mid 207.588621 133.31216)
		(end 207.832573 133.413209)
		(width 0.09)
		(layer "In9.Cu")
		(net 113)
	)
	(arc
		(start 209.034541 138.70773)
		(mid 208.954795 138.900254)
		(end 208.762271 138.98)
		(width 0.09)
		(layer "In9.Cu")
		(net 113)
	)
	(arc
		(start 208.768787 137.29)
		(mid 208.965918 137.371655)
		(end 209.047573 137.568786)
		(width 0.09)
		(layer "In9.Cu")
		(net 113)
	)
	(arc
		(start 207.832572 133.413209)
		(mid 207.933621 133.657161)
		(end 207.832573 133.901114)
		(width 0.09)
		(layer "In9.Cu")
		(net 113)
	)
	(arc
		(start 208.762271 138.29)
		(mid 208.954795 138.369746)
		(end 209.034541 138.56227)
		(width 0.09)
		(layer "In9.Cu")
		(net 113)
	)
	(arc
		(start 208.211213 137.98)
		(mid 208.148432 138.006005)
		(end 208.122427 138.068786)
		(width 0.09)
		(layer "In9.Cu")
		(net 113)
	)
	(arc
		(start 206.881512 133.657161)
		(mid 206.991113 133.702559)
		(end 207.100714 133.657161)
		(width 0.09)
		(layer "In9.Cu")
		(net 113)
	)
	(via
		(at 203.049 149.351)
		(size 0.35)
		(drill 0.15)
		(layers "F.Cu" "B.Cu")
		(remove_unused_layers yes)
		(keep_end_layers yes)
		(zone_layer_connections)
		(net 114)
	)
	(via
		(at 202.1195 152.801)
		(size 0.35)
		(drill 0.15)
		(layers "F.Cu" "B.Cu")
		(remove_unused_layers yes)
		(keep_end_layers yes)
		(zone_layer_connections)
		(net 114)
	)
	(segment
		(start 202.24675 152.92825)
		(end 202.1195 152.801)
		(width 0.11)
		(layer "B.Cu")
		(net 114)
	)
	(segment
		(start 202.375328 152.92825)
		(end 202.24675 152.92825)
		(width 0.11)
		(layer "B.Cu")
		(net 114)
	)
	(segment
		(start 202.617 151.776)
		(end 202.617 152.686578)
		(width 0.11)
		(layer "B.Cu")
		(net 114)
	)
	(segment
		(start 202.617 152.686578)
		(end 202.375328 152.92825)
		(width 0.11)
		(layer "B.Cu")
		(net 114)
	)
	(segment
		(start 202.517 151.676)
		(end 202.617 151.776)
		(width 0.11)
		(layer "B.Cu")
		(net 114)
	)
	(segment
		(start 202.517 151.461)
		(end 202.517 151.676)
		(width 0.11)
		(layer "B.Cu")
		(net 114)
	)
	(segment
		(start 201.106751 151.535)
		(end 203.04325 151.535)
		(width 0.09)
		(layer "In4.Cu")
		(net 114)
	)
	(segment
		(start 202.9 151.845)
		(end 203.04325 151.845)
		(width 0.09)
		(layer "In4.Cu")
		(net 114)
	)
	(segment
		(start 202.555 150.69)
		(end 202.555 150.510648)
		(width 0.09)
		(layer "In4.Cu")
		(net 114)
	)
	(segment
		(start 202.1195 152.801)
		(end 202.305299 152.801)
		(width 0.09)
		(layer "In4.Cu")
		(net 114)
	)
	(segment
		(start 203.049 149.548451)
		(end 203.049 149.351)
		(width 0.09)
		(layer "In4.Cu")
		(net 114)
	)
	(segment
		(start 202.729 150.336648)
		(end 202.729 149.868451)
		(width 0.09)
		(layer "In4.Cu")
		(net 114)
	)
	(segment
		(start 202.305299 152.801)
		(end 202.555 152.551299)
		(width 0.09)
		(layer "In4.Cu")
		(net 114)
	)
	(segment
		(start 202.729 149.868451)
		(end 203.049 149.548451)
		(width 0.09)
		(layer "In4.Cu")
		(net 114)
	)
	(segment
		(start 202.555 150.510648)
		(end 202.729 150.336648)
		(width 0.09)
		(layer "In4.Cu")
		(net 114)
	)
	(segment
		(start 202.555 152.551299)
		(end 202.555 152.19)
		(width 0.09)
		(layer "In4.Cu")
		(net 114)
	)
	(segment
		(start 201.106751 150.845)
		(end 202.4 150.845)
		(width 0.09)
		(layer "In4.Cu")
		(net 114)
	)
	(arc
		(start 201.106751 151.535)
		(mid 200.862799 151.433952)
		(end 200.761751 151.19)
		(width 0.09)
		(layer "In4.Cu")
		(net 114)
	)
	(arc
		(start 203.19825 151.69)
		(mid 203.152852 151.580398)
		(end 203.04325 151.535)
		(width 0.09)
		(layer "In4.Cu")
		(net 114)
	)
	(arc
		(start 202.555 152.19)
		(mid 202.656048 151.946048)
		(end 202.9 151.845)
		(width 0.09)
		(layer "In4.Cu")
		(net 114)
	)
	(arc
		(start 202.4 150.845)
		(mid 202.509602 150.799602)
		(end 202.555 150.69)
		(width 0.09)
		(layer "In4.Cu")
		(net 114)
	)
	(arc
		(start 200.761751 151.19)
		(mid 200.862799 150.946048)
		(end 201.106751 150.845)
		(width 0.09)
		(layer "In4.Cu")
		(net 114)
	)
	(arc
		(start 203.04325 151.845)
		(mid 203.152852 151.799602)
		(end 203.19825 151.69)
		(width 0.09)
		(layer "In4.Cu")
		(net 114)
	)
	(via
		(at 206.13 133.94)
		(size 0.35)
		(drill 0.15)
		(layers "F.Cu" "B.Cu")
		(remove_unused_layers yes)
		(keep_end_layers yes)
		(zone_layer_connections)
		(net 115)
	)
	(via
		(at 202.467 154.9)
		(size 0.35)
		(drill 0.15)
		(layers "F.Cu" "B.Cu")
		(remove_unused_layers yes)
		(keep_end_layers yes)
		(zone_layer_connections)
		(net 115)
	)
	(segment
		(start 202.517 154.171)
		(end 202.517 154.386)
		(width 0.11)
		(layer "B.Cu")
		(net 115)
	)
	(segment
		(start 202.617 154.486)
		(end 202.617 154.75)
		(width 0.11)
		(layer "B.Cu")
		(net 115)
	)
	(segment
		(start 202.617 154.75)
		(end 202.467 154.9)
		(width 0.11)
		(layer "B.Cu")
		(net 115)
	)
	(segment
		(start 202.517 154.386)
		(end 202.617 154.486)
		(width 0.11)
		(layer "B.Cu")
		(net 115)
	)
	(segment
		(start 207.945459 137.01454)
		(end 207.945459 137.20773)
		(width 0.09)
		(layer "In9.Cu")
		(net 115)
	)
	(segment
		(start 207.932427 138.068786)
		(end 207.932427 138.201214)
		(width 0.09)
		(layer "In9.Cu")
		(net 115)
	)
	(segment
		(start 206.856763 135.096126)
		(end 206.856764 135.096128)
		(width 0.09)
		(layer "In9.Cu")
		(net 115)
	)
	(segment
		(start 209.305336 143.317176)
		(end 209.305337 143.317175)
		(width 0.09)
		(layer "In9.Cu")
		(net 115)
	)
	(segment
		(start 209.057848 143.069688)
		(end 209.057847 143.069689)
		(width 0.09)
		(layer "In9.Cu")
		(net 115)
	)
	(segment
		(start 206.429499 133.620501)
		(end 206.576149 133.620501)
		(width 0.09)
		(layer "In9.Cu")
		(net 115)
	)
	(segment
		(start 206.185 133.865)
		(end 206.429499 133.620501)
		(width 0.09)
		(layer "In9.Cu")
		(net 115)
	)
	(segment
		(start 207.235066 133.791513)
		(end 207.47902 133.54756)
		(width 0.09)
		(layer "In9.Cu")
		(net 115)
	)
	(segment
		(start 206.576149 133.620501)
		(end 206.747161 133.791514)
		(width 0.09)
		(layer "In9.Cu")
		(net 115)
	)
	(segment
		(start 208.857573 137.568786)
		(end 208.857573 137.701214)
		(width 0.09)
		(layer "In9.Cu")
		(net 115)
	)
	(segment
		(start 207.807823 134.852174)
		(end 207.935 134.979352)
		(width 0.09)
		(layer "In9.Cu")
		(net 115)
	)
	(segment
		(start 203.370648 151.345)
		(end 202.621999 152.093649)
		(width 0.09)
		(layer "In9.Cu")
		(net 115)
	)
	(segment
		(start 206.13 133.94)
		(end 206.185 133.885)
		(width 0.09)
		(layer "In9.Cu")
		(net 115)
	)
	(segment
		(start 209.935 143.699352)
		(end 209.935 149.860648)
		(width 0.09)
		(layer "In9.Cu")
		(net 115)
	)
	(segment
		(start 208.211213 138.48)
		(end 208.762271 138.48)
		(width 0.09)
		(layer "In9.Cu")
		(net 115)
	)
	(segment
		(start 208.395 136.339352)
		(end 208.395 136.66)
		(width 0.09)
		(layer "In9.Cu")
		(net 115)
	)
	(segment
		(start 208.31273 136.74227)
		(end 208.217729 136.74227)
		(width 0.09)
		(layer "In9.Cu")
		(net 115)
	)
	(segment
		(start 208.768787 137.79)
		(end 208.211213 137.79)
		(width 0.09)
		(layer "In9.Cu")
		(net 115)
	)
	(segment
		(start 208.395 139.06227)
		(end 208.395 142.159352)
		(width 0.09)
		(layer "In9.Cu")
		(net 115)
	)
	(segment
		(start 207.935 134.979352)
		(end 207.935 135.879352)
		(width 0.09)
		(layer "In9.Cu")
		(net 115)
	)
	(segment
		(start 209.552824 143.317176)
		(end 209.935 143.699352)
		(width 0.09)
		(layer "In9.Cu")
		(net 115)
	)
	(segment
		(start 207.344669 135.096127)
		(end 207.588621 134.852174)
		(width 0.09)
		(layer "In9.Cu")
		(net 115)
	)
	(segment
		(start 202.621999 152.093649)
		(end 202.621999 154.745001)
		(width 0.09)
		(layer "In9.Cu")
		(net 115)
	)
	(segment
		(start 209.935 149.860648)
		(end 208.450648 151.345)
		(width 0.09)
		(layer "In9.Cu")
		(net 115)
	)
	(segment
		(start 207.698221 133.547561)
		(end 207.69822 133.547561)
		(width 0.09)
		(layer "In9.Cu")
		(net 115)
	)
	(segment
		(start 208.762271 138.79)
		(end 208.66727 138.79)
		(width 0.09)
		(layer "In9.Cu")
		(net 115)
	)
	(segment
		(start 206.185 133.885)
		(end 206.185 133.865)
		(width 0.09)
		(layer "In9.Cu")
		(net 115)
	)
	(segment
		(start 202.621999 154.745001)
		(end 202.467 154.9)
		(width 0.09)
		(layer "In9.Cu")
		(net 115)
	)
	(segment
		(start 208.844541 138.56227)
		(end 208.844541 138.70773)
		(width 0.09)
		(layer "In9.Cu")
		(net 115)
	)
	(segment
		(start 207.698221 133.766762)
		(end 206.856762 134.608221)
		(width 0.09)
		(layer "In9.Cu")
		(net 115)
	)
	(segment
		(start 208.450648 151.345)
		(end 203.370648 151.345)
		(width 0.09)
		(layer "In9.Cu")
		(net 115)
	)
	(segment
		(start 207.935 135.879352)
		(end 208.395 136.339352)
		(width 0.09)
		(layer "In9.Cu")
		(net 115)
	)
	(segment
		(start 209.057849 142.822201)
		(end 209.057848 142.8222)
		(width 0.09)
		(layer "In9.Cu")
		(net 115)
	)
	(segment
		(start 208.217729 137.48)
		(end 208.768787 137.48)
		(width 0.09)
		(layer "In9.Cu")
		(net 115)
	)
	(segment
		(start 208.395 142.159352)
		(end 209.057849 142.822201)
		(width 0.09)
		(layer "In9.Cu")
		(net 115)
	)
	(arc
		(start 206.856764 135.096128)
		(mid 207.100716 135.197175)
		(end 207.344669 135.096127)
		(width 0.09)
		(layer "In9.Cu")
		(net 115)
	)
	(arc
		(start 208.66727 138.79)
		(mid 208.474746 138.869746)
		(end 208.395 139.06227)
		(width 0.09)
		(layer "In9.Cu")
		(net 115)
	)
	(arc
		(start 207.945459 137.20773)
		(mid 208.025205 137.400254)
		(end 208.217729 137.48)
		(width 0.09)
		(layer "In9.Cu")
		(net 115)
	)
	(arc
		(start 206.747161 133.791514)
		(mid 206.991114 133.892562)
		(end 207.235066 133.791513)
		(width 0.09)
		(layer "In9.Cu")
		(net 115)
	)
	(arc
		(start 209.057848 142.8222)
		(mid 209.109104 142.945944)
		(end 209.057848 143.069688)
		(width 0.09)
		(layer "In9.Cu")
		(net 115)
	)
	(arc
		(start 208.844541 138.70773)
		(mid 208.820445 138.765904)
		(end 208.762271 138.79)
		(width 0.09)
		(layer "In9.Cu")
		(net 115)
	)
	(arc
		(start 208.762271 138.48)
		(mid 208.820445 138.504096)
		(end 208.844541 138.56227)
		(width 0.09)
		(layer "In9.Cu")
		(net 115)
	)
	(arc
		(start 208.395 136.66)
		(mid 208.370904 136.718174)
		(end 208.31273 136.74227)
		(width 0.09)
		(layer "In9.Cu")
		(net 115)
	)
	(arc
		(start 209.057847 143.069689)
		(mid 209.006591 143.193433)
		(end 209.057848 143.317176)
		(width 0.09)
		(layer "In9.Cu")
		(net 115)
	)
	(arc
		(start 208.768787 137.48)
		(mid 208.831568 137.506005)
		(end 208.857573 137.568786)
		(width 0.09)
		(layer "In9.Cu")
		(net 115)
	)
	(arc
		(start 208.857573 137.701214)
		(mid 208.831568 137.763995)
		(end 208.768787 137.79)
		(width 0.09)
		(layer "In9.Cu")
		(net 115)
	)
	(arc
		(start 209.305337 143.317175)
		(mid 209.429081 143.265919)
		(end 209.552824 143.317176)
		(width 0.09)
		(layer "In9.Cu")
		(net 115)
	)
	(arc
		(start 207.932427 138.201214)
		(mid 208.014082 138.398345)
		(end 208.211213 138.48)
		(width 0.09)
		(layer "In9.Cu")
		(net 115)
	)
	(arc
		(start 209.057848 143.317176)
		(mid 209.181592 143.368432)
		(end 209.305336 143.317176)
		(width 0.09)
		(layer "In9.Cu")
		(net 115)
	)
	(arc
		(start 208.217729 136.74227)
		(mid 208.025205 136.822016)
		(end 207.945459 137.01454)
		(width 0.09)
		(layer "In9.Cu")
		(net 115)
	)
	(arc
		(start 207.588621 134.852174)
		(mid 207.698223 134.806777)
		(end 207.807823 134.852174)
		(width 0.09)
		(layer "In9.Cu")
		(net 115)
	)
	(arc
		(start 207.69822 133.547561)
		(mid 207.743619 133.657161)
		(end 207.698221 133.766762)
		(width 0.09)
		(layer "In9.Cu")
		(net 115)
	)
	(arc
		(start 206.856762 134.608221)
		(mid 206.755715 134.852175)
		(end 206.856763 135.096126)
		(width 0.09)
		(layer "In9.Cu")
		(net 115)
	)
	(arc
		(start 207.47902 133.54756)
		(mid 207.588621 133.502162)
		(end 207.698221 133.547561)
		(width 0.09)
		(layer "In9.Cu")
		(net 115)
	)
	(arc
		(start 208.211213 137.79)
		(mid 208.014082 137.871655)
		(end 207.932427 138.068786)
		(width 0.09)
		(layer "In9.Cu")
		(net 115)
	)
	(via
		(at 200.9245 153.2555)
		(size 0.35)
		(drill 0.15)
		(layers "F.Cu" "B.Cu")
		(remove_unused_layers yes)
		(keep_end_layers yes)
		(zone_layer_connections)
		(net 116)
	)
	(via
		(at 200.449 150.001)
		(size 0.35)
		(drill 0.15)
		(layers "F.Cu" "B.Cu")
		(remove_unused_layers yes)
		(keep_end_layers yes)
		(zone_layer_connections)
		(net 116)
	)
	(segment
		(start 201.722 151.676)
		(end 201.622 151.776)
		(width 0.11)
		(layer "B.Cu")
		(net 116)
	)
	(segment
		(start 201.05175 153.12825)
		(end 200.9245 153.2555)
		(width 0.11)
		(layer "B.Cu")
		(net 116)
	)
	(segment
		(start 201.263172 153.12825)
		(end 201.05175 153.12825)
		(width 0.11)
		(layer "B.Cu")
		(net 116)
	)
	(segment
		(start 201.622 151.776)
		(end 201.622 152.769422)
		(width 0.11)
		(layer "B.Cu")
		(net 116)
	)
	(segment
		(start 201.622 152.769422)
		(end 201.263172 153.12825)
		(width 0.11)
		(layer "B.Cu")
		(net 116)
	)
	(segment
		(start 201.722 151.461)
		(end 201.722 151.676)
		(width 0.11)
		(layer "B.Cu")
		(net 116)
	)
	(segment
		(start 199.825 152.172151)
		(end 199.825 152.594411)
		(width 0.09)
		(layer "In2.Cu")
		(net 116)
	)
	(segment
		(start 201.345 151.660648)
		(end 201.249937 151.755711)
		(width 0.09)
		(layer "In2.Cu")
		(net 116)
	)
	(segment
		(start 201.047492 150.795)
		(end 201.209227 150.795)
		(width 0.09)
		(layer "In2.Cu")
		(net 116)
	)
	(segment
		(start 200.537456 151.263615)
		(end 200.976782 150.824289)
		(width 0.09)
		(layer "In2.Cu")
		(net 116)
	)
	(segment
		(start 200.305 150.211055)
		(end 200.305 150.21489)
		(width 0.09)
		(layer "In2.Cu")
		(net 116)
	)
	(segment
		(start 200.215428 151.345)
		(end 200.340975 151.345)
		(width 0.09)
		(layer "In2.Cu")
		(net 116)
	)
	(segment
		(start 201.345 151.52)
		(end 201.345 151.660648)
		(width 0.09)
		(layer "In2.Cu")
		(net 116)
	)
	(segment
		(start 201.145 151.22)
		(end 201.145 151.32)
		(width 0.09)
		(layer "In2.Cu")
		(net 116)
	)
	(segment
		(start 201.279938 150.82429)
		(end 201.315711 150.860063)
		(width 0.09)
		(layer "In2.Cu")
		(net 116)
	)
	(segment
		(start 201.345 150.930773)
		(end 201.345 151.02)
		(width 0.09)
		(layer "In2.Cu")
		(net 116)
	)
	(segment
		(start 200.821541 153.152541)
		(end 200.9245 153.2555)
		(width 0.09)
		(layer "In2.Cu")
		(net 116)
	)
	(segment
		(start 199.915391 151.139743)
		(end 200.053629 151.277981)
		(width 0.09)
		(layer "In2.Cu")
		(net 116)
	)
	(segment
		(start 199.845 150.813844)
		(end 199.845 150.969804)
		(width 0.09)
		(layer "In2.Cu")
		(net 116)
	)
	(segment
		(start 201.179227 151.785)
		(end 200.200714 151.785)
		(width 0.09)
		(layer "In2.Cu")
		(net 116)
	)
	(segment
		(start 200.461317 150.013317)
		(end 200.334289 150.140345)
		(width 0.09)
		(layer "In2.Cu")
		(net 116)
	)
	(segment
		(start 200.031673 151.855019)
		(end 199.903106 151.983586)
		(width 0.09)
		(layer "In2.Cu")
		(net 116)
	)
	(segment
		(start 199.898931 152.772896)
		(end 200.157595 153.03156)
		(width 0.09)
		(layer "In2.Cu")
		(net 116)
	)
	(segment
		(start 200.461317 150.013317)
		(end 200.449 150.001)
		(width 0.11)
		(layer "In2.Cu")
		(net 116)
	)
	(segment
		(start 200.27571 150.285601)
		(end 199.913966 150.647345)
		(width 0.09)
		(layer "In2.Cu")
		(net 116)
	)
	(segment
		(start 200.378957 153.123251)
		(end 200.75083 153.123251)
		(width 0.09)
		(layer "In2.Cu")
		(net 116)
	)
	(arc
		(start 199.898931 152.772896)
		(mid 199.844214 152.691006)
		(end 199.825 152.594411)
		(width 0.09)
		(layer "In2.Cu")
		(net 116)
	)
	(arc
		(start 201.279938 150.82429)
		(mid 201.247496 150.802612)
		(end 201.209227 150.795)
		(width 0.09)
		(layer "In2.Cu")
		(net 116)
	)
	(arc
		(start 200.031673 151.855019)
		(mid 200.10923 151.803197)
		(end 200.200714 151.785)
		(width 0.09)
		(layer "In2.Cu")
		(net 116)
	)
	(arc
		(start 201.249937 151.755711)
		(mid 201.217495 151.777388)
		(end 201.179227 151.785)
		(width 0.09)
		(layer "In2.Cu")
		(net 116)
	)
	(arc
		(start 201.345 151.02)
		(mid 201.315711 151.090711)
		(end 201.245 151.12)
		(width 0.09)
		(layer "In2.Cu")
		(net 116)
	)
	(arc
		(start 200.305 150.211055)
		(mid 200.312612 150.172787)
		(end 200.334289 150.140345)
		(width 0.09)
		(layer "In2.Cu")
		(net 116)
	)
	(arc
		(start 201.245 151.42)
		(mid 201.315711 151.449289)
		(end 201.345 151.52)
		(width 0.09)
		(layer "In2.Cu")
		(net 116)
	)
	(arc
		(start 201.315711 150.860063)
		(mid 201.337388 150.892505)
		(end 201.345 150.930773)
		(width 0.09)
		(layer "In2.Cu")
		(net 116)
	)
	(arc
		(start 200.305 150.21489)
		(mid 200.297388 150.253159)
		(end 200.27571 150.285601)
		(width 0.09)
		(layer "In2.Cu")
		(net 116)
	)
	(arc
		(start 200.537456 151.263615)
		(mid 200.44731 151.323849)
		(end 200.340975 151.345)
		(width 0.09)
		(layer "In2.Cu")
		(net 116)
	)
	(arc
		(start 200.053629 151.277981)
		(mid 200.127863 151.327582)
		(end 200.215428 151.345)
		(width 0.09)
		(layer "In2.Cu")
		(net 116)
	)
	(arc
		(start 200.976782 150.824289)
		(mid 201.009224 150.802612)
		(end 201.047492 150.795)
		(width 0.09)
		(layer "In2.Cu")
		(net 116)
	)
	(arc
		(start 199.845 150.969804)
		(mid 199.863294 151.061774)
		(end 199.915391 151.139743)
		(width 0.09)
		(layer "In2.Cu")
		(net 116)
	)
	(arc
		(start 199.903106 151.983586)
		(mid 199.845299 152.0701)
		(end 199.825 152.172151)
		(width 0.09)
		(layer "In2.Cu")
		(net 116)
	)
	(arc
		(start 200.157595 153.03156)
		(mid 200.259157 153.099421)
		(end 200.378957 153.123251)
		(width 0.09)
		(layer "In2.Cu")
		(net 116)
	)
	(arc
		(start 200.821541 153.152541)
		(mid 200.789099 153.130863)
		(end 200.75083 153.123251)
		(width 0.09)
		(layer "In2.Cu")
		(net 116)
	)
	(arc
		(start 201.145 151.32)
		(mid 201.174289 151.390711)
		(end 201.245 151.42)
		(width 0.09)
		(layer "In2.Cu")
		(net 116)
	)
	(arc
		(start 201.245 151.12)
		(mid 201.174289 151.149289)
		(end 201.145 151.22)
		(width 0.09)
		(layer "In2.Cu")
		(net 116)
	)
	(arc
		(start 199.913966 150.647345)
		(mid 199.862924 150.723735)
		(end 199.845 150.813844)
		(width 0.09)
		(layer "In2.Cu")
		(net 116)
	)
	(segment
		(start 223.959 146.060284)
		(end 223.959 143.959)
		(width 0.09)
		(layer "F.Cu")
		(net 117)
	)
	(segment
		(start 224.45 146.227)
		(end 224.125716 146.227)
		(width 0.09)
		(layer "F.Cu")
		(net 117)
	)
	(segment
		(start 225.4015 147.817)
		(end 225.2165 147.632)
		(width 0.09)
		(layer "F.Cu")
		(net 117)
	)
	(segment
		(start 223.959 143.959)
		(end 223.88 143.88)
		(width 0.09)
		(layer "F.Cu")
		(net 117)
	)
	(segment
		(start 225.2165 147.632)
		(end 225.2165 146.9935)
		(width 0.09)
		(layer "F.Cu")
		(net 117)
	)
	(segment
		(start 225.2165 146.9935)
		(end 224.45 146.227)
		(width 0.09)
		(layer "F.Cu")
		(net 117)
	)
	(segment
		(start 224.125716 146.227)
		(end 223.959 146.060284)
		(width 0.09)
		(layer "F.Cu")
		(net 117)
	)
	(via
		(at 223.88 143.88)
		(size 0.35)
		(drill 0.15)
		(layers "F.Cu" "B.Cu")
		(remove_unused_layers yes)
		(keep_end_layers yes)
		(zone_layer_connections)
		(net 117)
	)
	(via
		(at 201.772 154.9)
		(size 0.35)
		(drill 0.15)
		(layers "F.Cu" "B.Cu")
		(remove_unused_layers yes)
		(keep_end_layers yes)
		(zone_layer_connections)
		(net 118)
	)
	(via
		(at 205.3 134.74)
		(size 0.35)
		(drill 0.15)
		(layers "F.Cu" "B.Cu")
		(remove_unused_layers yes)
		(keep_end_layers yes)
		(zone_layer_connections)
		(net 118)
	)
	(segment
		(start 201.622 154.75)
		(end 201.772 154.9)
		(width 0.11)
		(layer "B.Cu")
		(net 118)
	)
	(segment
		(start 201.722 154.386)
		(end 201.622 154.486)
		(width 0.11)
		(layer "B.Cu")
		(net 118)
	)
	(segment
		(start 201.722 154.171)
		(end 201.722 154.386)
		(width 0.11)
		(layer "B.Cu")
		(net 118)
	)
	(segment
		(start 201.622 154.486)
		(end 201.622 154.75)
		(width 0.11)
		(layer "B.Cu")
		(net 118)
	)
	(segment
		(start 201.617001 151.717351)
		(end 201.617001 154.745001)
		(width 0.09)
		(layer "In9.Cu")
		(net 118)
	)
	(segment
		(start 206.939352 135.845)
		(end 207.61 136.515648)
		(width 0.09)
		(layer "In9.Cu")
		(net 118)
	)
	(segment
		(start 207.81938 141.3)
		(end 207.158091 141.3)
		(width 0.09)
		(layer "In9.Cu")
		(net 118)
	)
	(segment
		(start 202.309352 151.025)
		(end 201.617001 151.717351)
		(width 0.09)
		(layer "In9.Cu")
		(net 118)
	)
	(segment
		(start 204.635 134.609352)
		(end 204.635 135.470648)
		(width 0.09)
		(layer "In9.Cu")
		(net 118)
	)
	(segment
		(start 208.522176 142.83427)
		(end 208.522176 142.834269)
		(width 0.09)
		(layer "In9.Cu")
		(net 118)
	)
	(segment
		(start 207.036183 139.221908)
		(end 207.036183 139.308092)
		(width 0.09)
		(layer "In9.Cu")
		(net 118)
	)
	(segment
		(start 208.695 149.689352)
		(end 208.039352 150.345)
		(width 0.09)
		(layer "In9.Cu")
		(net 118)
	)
	(segment
		(start 207.268092 139.1)
		(end 207.158091 139.1)
		(width 0.09)
		(layer "In9.Cu")
		(net 118)
	)
	(segment
		(start 206.539352 150.345)
		(end 205.859352 151.025)
		(width 0.09)
		(layer "In9.Cu")
		(net 118)
	)
	(segment
		(start 207.61 136.515648)
		(end 207.61 138.758092)
		(width 0.09)
		(layer "In9.Cu")
		(net 118)
	)
	(segment
		(start 201.617001 154.745001)
		(end 201.772 154.9)
		(width 0.09)
		(layer "In9.Cu")
		(net 118)
	)
	(segment
		(start 208.695 143.360648)
		(end 208.695 149.689352)
		(width 0.09)
		(layer "In9.Cu")
		(net 118)
	)
	(segment
		(start 207.15561 140.53)
		(end 207.81938 140.53)
		(width 0.09)
		(layer "In9.Cu")
		(net 118)
	)
	(segment
		(start 207.158091 139.43)
		(end 207.81938 139.43)
		(width 0.09)
		(layer "In9.Cu")
		(net 118)
	)
	(segment
		(start 205.009352 135.845)
		(end 206.939352 135.845)
		(width 0.09)
		(layer "In9.Cu")
		(net 118)
	)
	(segment
		(start 207.61 141.99)
		(end 207.61 142.275648)
		(width 0.09)
		(layer "In9.Cu")
		(net 118)
	)
	(segment
		(start 208.138759 140.849379)
		(end 208.138759 140.980621)
		(width 0.09)
		(layer "In9.Cu")
		(net 118)
	)
	(segment
		(start 207.036183 141.421908)
		(end 207.036183 141.526184)
		(width 0.09)
		(layer "In9.Cu")
		(net 118)
	)
	(segment
		(start 205.29 134.74)
		(end 204.995001 134.445001)
		(width 0.09)
		(layer "In9.Cu")
		(net 118)
	)
	(segment
		(start 205.3 134.74)
		(end 205.29 134.74)
		(width 0.09)
		(layer "In9.Cu")
		(net 118)
	)
	(segment
		(start 204.635 135.470648)
		(end 205.009352 135.845)
		(width 0.09)
		(layer "In9.Cu")
		(net 118)
	)
	(segment
		(start 208.324186 142.813056)
		(end 208.324185 142.813057)
		(width 0.09)
		(layer "In9.Cu")
		(net 118)
	)
	(segment
		(start 207.158091 141.648092)
		(end 207.268092 141.648092)
		(width 0.09)
		(layer "In9.Cu")
		(net 118)
	)
	(segment
		(start 204.799351 134.445001)
		(end 204.635 134.609352)
		(width 0.09)
		(layer "In9.Cu")
		(net 118)
	)
	(segment
		(start 208.138759 139.749379)
		(end 208.138759 139.880621)
		(width 0.09)
		(layer "In9.Cu")
		(net 118)
	)
	(segment
		(start 208.039352 150.345)
		(end 206.539352 150.345)
		(width 0.09)
		(layer "In9.Cu")
		(net 118)
	)
	(segment
		(start 207.61 142.275648)
		(end 208.147409 142.813056)
		(width 0.09)
		(layer "In9.Cu")
		(net 118)
	)
	(segment
		(start 207.81938 140.2)
		(end 207.15561 140.2)
		(width 0.09)
		(layer "In9.Cu")
		(net 118)
	)
	(segment
		(start 204.995001 134.445001)
		(end 204.799351 134.445001)
		(width 0.09)
		(layer "In9.Cu")
		(net 118)
	)
	(segment
		(start 208.522176 143.011047)
		(end 208.522175 143.011047)
		(width 0.09)
		(layer "In9.Cu")
		(net 118)
	)
	(segment
		(start 205.859352 151.025)
		(end 202.309352 151.025)
		(width 0.09)
		(layer "In9.Cu")
		(net 118)
	)
	(segment
		(start 208.147409 142.813056)
		(end 208.147408 142.813056)
		(width 0.09)
		(layer "In9.Cu")
		(net 118)
	)
	(segment
		(start 207.03122 140.32439)
		(end 207.03122 140.40561)
		(width 0.09)
		(layer "In9.Cu")
		(net 118)
	)
	(segment
		(start 208.522176 143.187824)
		(end 208.695 143.360648)
		(width 0.09)
		(layer "In9.Cu")
		(net 118)
	)
	(segment
		(start 208.500962 142.813056)
		(end 208.522176 142.83427)
		(width 0.09)
		(layer "In9.Cu")
		(net 118)
	)
	(arc
		(start 208.522176 142.834269)
		(mid 208.558788 142.922658)
		(end 208.522176 143.011047)
		(width 0.09)
		(layer "In9.Cu")
		(net 118)
	)
	(arc
		(start 207.268092 141.648092)
		(mid 207.509857 141.748235)
		(end 207.61 141.99)
		(width 0.09)
		(layer "In9.Cu")
		(net 118)
	)
	(arc
		(start 208.324185 142.813057)
		(mid 208.412573 142.776445)
		(end 208.500962 142.813056)
		(width 0.09)
		(layer "In9.Cu")
		(net 118)
	)
	(arc
		(start 207.158091 141.3)
		(mid 207.071889 141.335706)
		(end 207.036183 141.421908)
		(width 0.09)
		(layer "In9.Cu")
		(net 118)
	)
	(arc
		(start 207.036183 141.526184)
		(mid 207.071889 141.612386)
		(end 207.158091 141.648092)
		(width 0.09)
		(layer "In9.Cu")
		(net 118)
	)
	(arc
		(start 207.158091 139.1)
		(mid 207.071889 139.135706)
		(end 207.036183 139.221908)
		(width 0.09)
		(layer "In9.Cu")
		(net 118)
	)
	(arc
		(start 207.15561 140.2)
		(mid 207.067653 140.236433)
		(end 207.03122 140.32439)
		(width 0.09)
		(layer "In9.Cu")
		(net 118)
	)
	(arc
		(start 208.147408 142.813056)
		(mid 208.235797 142.849668)
		(end 208.324186 142.813056)
		(width 0.09)
		(layer "In9.Cu")
		(net 118)
	)
	(arc
		(start 208.138759 140.980621)
		(mid 208.045215 141.206456)
		(end 207.81938 141.3)
		(width 0.09)
		(layer "In9.Cu")
		(net 118)
	)
	(arc
		(start 207.81938 139.43)
		(mid 208.045215 139.523544)
		(end 208.138759 139.749379)
		(width 0.09)
		(layer "In9.Cu")
		(net 118)
	)
	(arc
		(start 208.138759 139.880621)
		(mid 208.045215 140.106456)
		(end 207.81938 140.2)
		(width 0.09)
		(layer "In9.Cu")
		(net 118)
	)
	(arc
		(start 207.61 138.758092)
		(mid 207.509857 138.999857)
		(end 207.268092 139.1)
		(width 0.09)
		(layer "In9.Cu")
		(net 118)
	)
	(arc
		(start 208.522175 143.011047)
		(mid 208.485564 143.099436)
		(end 208.522176 143.187824)
		(width 0.09)
		(layer "In9.Cu")
		(net 118)
	)
	(arc
		(start 207.036183 139.308092)
		(mid 207.071889 139.394294)
		(end 207.158091 139.43)
		(width 0.09)
		(layer "In9.Cu")
		(net 118)
	)
	(arc
		(start 207.81938 140.53)
		(mid 208.045215 140.623544)
		(end 208.138759 140.849379)
		(width 0.09)
		(layer "In9.Cu")
		(net 118)
	)
	(arc
		(start 207.03122 140.40561)
		(mid 207.067653 140.493567)
		(end 207.15561 140.53)
		(width 0.09)
		(layer "In9.Cu")
		(net 118)
	)
	(via
		(at 200.449 149.351)
		(size 0.35)
		(drill 0.15)
		(layers "F.Cu" "B.Cu")
		(remove_unused_layers yes)
		(keep_end_layers yes)
		(zone_layer_connections)
		(net 119)
	)
	(via
		(at 200.9245 152.801)
		(size 0.35)
		(drill 0.15)
		(layers "F.Cu" "B.Cu")
		(remove_unused_layers yes)
		(keep_end_layers yes)
		(zone_layer_connections)
		(net 119)
	)
	(segment
		(start 201.180328 152.92825)
		(end 201.05175 152.92825)
		(width 0.11)
		(layer "B.Cu")
		(net 119)
	)
	(segment
		(start 201.422 151.776)
		(end 201.422 152.686578)
		(width 0.11)
		(layer "B.Cu")
		(net 119)
	)
	(segment
		(start 201.422 152.686578)
		(end 201.180328 152.92825)
		(width 0.11)
		(layer "B.Cu")
		(net 119)
	)
	(segment
		(start 201.322 151.676)
		(end 201.422 151.776)
		(width 0.11)
		(layer "B.Cu")
		(net 119)
	)
	(segment
		(start 201.05175 152.92825)
		(end 200.9245 152.801)
		(width 0.11)
		(layer "B.Cu")
		(net 119)
	)
	(segment
		(start 201.322 151.461)
		(end 201.322 151.676)
		(width 0.11)
		(layer "B.Cu")
		(net 119)
	)
	(segment
		(start 200.406657 151.12571)
		(end 200.855558 150.676809)
		(width 0.09)
		(layer "In2.Cu")
		(net 119)
	)
	(segment
		(start 201.1815 151.975)
		(end 200.221817 151.975)
		(width 0.09)
		(layer "In2.Cu")
		(net 119)
	)
	(segment
		(start 200.369409 152.933249)
		(end 200.75083 152.933249)
		(width 0.09)
		(layer "In2.Cu")
		(net 119)
	)
	(segment
		(start 200.035 150.836436)
		(end 200.035 150.949227)
		(width 0.09)
		(layer "In2.Cu")
		(net 119)
	)
	(segment
		(start 201.50571 151.768642)
		(end 201.382685 151.891667)
		(width 0.09)
		(layer "In2.Cu")
		(net 119)
	)
	(segment
		(start 200.821541 152.903959)
		(end 200.9245 152.801)
		(width 0.09)
		(layer "In2.Cu")
		(net 119)
	)
	(segment
		(start 200.04429 152.649551)
		(end 200.298699 152.90396)
		(width 0.09)
		(layer "In2.Cu")
		(net 119)
	)
	(segment
		(start 201.409995 150.685643)
		(end 201.505711 150.781359)
		(width 0.09)
		(layer "In2.Cu")
		(net 119)
	)
	(segment
		(start 200.449 149.351)
		(end 200.744711 149.646711)
		(width 0.09)
		(layer "In2.Cu")
		(net 119)
	)
	(segment
		(start 200.06429 151.019938)
		(end 200.170063 151.125711)
		(width 0.09)
		(layer "In2.Cu")
		(net 119)
	)
	(segment
		(start 200.240773 151.155)
		(end 200.335946 151.155)
		(width 0.09)
		(layer "In2.Cu")
		(net 119)
	)
	(segment
		(start 201.535 150.852069)
		(end 201.535 151.697931)
		(width 0.09)
		(layer "In2.Cu")
		(net 119)
	)
	(segment
		(start 200.015 152.181817)
		(end 200.015 152.57884)
		(width 0.09)
		(layer "In2.Cu")
		(net 119)
	)
	(segment
		(start 200.151106 152.00429)
		(end 200.044289 152.111107)
		(width 0.09)
		(layer "In2.Cu")
		(net 119)
	)
	(segment
		(start 200.453579 150.421691)
		(end 200.449745 150.421691)
		(width 0.09)
		(layer "In2.Cu")
		(net 119)
	)
	(segment
		(start 200.379034 150.450981)
		(end 200.064289 150.765726)
		(width 0.09)
		(layer "In2.Cu")
		(net 119)
	)
	(segment
		(start 200.74471 150.171981)
		(end 200.524289 150.392402)
		(width 0.09)
		(layer "In2.Cu")
		(net 119)
	)
	(segment
		(start 201.02892 150.605)
		(end 201.215304 150.605)
		(width 0.09)
		(layer "In2.Cu")
		(net 119)
	)
	(segment
		(start 200.774 149.717421)
		(end 200.774 150.10127)
		(width 0.09)
		(layer "In2.Cu")
		(net 119)
	)
	(arc
		(start 200.06429 151.019938)
		(mid 200.042612 150.987496)
		(end 200.035 150.949227)
		(width 0.09)
		(layer "In2.Cu")
		(net 119)
	)
	(arc
		(start 201.409995 150.685643)
		(mid 201.32067 150.625958)
		(end 201.215304 150.605)
		(width 0.09)
		(layer "In2.Cu")
		(net 119)
	)
	(arc
		(start 200.524289 150.392402)
		(mid 200.491847 150.414079)
		(end 200.453579 150.421691)
		(width 0.09)
		(layer "In2.Cu")
		(net 119)
	)
	(arc
		(start 200.75083 152.933249)
		(mid 200.789099 152.925637)
		(end 200.821541 152.903959)
		(width 0.09)
		(layer "In2.Cu")
		(net 119)
	)
	(arc
		(start 200.406657 151.12571)
		(mid 200.374215 151.147388)
		(end 200.335946 151.155)
		(width 0.09)
		(layer "In2.Cu")
		(net 119)
	)
	(arc
		(start 200.855558 150.676809)
		(mid 200.935097 150.623663)
		(end 201.02892 150.605)
		(width 0.09)
		(layer "In2.Cu")
		(net 119)
	)
	(arc
		(start 201.1815 151.975)
		(mid 201.29038 151.953342)
		(end 201.382685 151.891667)
		(width 0.09)
		(layer "In2.Cu")
		(net 119)
	)
	(arc
		(start 200.064289 150.765726)
		(mid 200.042612 150.798168)
		(end 200.035 150.836436)
		(width 0.09)
		(layer "In2.Cu")
		(net 119)
	)
	(arc
		(start 200.044289 152.111107)
		(mid 200.022612 152.143549)
		(end 200.015 152.181817)
		(width 0.09)
		(layer "In2.Cu")
		(net 119)
	)
	(arc
		(start 201.505711 150.781359)
		(mid 201.527388 150.813801)
		(end 201.535 150.852069)
		(width 0.09)
		(layer "In2.Cu")
		(net 119)
	)
	(arc
		(start 200.221817 151.975)
		(mid 200.183548 151.982612)
		(end 200.151106 152.00429)
		(width 0.09)
		(layer "In2.Cu")
		(net 119)
	)
	(arc
		(start 200.170063 151.125711)
		(mid 200.202505 151.147388)
		(end 200.240773 151.155)
		(width 0.09)
		(layer "In2.Cu")
		(net 119)
	)
	(arc
		(start 200.298699 152.90396)
		(mid 200.331141 152.925637)
		(end 200.369409 152.933249)
		(width 0.09)
		(layer "In2.Cu")
		(net 119)
	)
	(arc
		(start 200.744711 149.646711)
		(mid 200.766388 149.679153)
		(end 200.774 149.717421)
		(width 0.09)
		(layer "In2.Cu")
		(net 119)
	)
	(arc
		(start 200.74471 150.171981)
		(mid 200.766388 150.139539)
		(end 200.774 150.10127)
		(width 0.09)
		(layer "In2.Cu")
		(net 119)
	)
	(arc
		(start 200.04429 152.649551)
		(mid 200.022612 152.617109)
		(end 200.015 152.57884)
		(width 0.09)
		(layer "In2.Cu")
		(net 119)
	)
	(arc
		(start 200.379034 150.450981)
		(mid 200.411476 150.429303)
		(end 200.449745 150.421691)
		(width 0.09)
		(layer "In2.Cu")
		(net 119)
	)
	(arc
		(start 201.535 151.697931)
		(mid 201.527388 151.7362)
		(end 201.50571 151.768642)
		(width 0.09)
		(layer "In2.Cu")
		(net 119)
	)
	(via
		(at 201.272 154.9)
		(size 0.35)
		(drill 0.15)
		(layers "F.Cu" "B.Cu")
		(remove_unused_layers yes)
		(keep_end_layers yes)
		(zone_layer_connections)
		(net 120)
	)
	(via
		(at 205.28 133.94)
		(size 0.35)
		(drill 0.15)
		(layers "F.Cu" "B.Cu")
		(remove_unused_layers yes)
		(keep_end_layers yes)
		(zone_layer_connections)
		(net 120)
	)
	(segment
		(start 201.422 154.75)
		(end 201.272 154.9)
		(width 0.11)
		(layer "B.Cu")
		(net 120)
	)
	(segment
		(start 201.422 154.486)
		(end 201.422 154.75)
		(width 0.11)
		(layer "B.Cu")
		(net 120)
	)
	(segment
		(start 201.322 154.171)
		(end 201.322 154.386)
		(width 0.11)
		(layer "B.Cu")
		(net 120)
	)
	(segment
		(start 201.322 154.386)
		(end 201.422 154.486)
		(width 0.11)
		(layer "B.Cu")
		(net 120)
	)
	(segment
		(start 206.860648 136.035)
		(end 207.39 136.564352)
		(width 0.09)
		(layer "In9.Cu")
		(net 120)
	)
	(segment
		(start 204.930648 136.035)
		(end 206.860648 136.035)
		(width 0.09)
		(layer "In9.Cu")
		(net 120)
	)
	(segment
		(start 207.918759 140.849379)
		(end 207.918759 140.980621)
		(width 0.09)
		(layer "In9.Cu")
		(net 120)
	)
	(segment
		(start 201.426999 154.745001)
		(end 201.272 154.9)
		(width 0.09)
		(layer "In9.Cu")
		(net 120)
	)
	(segment
		(start 208.505 143.439352)
		(end 208.505 149.610648)
		(width 0.09)
		(layer "In9.Cu")
		(net 120)
	)
	(segment
		(start 207.15561 140.75)
		(end 207.81938 140.75)
		(width 0.09)
		(layer "In9.Cu")
		(net 120)
	)
	(segment
		(start 202.230648 150.835)
		(end 201.426999 151.638649)
		(width 0.09)
		(layer "In9.Cu")
		(net 120)
	)
	(segment
		(start 207.918759 139.749379)
		(end 207.918759 139.880621)
		(width 0.09)
		(layer "In9.Cu")
		(net 120)
	)
	(segment
		(start 206.460648 150.155)
		(end 205.780648 150.835)
		(width 0.09)
		(layer "In9.Cu")
		(net 120)
	)
	(segment
		(start 204.720649 134.254999)
		(end 204.445 134.530648)
		(width 0.09)
		(layer "In9.Cu")
		(net 120)
	)
	(segment
		(start 207.81938 139.98)
		(end 207.15561 139.98)
		(width 0.09)
		(layer "In9.Cu")
		(net 120)
	)
	(segment
		(start 207.39 142.324352)
		(end 208.505 143.439352)
		(width 0.09)
		(layer "In9.Cu")
		(net 120)
	)
	(segment
		(start 207.960648 150.155)
		(end 206.460648 150.155)
		(width 0.09)
		(layer "In9.Cu")
		(net 120)
	)
	(segment
		(start 206.816183 141.421908)
		(end 206.816183 141.526184)
		(width 0.09)
		(layer "In9.Cu")
		(net 120)
	)
	(segment
		(start 204.445 135.549352)
		(end 204.930648 136.035)
		(width 0.09)
		(layer "In9.Cu")
		(net 120)
	)
	(segment
		(start 207.158091 139.65)
		(end 207.81938 139.65)
		(width 0.09)
		(layer "In9.Cu")
		(net 120)
	)
	(segment
		(start 206.816183 139.221908)
		(end 206.816183 139.308092)
		(width 0.09)
		(layer "In9.Cu")
		(net 120)
	)
	(segment
		(start 204.445 134.530648)
		(end 204.445 135.549352)
		(width 0.09)
		(layer "In9.Cu")
		(net 120)
	)
	(segment
		(start 208.505 149.610648)
		(end 207.960648 150.155)
		(width 0.09)
		(layer "In9.Cu")
		(net 120)
	)
	(segment
		(start 207.39 136.564352)
		(end 207.39 138.758092)
		(width 0.09)
		(layer "In9.Cu")
		(net 120)
	)
	(segment
		(start 201.426999 151.638649)
		(end 201.426999 154.745001)
		(width 0.09)
		(layer "In9.Cu")
		(net 120)
	)
	(segment
		(start 207.268092 138.88)
		(end 207.158091 138.88)
		(width 0.09)
		(layer "In9.Cu")
		(net 120)
	)
	(segment
		(start 207.39 141.99)
		(end 207.39 142.324352)
		(width 0.09)
		(layer "In9.Cu")
		(net 120)
	)
	(segment
		(start 205.780648 150.835)
		(end 202.230648 150.835)
		(width 0.09)
		(layer "In9.Cu")
		(net 120)
	)
	(segment
		(start 205.28 133.94)
		(end 205.28 133.97)
		(width 0.09)
		(layer "In9.Cu")
		(net 120)
	)
	(segment
		(start 204.995001 134.254999)
		(end 204.720649 134.254999)
		(width 0.09)
		(layer "In9.Cu")
		(net 120)
	)
	(segment
		(start 205.28 133.97)
		(end 204.995001 134.254999)
		(width 0.09)
		(layer "In9.Cu")
		(net 120)
	)
	(segment
		(start 207.81938 141.08)
		(end 207.158091 141.08)
		(width 0.09)
		(layer "In9.Cu")
		(net 120)
	)
	(segment
		(start 206.81122 140.32439)
		(end 206.81122 140.40561)
		(width 0.09)
		(layer "In9.Cu")
		(net 120)
	)
	(segment
		(start 207.158091 141.868092)
		(end 207.268092 141.868092)
		(width 0.09)
		(layer "In9.Cu")
		(net 120)
	)
	(arc
		(start 207.81938 139.65)
		(mid 207.889652 139.679107)
		(end 207.918759 139.749379)
		(width 0.09)
		(layer "In9.Cu")
		(net 120)
	)
	(arc
		(start 207.158091 138.88)
		(mid 206.916326 138.980143)
		(end 206.816183 139.221908)
		(width 0.09)
		(layer "In9.Cu")
		(net 120)
	)
	(arc
		(start 207.268092 141.868092)
		(mid 207.354294 141.903798)
		(end 207.39 141.99)
		(width 0.09)
		(layer "In9.Cu")
		(net 120)
	)
	(arc
		(start 207.15561 139.98)
		(mid 206.912089 140.080869)
		(end 206.81122 140.32439)
		(width 0.09)
		(layer "In9.Cu")
		(net 120)
	)
	(arc
		(start 206.816183 139.308092)
		(mid 206.916326 139.549857)
		(end 207.158091 139.65)
		(width 0.09)
		(layer "In9.Cu")
		(net 120)
	)
	(arc
		(start 207.918759 140.980621)
		(mid 207.889652 141.050893)
		(end 207.81938 141.08)
		(width 0.09)
		(layer "In9.Cu")
		(net 120)
	)
	(arc
		(start 207.918759 139.880621)
		(mid 207.889652 139.950893)
		(end 207.81938 139.98)
		(width 0.09)
		(layer "In9.Cu")
		(net 120)
	)
	(arc
		(start 207.81938 140.75)
		(mid 207.889652 140.779107)
		(end 207.918759 140.849379)
		(width 0.09)
		(layer "In9.Cu")
		(net 120)
	)
	(arc
		(start 207.158091 141.08)
		(mid 206.916326 141.180143)
		(end 206.816183 141.421908)
		(width 0.09)
		(layer "In9.Cu")
		(net 120)
	)
	(arc
		(start 207.39 138.758092)
		(mid 207.354294 138.844294)
		(end 207.268092 138.88)
		(width 0.09)
		(layer "In9.Cu")
		(net 120)
	)
	(arc
		(start 206.816183 141.526184)
		(mid 206.916326 141.767949)
		(end 207.158091 141.868092)
		(width 0.09)
		(layer "In9.Cu")
		(net 120)
	)
	(arc
		(start 206.81122 140.40561)
		(mid 206.912089 140.649131)
		(end 207.15561 140.75)
		(width 0.09)
		(layer "In9.Cu")
		(net 120)
	)
	(via
		(at 198.899 141.101)
		(size 0.35)
		(drill 0.15)
		(layers "F.Cu" "B.Cu")
		(remove_unused_layers yes)
		(keep_end_layers yes)
		(zone_layer_connections)
		(net 121)
	)
	(via
		(at 199.372 154.9)
		(size 0.35)
		(drill 0.15)
		(layers "F.Cu" "B.Cu")
		(remove_unused_layers yes)
		(keep_end_layers yes)
		(zone_layer_connections)
		(net 121)
	)
	(segment
		(start 199.322 154.171)
		(end 199.322 154.386)
		(width 0.125)
		(layer "B.Cu")
		(net 121)
	)
	(segment
		(start 199.322 154.386)
		(end 199.2295 154.4785)
		(width 0.125)
		(layer "B.Cu")
		(net 121)
	)
	(segment
		(start 199.2295 154.4785)
		(end 199.2295 154.7575)
		(width 0.125)
		(layer "B.Cu")
		(net 121)
	)
	(segment
		(start 199.2295 154.7575)
		(end 199.372 154.9)
		(width 0.125)
		(layer "B.Cu")
		(net 121)
	)
	(segment
		(start 198.975 140.8)
		(end 199.1595 140.8)
		(width 0.1)
		(layer "In4.Cu")
		(net 121)
	)
	(segment
		(start 198.4 148.598578)
		(end 199.222 149.420578)
		(width 0.1)
		(layer "In4.Cu")
		(net 121)
	)
	(segment
		(start 199.244 141.347422)
		(end 198.4 142.191422)
		(width 0.1)
		(layer "In4.Cu")
		(net 121)
	)
	(segment
		(start 199.244 140.8845)
		(end 199.244 141.347422)
		(width 0.1)
		(layer "In4.Cu")
		(net 121)
	)
	(segment
		(start 199.222 154.75)
		(end 199.372 154.9)
		(width 0.1)
		(layer "In4.Cu")
		(net 121)
	)
	(segment
		(start 198.899 141.101)
		(end 198.899 140.876)
		(width 0.1)
		(layer "In4.Cu")
		(net 121)
	)
	(segment
		(start 198.4 142.191422)
		(end 198.4 148.598578)
		(width 0.1)
		(layer "In4.Cu")
		(net 121)
	)
	(segment
		(start 199.222 149.420578)
		(end 199.222 154.75)
		(width 0.1)
		(layer "In4.Cu")
		(net 121)
	)
	(segment
		(start 199.1595 140.8)
		(end 199.244 140.8845)
		(width 0.1)
		(layer "In4.Cu")
		(net 121)
	)
	(segment
		(start 198.899 140.876)
		(end 198.975 140.8)
		(width 0.1)
		(layer "In4.Cu")
		(net 121)
	)
	(segment
		(start 212.205499 147.305501)
		(end 212.342749 147.442751)
		(width 0.09)
		(layer "F.Cu")
		(net 122)
	)
	(segment
		(start 212.642751 147.3)
		(end 212.5 147.442751)
		(width 0.09)
		(layer "F.Cu")
		(net 122)
	)
	(segment
		(start 212.342749 147.442751)
		(end 212.5 147.442751)
		(width 0.09)
		(layer "F.Cu")
		(net 122)
	)
	(segment
		(start 212.927 147.3)
		(end 212.642751 147.3)
		(width 0.09)
		(layer "F.Cu")
		(net 122)
	)
	(via
		(at 212.205499 147.305501)
		(size 0.35)
		(drill 0.15)
		(layers "F.Cu" "B.Cu")
		(remove_unused_layers yes)
		(keep_end_layers yes)
		(zone_layer_connections)
		(net 122)
	)
	(via
		(at 221.2675 146.245)
		(size 0.35)
		(drill 0.15)
		(layers "F.Cu" "B.Cu")
		(remove_unused_layers yes)
		(keep_end_layers yes)
		(zone_layer_connections)
		(net 122)
	)
	(segment
		(start 214.405 148.370648)
		(end 214.405 147.820648)
		(width 0.09)
		(layer "In4.Cu")
		(net 122)
	)
	(segment
		(start 219.712688 149.375324)
		(end 219.712689 149.375324)
		(width 0.09)
		(layer "In4.Cu")
		(net 122)
	)
	(segment
		(start 221.2675 146.245)
		(end 221.422499 146.399999)
		(width 0.09)
		(layer "In4.Cu")
		(net 122)
	)
	(segment
		(start 214.405 147.820648)
		(end 214.022102 147.43775)
		(width 0.09)
		(layer "In4.Cu")
		(net 122)
	)
	(segment
		(start 221.422499 146.698149)
		(end 220.235 147.885648)
		(width 0.09)
		(layer "In4.Cu")
		(net 122)
	)
	(segment
		(start 219.550053 149.700591)
		(end 219.550053 149.700592)
		(width 0.09)
		(layer "In4.Cu")
		(net 122)
	)
	(segment
		(start 219.533071 149.520975)
		(end 219.550053 149.537957)
		(width 0.09)
		(layer "In4.Cu")
		(net 122)
	)
	(segment
		(start 214.022102 147.43775)
		(end 212.337748 147.43775)
		(width 0.09)
		(layer "In4.Cu")
		(net 122)
	)
	(segment
		(start 220.235 149.015648)
		(end 219.875324 149.375324)
		(width 0.09)
		(layer "In4.Cu")
		(net 122)
	)
	(segment
		(start 212.337748 147.43775)
		(end 212.205499 147.305501)
		(width 0.09)
		(layer "In4.Cu")
		(net 122)
	)
	(segment
		(start 221.422499 146.399999)
		(end 221.422499 146.698149)
		(width 0.09)
		(layer "In4.Cu")
		(net 122)
	)
	(segment
		(start 219.712689 149.375324)
		(end 219.695706 149.358341)
		(width 0.09)
		(layer "In4.Cu")
		(net 122)
	)
	(segment
		(start 219.445648 149.805)
		(end 215.839352 149.805)
		(width 0.09)
		(layer "In4.Cu")
		(net 122)
	)
	(segment
		(start 220.235 147.885648)
		(end 220.235 149.015648)
		(width 0.09)
		(layer "In4.Cu")
		(net 122)
	)
	(segment
		(start 215.839352 149.805)
		(end 214.405 148.370648)
		(width 0.09)
		(layer "In4.Cu")
		(net 122)
	)
	(segment
		(start 219.533072 149.358341)
		(end 219.533071 149.358341)
		(width 0.09)
		(layer "In4.Cu")
		(net 122)
	)
	(segment
		(start 219.550053 149.700592)
		(end 219.445648 149.805)
		(width 0.09)
		(layer "In4.Cu")
		(net 122)
	)
	(arc
		(start 219.533071 149.358341)
		(mid 219.499388 149.439658)
		(end 219.533071 149.520975)
		(width 0.09)
		(layer "In4.Cu")
		(net 122)
	)
	(arc
		(start 219.875324 149.375324)
		(mid 219.794006 149.409007)
		(end 219.712688 149.375324)
		(width 0.09)
		(layer "In4.Cu")
		(net 122)
	)
	(arc
		(start 219.550053 149.537957)
		(mid 219.583736 149.619274)
		(end 219.550053 149.700591)
		(width 0.09)
		(layer "In4.Cu")
		(net 122)
	)
	(arc
		(start 219.695706 149.358341)
		(mid 219.614389 149.324658)
		(end 219.533072 149.358341)
		(width 0.09)
		(layer "In4.Cu")
		(net 122)
	)
	(segment
		(start 219.8265 145.342)
		(end 219.753 145.342)
		(width 0.1)
		(layer "F.Cu")
		(net 123)
	)
	(segment
		(start 219.753 145.342)
		(end 219.2 145.895)
		(width 0.1)
		(layer "F.Cu")
		(net 123)
	)
	(via
		(at 202.1 129.901)
		(size 0.35)
		(drill 0.15)
		(layers "F.Cu" "B.Cu")
		(remove_unused_layers yes)
		(keep_end_layers yes)
		(zone_layer_connections)
		(net 123)
	)
	(via
		(at 181.601 117.946)
		(size 0.35)
		(drill 0.15)
		(layers "F.Cu" "B.Cu")
		(remove_unused_layers yes)
		(keep_end_layers yes)
		(zone_layer_connections)
		(net 123)
	)
	(via
		(at 215.05 116.4)
		(size 0.35)
		(drill 0.15)
		(layers "F.Cu" "B.Cu")
		(remove_unused_layers yes)
		(keep_end_layers yes)
		(zone_layer_connections)
		(net 123)
	)
	(via
		(at 190.35 121.1)
		(size 0.35)
		(drill 0.15)
		(layers "F.Cu" "B.Cu")
		(remove_unused_layers yes)
		(keep_end_layers yes)
		(zone_layer_connections)
		(net 123)
	)
	(via
		(at 219.2 145.895)
		(size 0.35)
		(drill 0.15)
		(layers "F.Cu" "B.Cu")
		(remove_unused_layers yes)
		(keep_end_layers yes)
		(zone_layer_connections)
		(net 123)
	)
	(via
		(at 185.24 119.92)
		(size 0.35)
		(drill 0.15)
		(layers "F.Cu" "B.Cu")
		(remove_unused_layers yes)
		(keep_end_layers yes)
		(zone_layer_connections)
		(net 123)
	)
	(segment
		(start 190.695478 121.1)
		(end 194.381478 124.786)
		(width 0.1)
		(layer "In2.Cu")
		(net 123)
	)
	(segment
		(start 199.269185 129.480815)
		(end 201.679815 129.480815)
		(width 0.1)
		(layer "In2.Cu")
		(net 123)
	)
	(segment
		(start 198.57337 128.785)
		(end 199.269185 129.480815)
		(width 0.1)
		(layer "In2.Cu")
		(net 123)
	)
	(segment
		(start 196.984 128.4445)
		(end 197.3245 128.785)
		(width 0.1)
		(layer "In2.Cu")
		(net 123)
	)
	(segment
		(start 190.35 121.1)
		(end 190.695478 121.1)
		(width 0.1)
		(layer "In2.Cu")
		(net 123)
	)
	(segment
		(start 194.381478 124.786)
		(end 196.541 124.786)
		(width 0.1)
		(layer "In2.Cu")
		(net 123)
	)
	(segment
		(start 197.3245 128.785)
		(end 198.57337 128.785)
		(width 0.1)
		(layer "In2.Cu")
		(net 123)
	)
	(segment
		(start 196.541 124.786)
		(end 196.984 125.229)
		(width 0.1)
		(layer "In2.Cu")
		(net 123)
	)
	(segment
		(start 201.679815 129.480815)
		(end 202.1 129.901)
		(width 0.1)
		(layer "In2.Cu")
		(net 123)
	)
	(segment
		(start 196.984 125.229)
		(end 196.984 128.4445)
		(width 0.1)
		(layer "In2.Cu")
		(net 123)
	)
	(segment
		(start 218.855 145.55)
		(end 215.214437 145.55)
		(width 0.1)
		(layer "In4.Cu")
		(net 123)
	)
	(segment
		(start 209 134.2)
		(end 209 135.15)
		(width 0.1)
		(layer "In4.Cu")
		(net 123)
	)
	(segment
		(start 202.451 129.55)
		(end 204.75 129.55)
		(width 0.1)
		(layer "In4.Cu")
		(net 123)
	)
	(segment
		(start 214.725882 145.625882)
		(end 214.1755 145.0755)
		(width 0.1)
		(layer "In4.Cu")
		(net 123)
	)
	(segment
		(start 215.138555 145.625882)
		(end 214.725882 145.625882)
		(width 0.1)
		(layer "In4.Cu")
		(net 123)
	)
	(segment
		(start 187.5 121.3)
		(end 188.25 122.05)
		(width 0.1)
		(layer "In4.Cu")
		(net 123)
	)
	(segment
		(start 189.90962 122.05)
		(end 190.375 121.58462)
		(width 0.1)
		(layer "In4.Cu")
		(net 123)
	)
	(segment
		(start 205.1 130.3)
		(end 205.45 130.3)
		(width 0.1)
		(layer "In4.Cu")
		(net 123)
	)
	(segment
		(start 204.75 129.55)
		(end 204.9 129.7)
		(width 0.1)
		(layer "In4.Cu")
		(net 123)
	)
	(segment
		(start 190.375 121.58462)
		(end 190.375 121.125)
		(width 0.1)
		(layer "In4.Cu")
		(net 123)
	)
	(segment
		(start 214.1755 145.0755)
		(end 213.3755 145.0755)
		(width 0.1)
		(layer "In4.Cu")
		(net 123)
	)
	(segment
		(start 204.9 129.7)
		(end 204.9 130.1)
		(width 0.1)
		(layer "In4.Cu")
		(net 123)
	)
	(segment
		(start 212.75 138.475)
		(end 212.75 139.36538)
		(width 0.1)
		(layer "In4.Cu")
		(net 123)
	)
	(segment
		(start 205.7 130.9)
		(end 209 134.2)
		(width 0.1)
		(layer "In4.Cu")
		(net 123)
	)
	(segment
		(start 215.214437 145.55)
		(end 215.138555 145.625882)
		(width 0.1)
		(layer "In4.Cu")
		(net 123)
	)
	(segment
		(start 219.2 145.895)
		(end 218.855 145.55)
		(width 0.1)
		(layer "In4.Cu")
		(net 123)
	)
	(segment
		(start 209.55 135.7)
		(end 209.975 135.7)
		(width 0.1)
		(layer "In4.Cu")
		(net 123)
	)
	(segment
		(start 190.375 121.125)
		(end 190.35 121.1)
		(width 0.1)
		(layer "In4.Cu")
		(net 123)
	)
	(segment
		(start 212.75 139.36538)
		(end 212.225 139.89038)
		(width 0.1)
		(layer "In4.Cu")
		(net 123)
	)
	(segment
		(start 209.975 135.7)
		(end 212.75 138.475)
		(width 0.1)
		(layer "In4.Cu")
		(net 123)
	)
	(segment
		(start 209 135.15)
		(end 209.55 135.7)
		(width 0.1)
		(layer "In4.Cu")
		(net 123)
	)
	(segment
		(start 205.7 130.55)
		(end 205.7 130.9)
		(width 0.1)
		(layer "In4.Cu")
		(net 123)
	)
	(segment
		(start 186.62 121.3)
		(end 187.5 121.3)
		(width 0.1)
		(layer "In4.Cu")
		(net 123)
	)
	(segment
		(start 188.25 122.05)
		(end 189.90962 122.05)
		(width 0.1)
		(layer "In4.Cu")
		(net 123)
	)
	(segment
		(start 205.45 130.3)
		(end 205.7 130.55)
		(width 0.1)
		(layer "In4.Cu")
		(net 123)
	)
	(segment
		(start 185.25 119.93)
		(end 186.62 121.3)
		(width 0.1)
		(layer "In4.Cu")
		(net 123)
	)
	(segment
		(start 212.225 143.925)
		(end 213.3755 145.0755)
		(width 0.1)
		(layer "In4.Cu")
		(net 123)
	)
	(segment
		(start 212.225 139.89038)
		(end 212.225 143.925)
		(width 0.1)
		(layer "In4.Cu")
		(net 123)
	)
	(segment
		(start 204.9 130.1)
		(end 205.1 130.3)
		(width 0.1)
		(layer "In4.Cu")
		(net 123)
	)
	(segment
		(start 202.1 129.901)
		(end 202.451 129.55)
		(width 0.1)
		(layer "In4.Cu")
		(net 123)
	)
	(segment
		(start 209.475 126.7)
		(end 213.9126 126.7)
		(width 0.1)
		(layer "In9.Cu")
		(net 123)
	)
	(segment
		(start 215.05 117.075)
		(end 215.05 116.4)
		(width 0.1)
		(layer "In9.Cu")
		(net 123)
	)
	(segment
		(start 208.3 127.875)
		(end 209.475 126.7)
		(width 0.1)
		(layer "In9.Cu")
		(net 123)
	)
	(segment
		(start 215 125.6126)
		(end 215 123.69065)
		(width 0.1)
		(layer "In9.Cu")
		(net 123)
	)
	(segment
		(start 202.1 129.901)
		(end 202.1 129)
		(width 0.1)
		(layer "In9.Cu")
		(net 123)
	)
	(segment
		(start 202.1 129)
		(end 203.225 127.875)
		(width 0.1)
		(layer "In9.Cu")
		(net 123)
	)
	(segment
		(start 215 123.69065)
		(end 215.75 122.94065)
		(width 0.1)
		(layer "In9.Cu")
		(net 123)
	)
	(segment
		(start 215.75 122.94065)
		(end 215.75 117.775)
		(width 0.1)
		(layer "In9.Cu")
		(net 123)
	)
	(segment
		(start 213.9126 126.7)
		(end 215 125.6126)
		(width 0.1)
		(layer "In9.Cu")
		(net 123)
	)
	(segment
		(start 203.225 127.875)
		(end 208.3 127.875)
		(width 0.1)
		(layer "In9.Cu")
		(net 123)
	)
	(segment
		(start 215.75 117.775)
		(end 215.05 117.075)
		(width 0.1)
		(layer "In9.Cu")
		(net 123)
	)
	(segment
		(start 183.575 119.92)
		(end 181.601 117.946)
		(width 0.1)
		(layer "In11.Cu")
		(net 123)
	)
	(segment
		(start 185.24 119.92)
		(end 183.575 119.92)
		(width 0.1)
		(layer "In11.Cu")
		(net 123)
	)
	(segment
		(start 200.1 123.7)
		(end 199.325 122.925)
		(width 0.1)
		(layer "F.Cu")
		(net 124)
	)
	(segment
		(start 194.5 122.925)
		(end 194.05 123.375)
		(width 0.1)
		(layer "F.Cu")
		(net 124)
	)
	(segment
		(start 189.236382 122.936382)
		(end 189.236382 121.427265)
		(width 0.1)
		(layer "F.Cu")
		(net 124)
	)
	(segment
		(start 200.864 130.052188)
		(end 200.864 129.714)
		(width 0.1)
		(layer "F.Cu")
		(net 124)
	)
	(segment
		(start 202.9 130.65)
		(end 202.55 130.3)
		(width 0.1)
		(layer "F.Cu")
		(net 124)
	)
	(segment
		(start 194.05 123.375)
		(end 189.675 123.375)
		(width 0.1)
		(layer "F.Cu")
		(net 124)
	)
	(segment
		(start 189.675 123.375)
		(end 189.236382 122.936382)
		(width 0.1)
		(layer "F.Cu")
		(net 124)
	)
	(segment
		(start 200.1 129.217188)
		(end 200.1 123.7)
		(width 0.1)
		(layer "F.Cu")
		(net 124)
	)
	(segment
		(start 219.439887 144.742)
		(end 219.227486 144.954401)
		(width 0.1)
		(layer "F.Cu")
		(net 124)
	)
	(segment
		(start 219.8265 144.742)
		(end 219.439887 144.742)
		(width 0.1)
		(layer "F.Cu")
		(net 124)
	)
	(segment
		(start 199.325 122.925)
		(end 194.5 122.925)
		(width 0.1)
		(layer "F.Cu")
		(net 124)
	)
	(segment
		(start 202.55 130.3)
		(end 201.111812 130.3)
		(width 0.1)
		(layer "F.Cu")
		(net 124)
	)
	(segment
		(start 201.111812 130.3)
		(end 200.864 130.052188)
		(width 0.1)
		(layer "F.Cu")
		(net 124)
	)
	(segment
		(start 200.347812 129.465)
		(end 200.1 129.217188)
		(width 0.1)
		(layer "F.Cu")
		(net 124)
	)
	(segment
		(start 200.615 129.465)
		(end 200.347812 129.465)
		(width 0.1)
		(layer "F.Cu")
		(net 124)
	)
	(segment
		(start 200.864 129.714)
		(end 200.615 129.465)
		(width 0.1)
		(layer "F.Cu")
		(net 124)
	)
	(via
		(at 216.05 116.411)
		(size 0.35)
		(drill 0.15)
		(layers "F.Cu" "B.Cu")
		(remove_unused_layers yes)
		(keep_end_layers yes)
		(zone_layer_connections)
		(net 124)
	)
	(via
		(at 202.9 130.65)
		(size 0.35)
		(drill 0.15)
		(layers "F.Cu" "B.Cu")
		(remove_unused_layers yes)
		(keep_end_layers yes)
		(zone_layer_connections)
		(net 124)
	)
	(via
		(at 219.227486 144.954401)
		(size 0.35)
		(drill 0.15)
		(layers "F.Cu" "B.Cu")
		(remove_unused_layers yes)
		(keep_end_layers yes)
		(zone_layer_connections)
		(net 124)
	)
	(via
		(at 189.236382 121.427265)
		(size 0.35)
		(drill 0.15)
		(layers "F.Cu" "B.Cu")
		(remove_unused_layers yes)
		(keep_end_layers yes)
		(zone_layer_connections)
		(net 124)
	)
	(via
		(at 186.68 117.946)
		(size 0.35)
		(drill 0.15)
		(layers "F.Cu" "B.Cu")
		(remove_unused_layers yes)
		(keep_end_layers yes)
		(zone_layer_connections)
		(net 124)
	)
	(segment
		(start 184.065 116.635)
		(end 185.369 116.635)
		(width 0.1)
		(layer "B.Cu")
		(net 124)
	)
	(segment
		(start 185.225 120.895)
		(end 184.045 120.895)
		(width 0.1)
		(layer "B.Cu")
		(net 124)
	)
	(segment
		(start 183.675 117.025)
		(end 184.065 116.635)
		(width 0.1)
		(layer "B.Cu")
		(net 124)
	)
	(segment
		(start 185.75 120.37)
		(end 185.225 120.895)
		(width 0.1)
		(layer "B.Cu")
		(net 124)
	)
	(segment
		(start 183.675 120.525)
		(end 183.675 117.025)
		(width 0.1)
		(layer "B.Cu")
		(net 124)
	)
	(segment
		(start 184.045 120.895)
		(end 183.675 120.525)
		(width 0.1)
		(layer "B.Cu")
		(net 124)
	)
	(segment
		(start 185.369 116.635)
		(end 186.68 117.946)
		(width 0.1)
		(layer "B.Cu")
		(net 124)
	)
	(segment
		(start 189.236382 121.427265)
		(end 189.236382 120.936382)
		(width 0.1)
		(layer "In4.Cu")
		(net 124)
	)
	(segment
		(start 208.6 135.2)
		(end 209.45 136.05)
		(width 0.1)
		(layer "In4.Cu")
		(net 124)
	)
	(segment
		(start 219.033 146.867)
		(end 219.6 146.3)
		(width 0.1)
		(layer "In4.Cu")
		(net 124)
	)
	(segment
		(start 217.57488 145.95)
		(end 218.49188 146.867)
		(width 0.1)
		(layer "In4.Cu")
		(net 124)
	)
	(segment
		(start 213.9 145.95)
		(end 217.57488 145.95)
		(width 0.1)
		(layer "In4.Cu")
		(net 124)
	)
	(segment
		(start 204.6 130.3)
		(end 204.974 130.674)
		(width 0.1)
		(layer "In4.Cu")
		(net 124)
	)
	(segment
		(start 189.236382 120.936382)
		(end 188.2 119.9)
		(width 0.1)
		(layer "In4.Cu")
		(net 124)
	)
	(segment
		(start 205.476 131.176)
		(end 208.6 134.3)
		(width 0.1)
		(layer "In4.Cu")
		(net 124)
	)
	(segment
		(start 218.49188 146.867)
		(end 219.033 146.867)
		(width 0.1)
		(layer "In4.Cu")
		(net 124)
	)
	(segment
		(start 202.9 130.65)
		(end 203.25 130.3)
		(width 0.1)
		(layer "In4.Cu")
		(net 124)
	)
	(segment
		(start 187.1 119.1)
		(end 187.1 118.366)
		(width 0.1)
		(layer "In4.Cu")
		(net 124)
	)
	(segment
		(start 209.85 136.05)
		(end 211.95 138.15)
		(width 0.1)
		(layer "In4.Cu")
		(net 124)
	)
	(segment
		(start 187.9 119.9)
		(end 187.1 119.1)
		(width 0.1)
		(layer "In4.Cu")
		(net 124)
	)
	(segment
		(start 204.974 130.874)
		(end 205.276 131.176)
		(width 0.1)
		(layer "In4.Cu")
		(net 124)
	)
	(segment
		(start 188.2 119.9)
		(end 187.9 119.9)
		(width 0.1)
		(layer "In4.Cu")
		(net 124)
	)
	(segment
		(start 203.25 130.3)
		(end 204.6 130.3)
		(width 0.1)
		(layer "In4.Cu")
		(net 124)
	)
	(segment
		(start 219.6 145.326915)
		(end 219.227486 144.954401)
		(width 0.1)
		(layer "In4.Cu")
		(net 124)
	)
	(segment
		(start 205.276 131.176)
		(end 205.476 131.176)
		(width 0.1)
		(layer "In4.Cu")
		(net 124)
	)
	(segment
		(start 211.95 144)
		(end 213.9 145.95)
		(width 0.1)
		(layer "In4.Cu")
		(net 124)
	)
	(segment
		(start 211.95 138.15)
		(end 211.95 144)
		(width 0.1)
		(layer "In4.Cu")
		(net 124)
	)
	(segment
		(start 204.974 130.674)
		(end 204.974 130.874)
		(width 0.1)
		(layer "In4.Cu")
		(net 124)
	)
	(segment
		(start 187.1 118.366)
		(end 186.68 117.946)
		(width 0.1)
		(layer "In4.Cu")
		(net 124)
	)
	(segment
		(start 208.6 134.3)
		(end 208.6 135.2)
		(width 0.1)
		(layer "In4.Cu")
		(net 124)
	)
	(segment
		(start 219.6 146.3)
		(end 219.6 145.326915)
		(width 0.1)
		(layer "In4.Cu")
		(net 124)
	)
	(segment
		(start 209.45 136.05)
		(end 209.85 136.05)
		(width 0.1)
		(layer "In4.Cu")
		(net 124)
	)
	(segment
		(start 209.425 127.8)
		(end 208.6 128.625)
		(width 0.1)
		(layer "In9.Cu")
		(net 124)
	)
	(segment
		(start 216.05 116.411)
		(end 216.015 116.446)
		(width 0.1)
		(layer "In9.Cu")
		(net 124)
	)
	(segment
		(start 202.575 129.625)
		(end 202.575 130.325)
		(width 0.1)
		(layer "In9.Cu")
		(net 124)
	)
	(segment
		(start 210.177 127.8)
		(end 209.425 127.8)
		(width 0.1)
		(layer "In9.Cu")
		(net 124)
	)
	(segment
		(start 215.45 124)
		(end 215.45 125.7)
		(width 0.1)
		(layer "In9.Cu")
		(net 124)
	)
	(segment
		(start 203.875 128.625)
		(end 203.05 129.45)
		(width 0.1)
		(layer "In9.Cu")
		(net 124)
	)
	(segment
		(start 214.1 127.05)
		(end 210.927 127.05)
		(width 0.1)
		(layer "In9.Cu")
		(net 124)
	)
	(segment
		(start 216.015 123.435)
		(end 215.45 124)
		(width 0.1)
		(layer "In9.Cu")
		(net 124)
	)
	(segment
		(start 202.575 130.325)
		(end 202.9 130.65)
		(width 0.1)
		(layer "In9.Cu")
		(net 124)
	)
	(segment
		(start 215.45 125.7)
		(end 214.1 127.05)
		(width 0.1)
		(layer "In9.Cu")
		(net 124)
	)
	(segment
		(start 210.927 127.05)
		(end 210.177 127.8)
		(width 0.1)
		(layer "In9.Cu")
		(net 124)
	)
	(segment
		(start 203.05 129.45)
		(end 202.75 129.45)
		(width 0.1)
		(layer "In9.Cu")
		(net 124)
	)
	(segment
		(start 216.015 116.446)
		(end 216.015 123.435)
		(width 0.1)
		(layer "In9.Cu")
		(net 124)
	)
	(segment
		(start 202.75 129.45)
		(end 202.575 129.625)
		(width 0.1)
		(layer "In9.Cu")
		(net 124)
	)
	(segment
		(start 208.6 128.625)
		(end 203.875 128.625)
		(width 0.1)
		(layer "In9.Cu")
		(net 124)
	)
	(segment
		(start 183.53 119.62)
		(end 183.53 118.556)
		(width 0.1)
		(layer "F.Cu")
		(net 125)
	)
	(segment
		(start 182.1 121.05)
		(end 183.53 119.62)
		(width 0.1)
		(layer "F.Cu")
		(net 125)
	)
	(segment
		(start 183.53 118.556)
		(end 184.14 117.946)
		(width 0.1)
		(layer "F.Cu")
		(net 125)
	)
	(segment
		(start 182.1 121.45)
		(end 182.1 121.05)
		(width 0.1)
		(layer "F.Cu")
		(net 125)
	)
	(segment
		(start 182.1 121.45)
		(end 181.63 121.45)
		(width 0.1)
		(layer "F.Cu")
		(net 125)
	)
	(segment
		(start 182.62 121.45)
		(end 182.1 121.45)
		(width 0.1)
		(layer "F.Cu")
		(net 125)
	)
	(segment
		(start 200.064 129.749812)
		(end 200.064 130.014)
		(width 0.1)
		(layer "F.Cu")
		(net 126)
	)
	(segment
		(start 185.24 118.97)
		(end 185.41 119.14)
		(width 0.1)
		(layer "F.Cu")
		(net 126)
	)
	(segment
		(start 199.618812 129.536)
		(end 199.850188 129.536)
		(width 0.1)
		(layer "F.Cu")
		(net 126)
	)
	(segment
		(start 188.85 123.2)
		(end 189.325 123.675)
		(width 0.1)
		(layer "F.Cu")
		(net 126)
	)
	(segment
		(start 199.850188 129.536)
		(end 200.064 129.749812)
		(width 0.1)
		(layer "F.Cu")
		(net 126)
	)
	(segment
		(start 185.41 119.14)
		(end 185.41 119.215)
		(width 0.1)
		(layer "F.Cu")
		(net 126)
	)
	(segment
		(start 194.2 123.675)
		(end 194.575 123.3)
		(width 0.1)
		(layer "F.Cu")
		(net 126)
	)
	(segment
		(start 194.575 123.3)
		(end 198.85 123.3)
		(width 0.1)
		(layer "F.Cu")
		(net 126)
	)
	(segment
		(start 199.3 129.217188)
		(end 199.618812 129.536)
		(width 0.1)
		(layer "F.Cu")
		(net 126)
	)
	(segment
		(start 198.85 123.3)
		(end 199.3 123.75)
		(width 0.1)
		(layer "F.Cu")
		(net 126)
	)
	(segment
		(start 200.316 130.266)
		(end 200.580188 130.266)
		(width 0.1)
		(layer "F.Cu")
		(net 126)
	)
	(segment
		(start 200.580188 130.266)
		(end 201.015188 130.701)
		(width 0.1)
		(layer "F.Cu")
		(net 126)
	)
	(segment
		(start 200.064 130.014)
		(end 200.316 130.266)
		(width 0.1)
		(layer "F.Cu")
		(net 126)
	)
	(segment
		(start 199.3 123.75)
		(end 199.3 129.217188)
		(width 0.1)
		(layer "F.Cu")
		(net 126)
	)
	(segment
		(start 188.85 121.05)
		(end 188.85 123.2)
		(width 0.1)
		(layer "F.Cu")
		(net 126)
	)
	(segment
		(start 189.325 123.675)
		(end 194.2 123.675)
		(width 0.1)
		(layer "F.Cu")
		(net 126)
	)
	(segment
		(start 201.015188 130.701)
		(end 201.3 130.701)
		(width 0.1)
		(layer "F.Cu")
		(net 126)
	)
	(via
		(at 185.24 118.97)
		(size 0.35)
		(drill 0.15)
		(layers "F.Cu" "B.Cu")
		(remove_unused_layers yes)
		(keep_end_layers yes)
		(zone_layer_connections)
		(net 126)
	)
	(via
		(at 188.85 121.05)
		(size 0.35)
		(drill 0.15)
		(layers "F.Cu" "B.Cu")
		(remove_unused_layers yes)
		(keep_end_layers yes)
		(zone_layer_connections)
		(net 126)
	)
	(segment
		(start 188.25 120.45)
		(end 187.18 120.45)
		(width 0.1)
		(layer "In4.Cu")
		(net 126)
	)
	(segment
		(start 185.24 118.97)
		(end 185.7 118.97)
		(width 0.1)
		(layer "In4.Cu")
		(net 126)
	)
	(segment
		(start 188.85 121.05)
		(end 188.25 120.45)
		(width 0.1)
		(layer "In4.Cu")
		(net 126)
	)
	(segment
		(start 185.7 118.97)
		(end 187.18 120.45)
		(width 0.1)
		(layer "In4.Cu")
		(net 126)
	)
	(segment
		(start 201.7 123.85)
		(end 201.7 128.416188)
		(width 0.1)
		(layer "F.Cu")
		(net 127)
	)
	(segment
		(start 193.85 122.775)
		(end 194.35 122.275)
		(width 0.1)
		(layer "F.Cu")
		(net 127)
	)
	(segment
		(start 201.3 129.687188)
		(end 201.3 129.901)
		(width 0.1)
		(layer "F.Cu")
		(net 127)
	)
	(segment
		(start 220.45 143.85)
		(end 220.45 143.5655)
		(width 0.1)
		(layer "F.Cu")
		(net 127)
	)
	(segment
		(start 200.9 129.287188)
		(end 201.3 129.687188)
		(width 0.1)
		(layer "F.Cu")
		(net 127)
	)
	(segment
		(start 201.183812 128.7)
		(end 200.9 128.983812)
		(width 0.1)
		(layer "F.Cu")
		(net 127)
	)
	(segment
		(start 200.9 128.983812)
		(end 200.9 129.287188)
		(width 0.1)
		(layer "F.Cu")
		(net 127)
	)
	(segment
		(start 200.125 122.275)
		(end 201.7 123.85)
		(width 0.1)
		(layer "F.Cu")
		(net 127)
	)
	(segment
		(start 190.475 122.775)
		(end 193.85 122.775)
		(width 0.1)
		(layer "F.Cu")
		(net 127)
	)
	(segment
		(start 190.05 121.45)
		(end 190.05 122.35)
		(width 0.1)
		(layer "F.Cu")
		(net 127)
	)
	(segment
		(start 220.45 143.5655)
		(end 219.8265 142.942)
		(width 0.1)
		(layer "F.Cu")
		(net 127)
	)
	(segment
		(start 190.05 122.35)
		(end 190.475 122.775)
		(width 0.1)
		(layer "F.Cu")
		(net 127)
	)
	(segment
		(start 201.416188 128.7)
		(end 201.183812 128.7)
		(width 0.1)
		(layer "F.Cu")
		(net 127)
	)
	(segment
		(start 201.7 128.416188)
		(end 201.416188 128.7)
		(width 0.1)
		(layer "F.Cu")
		(net 127)
	)
	(segment
		(start 194.35 122.275)
		(end 200.125 122.275)
		(width 0.1)
		(layer "F.Cu")
		(net 127)
	)
	(via
		(at 220.45 143.85)
		(size 0.35)
		(drill 0.15)
		(layers "F.Cu" "B.Cu")
		(remove_unused_layers yes)
		(keep_end_layers yes)
		(zone_layer_connections)
		(net 127)
	)
	(via
		(at 184.14 119.215)
		(size 0.35)
		(drill 0.15)
		(layers "F.Cu" "B.Cu")
		(remove_unused_layers yes)
		(keep_end_layers yes)
		(zone_layer_connections)
		(net 127)
	)
	(via
		(at 190.05 121.45)
		(size 0.35)
		(drill 0.15)
		(layers "F.Cu" "B.Cu")
		(remove_unused_layers yes)
		(keep_end_layers yes)
		(zone_layer_connections)
		(net 127)
	)
	(segment
		(start 187.28 120.85)
		(end 188.1 120.85)
		(width 0.1)
		(layer "B.Cu")
		(net 127)
	)
	(segment
		(start 188.1 120.85)
		(end 189.002265 121.752265)
		(width 0.1)
		(layer "B.Cu")
		(net 127)
	)
	(segment
		(start 189.747735 121.752265)
		(end 190.05 121.45)
		(width 0.1)
		(layer "B.Cu")
		(net 127)
	)
	(segment
		(start 189.002265 121.752265)
		(end 189.747735 121.752265)
		(width 0.1)
		(layer "B.Cu")
		(net 127)
	)
	(segment
		(start 186.8 120.37)
		(end 187.28 120.85)
		(width 0.1)
		(layer "B.Cu")
		(net 127)
	)
	(segment
		(start 184.465 119.54)
		(end 185.57 119.54)
		(width 0.1)
		(layer "In4.Cu")
		(net 127)
	)
	(segment
		(start 185.57 119.54)
		(end 186.93 120.9)
		(width 0.1)
		(layer "In4.Cu")
		(net 127)
	)
	(segment
		(start 184.14 119.215)
		(end 184.465 119.54)
		(width 0.1)
		(layer "In4.Cu")
		(net 127)
	)
	(segment
		(start 186.93 120.9)
		(end 187.95 120.9)
		(width 0.1)
		(layer "In4.Cu")
		(net 127)
	)
	(segment
		(start 187.95 120.9)
		(end 188.802265 121.752265)
		(width 0.1)
		(layer "In4.Cu")
		(net 127)
	)
	(segment
		(start 189.747735 121.752265)
		(end 190.05 121.45)
		(width 0.1)
		(layer "In4.Cu")
		(net 127)
	)
	(segment
		(start 188.802265 121.752265)
		(end 189.747735 121.752265)
		(width 0.1)
		(layer "In4.Cu")
		(net 127)
	)
	(segment
		(start 185.154 117.466)
		(end 184.14 118.48)
		(width 0.1)
		(layer "In11.Cu")
		(net 127)
	)
	(segment
		(start 218.546 142.666)
		(end 218.546 140.144)
		(width 0.1)
		(layer "In11.Cu")
		(net 127)
	)
	(segment
		(start 219.65 139.04)
		(end 219.65 133.10962)
		(width 0.1)
		(layer "In11.Cu")
		(net 127)
	)
	(segment
		(start 216.211 117.239)
		(end 213.961 117.239)
		(width 0.1)
		(layer "In11.Cu")
		(net 127)
	)
	(segment
		(start 220.45 143.85)
		(end 219.54 142.94)
		(width 0.1)
		(layer "In11.Cu")
		(net 127)
	)
	(segment
		(start 218.546 140.144)
		(end 219.65 139.04)
		(width 0.1)
		(layer "In11.Cu")
		(net 127)
	)
	(segment
		(start 189.636 117.586)
		(end 189.516 117.466)
		(width 0.1)
		(layer "In11.Cu")
		(net 127)
	)
	(segment
		(start 219.56 117.11)
		(end 216.34 117.11)
		(width 0.1)
		(layer "In11.Cu")
		(net 127)
	)
	(segment
		(start 219.85 117.4)
		(end 219.56 117.11)
		(width 0.1)
		(layer "In11.Cu")
		(net 127)
	)
	(segment
		(start 206.01 117.415)
		(end 205.825 117.6)
		(width 0.1)
		(layer "In11.Cu")
		(net 127)
	)
	(segment
		(start 216.34 117.11)
		(end 216.211 117.239)
		(width 0.1)
		(layer "In11.Cu")
		(net 127)
	)
	(segment
		(start 212.24962 117.8)
		(end 211.86462 117.415)
		(width 0.1)
		(layer "In11.Cu")
		(net 127)
	)
	(segment
		(start 219.54 142.94)
		(end 218.82 142.94)
		(width 0.1)
		(layer "In11.Cu")
		(net 127)
	)
	(segment
		(start 219.85 128.49038)
		(end 219.85 117.4)
		(width 0.1)
		(layer "In11.Cu")
		(net 127)
	)
	(segment
		(start 189.516 117.466)
		(end 185.154 117.466)
		(width 0.1)
		(layer "In11.Cu")
		(net 127)
	)
	(segment
		(start 213.961 117.239)
		(end 213.4 117.8)
		(width 0.1)
		(layer "In11.Cu")
		(net 127)
	)
	(segment
		(start 205.825 117.6)
		(end 197.176907 117.6)
		(width 0.1)
		(layer "In11.Cu")
		(net 127)
	)
	(segment
		(start 219.65 133.10962)
		(end 220.4245 132.33512)
		(width 0.1)
		(layer "In11.Cu")
		(net 127)
	)
	(segment
		(start 220.4245 132.33512)
		(end 220.4245 129.06488)
		(width 0.1)
		(layer "In11.Cu")
		(net 127)
	)
	(segment
		(start 197.162907 117.586)
		(end 189.636 117.586)
		(width 0.1)
		(layer "In11.Cu")
		(net 127)
	)
	(segment
		(start 197.176907 117.6)
		(end 197.162907 117.586)
		(width 0.1)
		(layer "In11.Cu")
		(net 127)
	)
	(segment
		(start 213.4 117.8)
		(end 212.24962 117.8)
		(width 0.1)
		(layer "In11.Cu")
		(net 127)
	)
	(segment
		(start 211.86462 117.415)
		(end 206.01 117.415)
		(width 0.1)
		(layer "In11.Cu")
		(net 127)
	)
	(segment
		(start 220.4245 129.06488)
		(end 219.85 128.49038)
		(width 0.1)
		(layer "In11.Cu")
		(net 127)
	)
	(segment
		(start 184.14 118.48)
		(end 184.14 119.215)
		(width 0.1)
		(layer "In11.Cu")
		(net 127)
	)
	(segment
		(start 218.82 142.94)
		(end 218.546 142.666)
		(width 0.1)
		(layer "In11.Cu")
		(net 127)
	)
	(segment
		(start 220.62 142.79)
		(end 220.53 142.88)
		(width 0.09)
		(layer "F.Cu")
		(net 128)
	)
	(segment
		(start 220.38 142.88)
		(end 220.29 142.79)
		(width 0.09)
		(layer "F.Cu")
		(net 128)
	)
	(segment
		(start 220.29 142.001135)
		(end 220.6015 141.689635)
		(width 0.09)
		(layer "F.Cu")
		(net 128)
	)
	(segment
		(start 220.53 142.88)
		(end 220.38 142.88)
		(width 0.09)
		(layer "F.Cu")
		(net 128)
	)
	(segment
		(start 220.6015 141.689635)
		(end 220.6015 141.067)
		(width 0.09)
		(layer "F.Cu")
		(net 128)
	)
	(segment
		(start 220.29 142.79)
		(end 220.29 142.001135)
		(width 0.09)
		(layer "F.Cu")
		(net 128)
	)
	(via
		(at 220.62 142.79)
		(size 0.35)
		(drill 0.15)
		(layers "F.Cu" "B.Cu")
		(remove_unused_layers yes)
		(keep_end_layers yes)
		(zone_layer_connections)
		(net 128)
	)
	(segment
		(start 220.62 142.79)
		(end 220.59 142.76)
		(width 0.09)
		(layer "B.Cu")
		(net 128)
	)
	(segment
		(start 220.59 142.76)
		(end 220.59 142.37)
		(width 0.09)
		(layer "B.Cu")
		(net 128)
	)
	(segment
		(start 219.469 141.991)
		(end 219.38 142.08)
		(width 0.09)
		(layer "F.Cu")
		(net 129)
	)
	(segment
		(start 219.13 142.75)
		(end 219.13 142.41)
		(width 0.09)
		(layer "F.Cu")
		(net 129)
	)
	(segment
		(start 219.2 142.82)
		(end 219.13 142.75)
		(width 0.09)
		(layer "F.Cu")
		(net 129)
	)
	(segment
		(start 219.4015 141.5115)
		(end 219.469 141.579)
		(width 0.09)
		(layer "F.Cu")
		(net 129)
	)
	(segment
		(start 219.38 142.08)
		(end 219.38 142.75)
		(width 0.09)
		(layer "F.Cu")
		(net 129)
	)
	(segment
		(start 219.31 142.82)
		(end 219.2 142.82)
		(width 0.09)
		(layer "F.Cu")
		(net 129)
	)
	(segment
		(start 219.469 141.579)
		(end 219.469 141.991)
		(width 0.09)
		(layer "F.Cu")
		(net 129)
	)
	(segment
		(start 219.4015 141.067)
		(end 219.4015 141.5115)
		(width 0.09)
		(layer "F.Cu")
		(net 129)
	)
	(segment
		(start 219.38 142.75)
		(end 219.31 142.82)
		(width 0.09)
		(layer "F.Cu")
		(net 129)
	)
	(via
		(at 219.13 142.41)
		(size 0.35)
		(drill 0.15)
		(layers "F.Cu" "B.Cu")
		(remove_unused_layers yes)
		(keep_end_layers yes)
		(zone_layer_connections)
		(net 129)
	)
	(segment
		(start 218.91 142.41)
		(end 218.87 142.37)
		(width 0.09)
		(layer "B.Cu")
		(net 129)
	)
	(segment
		(start 219.13 142.41)
		(end 218.91 142.41)
		(width 0.09)
		(layer "B.Cu")
		(net 129)
	)
	(via
		(at 200.449 144.801)
		(size 0.35)
		(drill 0.15)
		(layers "F.Cu" "B.Cu")
		(remove_unused_layers yes)
		(keep_end_layers yes)
		(zone_layer_connections)
		(net 130)
	)
	(via
		(at 190.1 137.901)
		(size 0.35)
		(drill 0.15)
		(layers "F.Cu" "B.Cu")
		(remove_unused_layers yes)
		(keep_end_layers yes)
		(zone_layer_connections)
		(net 130)
	)
	(segment
		(start 191.21 137.21)
		(end 191.21 137.36)
		(width 0.09)
		(layer "In9.Cu")
		(net 130)
	)
	(segment
		(start 193.74 137.994549)
		(end 193.74 137.751)
		(width 0.09)
		(layer "In9.Cu")
		(net 130)
	)
	(segment
		(start 190.36 137.51)
		(end 190.22 137.51)
		(width 0.09)
		(layer "In9.Cu")
		(net 130)
	)
	(segment
		(start 195.012549 138.28)
		(end 194.025451 138.28)
		(width 0.09)
		(layer "In9.Cu")
		(net 130)
	)
	(segment
		(start 193.74 137.751)
		(end 193.499 137.51)
		(width 0.09)
		(layer "In9.Cu")
		(net 130)
	)
	(segment
		(start 198.5 141.3)
		(end 198.5 140.98)
		(width 0.09)
		(layer "In9.Cu")
		(net 130)
	)
	(segment
		(start 196.09 139.79)
		(end 196.09 139.357451)
		(width 0.09)
		(layer "In9.Cu")
		(net 130)
	)
	(segment
		(start 191.51 137.96)
		(end 191.51 137.21)
		(width 0.09)
		(layer "In9.Cu")
		(net 130)
	)
	(segment
		(start 197.949 140.68)
		(end 197.71 140.441)
		(width 0.09)
		(layer "In9.Cu")
		(net 130)
	)
	(segment
		(start 190.535 137.885)
		(end 190.535 137.685)
		(width 0.09)
		(layer "In9.Cu")
		(net 130)
	)
	(segment
		(start 197.71 140.18)
		(end 197.45 139.92)
		(width 0.09)
		(layer "In9.Cu")
		(net 130)
	)
	(segment
		(start 198.2 140.68)
		(end 197.949 140.68)
		(width 0.09)
		(layer "In9.Cu")
		(net 130)
	)
	(segment
		(start 192.11 137.36)
		(end 192.11 137.11)
		(width 0.09)
		(layer "In9.Cu")
		(net 130)
	)
	(segment
		(start 196.22 139.92)
		(end 196.09 139.79)
		(width 0.09)
		(layer "In9.Cu")
		(net 130)
	)
	(segment
		(start 194.025451 138.28)
		(end 193.74 137.994549)
		(width 0.09)
		(layer "In9.Cu")
		(net 130)
	)
	(segment
		(start 198.5 140.98)
		(end 198.2 140.68)
		(width 0.09)
		(layer "In9.Cu")
		(net 130)
	)
	(segment
		(start 193.499 137.51)
		(end 192.26 137.51)
		(width 0.09)
		(layer "In9.Cu")
		(net 130)
	)
	(segment
		(start 196.498452 139.92)
		(end 196.22 139.92)
		(width 0.09)
		(layer "In9.Cu")
		(net 130)
	)
	(segment
		(start 196.634226 139.784225)
		(end 196.634226 139.784226)
		(width 0.09)
		(layer "In9.Cu")
		(net 130)
	)
	(segment
		(start 190.1 137.63)
		(end 190.1 137.901)
		(width 0.09)
		(layer "In9.Cu")
		(net 130)
	)
	(segment
		(start 196.798452 139.648451)
		(end 196.77 139.648451)
		(width 0.09)
		(layer "In9.Cu")
		(net 130)
	)
	(segment
		(start 200.449 144.801)
		(end 199.988451 144.801)
		(width 0.09)
		(layer "In9.Cu")
		(net 130)
	)
	(segment
		(start 191.81 137.11)
		(end 191.81 137.96)
		(width 0.09)
		(layer "In9.Cu")
		(net 130)
	)
	(segment
		(start 197.71 140.441)
		(end 197.71 140.18)
		(width 0.09)
		(layer "In9.Cu")
		(net 130)
	)
	(segment
		(start 196.09 139.357451)
		(end 195.012549 138.28)
		(width 0.09)
		(layer "In9.Cu")
		(net 130)
	)
	(segment
		(start 190.885 137.685)
		(end 190.885 137.885)
		(width 0.09)
		(layer "In9.Cu")
		(net 130)
	)
	(segment
		(start 197.45 139.92)
		(end 197.07 139.92)
		(width 0.09)
		(layer "In9.Cu")
		(net 130)
	)
	(segment
		(start 196.934226 139.784226)
		(end 196.934226 139.784225)
		(width 0.09)
		(layer "In9.Cu")
		(net 130)
	)
	(segment
		(start 190.22 137.51)
		(end 190.1 137.63)
		(width 0.09)
		(layer "In9.Cu")
		(net 130)
	)
	(segment
		(start 199.08 143.892549)
		(end 199.08 141.88)
		(width 0.09)
		(layer "In9.Cu")
		(net 130)
	)
	(segment
		(start 199.08 141.88)
		(end 198.5 141.3)
		(width 0.09)
		(layer "In9.Cu")
		(net 130)
	)
	(segment
		(start 199.988451 144.801)
		(end 199.08 143.892549)
		(width 0.09)
		(layer "In9.Cu")
		(net 130)
	)
	(arc
		(start 191.51 137.21)
		(mid 191.466066 137.103934)
		(end 191.36 137.06)
		(width 0.09)
		(layer "In9.Cu")
		(net 130)
	)
	(arc
		(start 196.634226 139.784226)
		(mid 196.594459 139.880233)
		(end 196.498452 139.92)
		(width 0.09)
		(layer "In9.Cu")
		(net 130)
	)
	(arc
		(start 192.11 137.11)
		(mid 192.066066 137.003934)
		(end 191.96 136.96)
		(width 0.09)
		(layer "In9.Cu")
		(net 130)
	)
	(arc
		(start 197.07 139.92)
		(mid 196.973993 139.880233)
		(end 196.934226 139.784226)
		(width 0.09)
		(layer "In9.Cu")
		(net 130)
	)
	(arc
		(start 191.06 137.51)
		(mid 190.936256 137.561256)
		(end 190.885 137.685)
		(width 0.09)
		(layer "In9.Cu")
		(net 130)
	)
	(arc
		(start 190.885 137.885)
		(mid 190.833744 138.008744)
		(end 190.71 138.06)
		(width 0.09)
		(layer "In9.Cu")
		(net 130)
	)
	(arc
		(start 196.934226 139.784225)
		(mid 196.894459 139.688218)
		(end 196.798452 139.648451)
		(width 0.09)
		(layer "In9.Cu")
		(net 130)
	)
	(arc
		(start 191.21 137.36)
		(mid 191.166066 137.466066)
		(end 191.06 137.51)
		(width 0.09)
		(layer "In9.Cu")
		(net 130)
	)
	(arc
		(start 191.66 138.11)
		(mid 191.553934 138.066066)
		(end 191.51 137.96)
		(width 0.09)
		(layer "In9.Cu")
		(net 130)
	)
	(arc
		(start 191.36 137.06)
		(mid 191.253934 137.103934)
		(end 191.21 137.21)
		(width 0.09)
		(layer "In9.Cu")
		(net 130)
	)
	(arc
		(start 190.535 137.685)
		(mid 190.483744 137.561256)
		(end 190.36 137.51)
		(width 0.09)
		(layer "In9.Cu")
		(net 130)
	)
	(arc
		(start 192.26 137.51)
		(mid 192.153934 137.466066)
		(end 192.11 137.36)
		(width 0.09)
		(layer "In9.Cu")
		(net 130)
	)
	(arc
		(start 191.96 136.96)
		(mid 191.853934 137.003934)
		(end 191.81 137.11)
		(width 0.09)
		(layer "In9.Cu")
		(net 130)
	)
	(arc
		(start 190.71 138.06)
		(mid 190.586256 138.008744)
		(end 190.535 137.885)
		(width 0.09)
		(layer "In9.Cu")
		(net 130)
	)
	(arc
		(start 191.81 137.96)
		(mid 191.766066 138.066066)
		(end 191.66 138.11)
		(width 0.09)
		(layer "In9.Cu")
		(net 130)
	)
	(arc
		(start 196.77 139.648451)
		(mid 196.673993 139.688218)
		(end 196.634226 139.784225)
		(width 0.09)
		(layer "In9.Cu")
		(net 130)
	)
	(via
		(at 190.1 139.5)
		(size 0.35)
		(drill 0.15)
		(layers "F.Cu" "B.Cu")
		(remove_unused_layers yes)
		(keep_end_layers yes)
		(zone_layer_connections)
		(net 131)
	)
	(via
		(at 200.449 145.451)
		(size 0.35)
		(drill 0.15)
		(layers "F.Cu" "B.Cu")
		(remove_unused_layers yes)
		(keep_end_layers yes)
		(zone_layer_connections)
		(net 131)
	)
	(segment
		(start 194.23 139.9)
		(end 194.54 140.21)
		(width 0.09)
		(layer "In9.Cu")
		(net 131)
	)
	(segment
		(start 193.71 139.4)
		(end 193.71 139.58)
		(width 0.09)
		(layer "In9.Cu")
		(net 131)
	)
	(segment
		(start 194.54 140.51)
		(end 194.811 140.781)
		(width 0.09)
		(layer "In9.Cu")
		(net 131)
	)
	(segment
		(start 194.45 141.93)
		(end 194.45 142.22)
		(width 0.09)
		(layer "In9.Cu")
		(net 131)
	)
	(segment
		(start 195.21 142.24)
		(end 195.21 141.956451)
		(width 0.09)
		(layer "In9.Cu")
		(net 131)
	)
	(segment
		(start 197.801893 141.51)
		(end 197.892893 141.601)
		(width 0.09)
		(layer "In9.Cu")
		(net 131)
	)
	(segment
		(start 195.21 141.956451)
		(end 195.656451 141.51)
		(width 0.09)
		(layer "In9.Cu")
		(net 131)
	)
	(segment
		(start 190.5 138.95)
		(end 190.5 138.884831)
		(width 0.09)
		(layer "In9.Cu")
		(net 131)
	)
	(segment
		(start 191.1 138.95)
		(end 191.1 138.934815)
		(width 0.09)
		(layer "In9.Cu")
		(net 131)
	)
	(segment
		(start 198.45 144.1)
		(end 199.801 145.451)
		(width 0.09)
		(layer "In9.Cu")
		(net 131)
	)
	(segment
		(start 194.54 140.21)
		(end 194.54 140.51)
		(width 0.09)
		(layer "In9.Cu")
		(net 131)
	)
	(segment
		(start 194.59 141.79)
		(end 194.45 141.93)
		(width 0.09)
		(layer "In9.Cu")
		(net 131)
	)
	(segment
		(start 198.051 141.601)
		(end 198.45 142)
		(width 0.09)
		(layer "In9.Cu")
		(net 131)
	)
	(segment
		(start 199.801 145.451)
		(end 200.449 145.451)
		(width 0.09)
		(layer "In9.Cu")
		(net 131)
	)
	(segment
		(start 195.032549 140.781)
		(end 195.22 140.968451)
		(width 0.09)
		(layer "In9.Cu")
		(net 131)
	)
	(segment
		(start 190.8 138.884831)
		(end 190.8 138.95)
		(width 0.09)
		(layer "In9.Cu")
		(net 131)
	)
	(segment
		(start 193.31 139)
		(end 193.71 139.4)
		(width 0.09)
		(layer "In9.Cu")
		(net 131)
	)
	(segment
		(start 193.71 139.58)
		(end 194.03 139.9)
		(width 0.09)
		(layer "In9.Cu")
		(net 131)
	)
	(segment
		(start 197.892893 141.601)
		(end 198.051 141.601)
		(width 0.09)
		(layer "In9.Cu")
		(net 131)
	)
	(segment
		(start 194.811 140.781)
		(end 195.032549 140.781)
		(width 0.09)
		(layer "In9.Cu")
		(net 131)
	)
	(segment
		(start 191.4 138.934815)
		(end 191.4 138.95)
		(width 0.09)
		(layer "In9.Cu")
		(net 131)
	)
	(segment
		(start 192.551549 139.1)
		(end 192.651549 139)
		(width 0.09)
		(layer "In9.Cu")
		(net 131)
	)
	(segment
		(start 194.77 141.79)
		(end 194.59 141.79)
		(width 0.09)
		(layer "In9.Cu")
		(net 131)
	)
	(segment
		(start 195.656451 141.51)
		(end 197.801893 141.51)
		(width 0.09)
		(layer "In9.Cu")
		(net 131)
	)
	(segment
		(start 195.22 140.968451)
		(end 195.22 141.34)
		(width 0.09)
		(layer "In9.Cu")
		(net 131)
	)
	(segment
		(start 195.1 142.35)
		(end 195.21 142.24)
		(width 0.09)
		(layer "In9.Cu")
		(net 131)
	)
	(segment
		(start 192.651549 139)
		(end 193.31 139)
		(width 0.09)
		(layer "In9.Cu")
		(net 131)
	)
	(segment
		(start 190.1 139.5)
		(end 190.1 139.26)
		(width 0.09)
		(layer "In9.Cu")
		(net 131)
	)
	(segment
		(start 194.45 142.22)
		(end 194.58 142.35)
		(width 0.09)
		(layer "In9.Cu")
		(net 131)
	)
	(segment
		(start 194.03 139.9)
		(end 194.23 139.9)
		(width 0.09)
		(layer "In9.Cu")
		(net 131)
	)
	(segment
		(start 190.26 139.1)
		(end 190.35 139.1)
		(width 0.09)
		(layer "In9.Cu")
		(net 131)
	)
	(segment
		(start 194.58 142.35)
		(end 195.1 142.35)
		(width 0.09)
		(layer "In9.Cu")
		(net 131)
	)
	(segment
		(start 191.55 139.1)
		(end 192.551549 139.1)
		(width 0.09)
		(layer "In9.Cu")
		(net 131)
	)
	(segment
		(start 190.1 139.26)
		(end 190.26 139.1)
		(width 0.09)
		(layer "In9.Cu")
		(net 131)
	)
	(segment
		(start 195.22 141.34)
		(end 194.77 141.79)
		(width 0.09)
		(layer "In9.Cu")
		(net 131)
	)
	(segment
		(start 198.45 142)
		(end 198.45 144.1)
		(width 0.09)
		(layer "In9.Cu")
		(net 131)
	)
	(arc
		(start 190.95 139.1)
		(mid 191.056066 139.056066)
		(end 191.1 138.95)
		(width 0.09)
		(layer "In9.Cu")
		(net 131)
	)
	(arc
		(start 191.4 138.95)
		(mid 191.443934 139.056066)
		(end 191.55 139.1)
		(width 0.09)
		(layer "In9.Cu")
		(net 131)
	)
	(arc
		(start 190.35 139.1)
		(mid 190.456066 139.056066)
		(end 190.5 138.95)
		(width 0.09)
		(layer "In9.Cu")
		(net 131)
	)
	(arc
		(start 190.65 138.734831)
		(mid 190.756066 138.778765)
		(end 190.8 138.884831)
		(width 0.09)
		(layer "In9.Cu")
		(net 131)
	)
	(arc
		(start 190.5 138.884831)
		(mid 190.543934 138.778765)
		(end 190.65 138.734831)
		(width 0.09)
		(layer "In9.Cu")
		(net 131)
	)
	(arc
		(start 191.1 138.934815)
		(mid 191.143934 138.828749)
		(end 191.25 138.784815)
		(width 0.09)
		(layer "In9.Cu")
		(net 131)
	)
	(arc
		(start 191.25 138.784815)
		(mid 191.356066 138.828749)
		(end 191.4 138.934815)
		(width 0.09)
		(layer "In9.Cu")
		(net 131)
	)
	(arc
		(start 190.8 138.95)
		(mid 190.843934 139.056066)
		(end 190.95 139.1)
		(width 0.09)
		(layer "In9.Cu")
		(net 131)
	)
	(via
		(at 202.1 136.301)
		(size 0.35)
		(drill 0.15)
		(layers "F.Cu" "B.Cu")
		(remove_unused_layers yes)
		(keep_end_layers yes)
		(zone_layer_connections)
		(net 132)
	)
	(via
		(at 200.12 117.05)
		(size 0.35)
		(drill 0.15)
		(layers "F.Cu" "B.Cu")
		(remove_unused_layers yes)
		(keep_end_layers yes)
		(zone_layer_connections)
		(net 132)
	)
	(segment
		(start 200.12 117.05)
		(end 200.12 117.683591)
		(width 0.09)
		(layer "In7.Cu")
		(net 132)
	)
	(segment
		(start 197.8 133.9)
		(end 198.1 134.2)
		(width 0.09)
		(layer "In7.Cu")
		(net 132)
	)
	(segment
		(start 199.567451 137.58)
		(end 199.38 137.767451)
		(width 0.09)
		(layer "In7.Cu")
		(net 132)
	)
	(segment
		(start 199.38 137.767451)
		(end 199.38 138.106)
		(width 0.09)
		(layer "In7.Cu")
		(net 132)
	)
	(segment
		(start 197.6 133.9)
		(end 197.8 133.9)
		(width 0.09)
		(layer "In7.Cu")
		(net 132)
	)
	(segment
		(start 199.567451 135.867451)
		(end 199.567451 137.58)
		(width 0.09)
		(layer "In7.Cu")
		(net 132)
	)
	(segment
		(start 199.525 120.559316)
		(end 199.525 121.61438)
		(width 0.09)
		(layer "In7.Cu")
		(net 132)
	)
	(segment
		(start 200.115294 118.615294)
		(end 200.115294 119.969022)
		(width 0.09)
		(layer "In7.Cu")
		(net 132)
	)
	(segment
		(start 199.865294 117.938297)
		(end 199.865294 118.365294)
		(width 0.09)
		(layer "In7.Cu")
		(net 132)
	)
	(segment
		(start 197.7 123.43938)
		(end 197.7 128.7)
		(width 0.09)
		(layer "In7.Cu")
		(net 132)
	)
	(segment
		(start 199.5 138.226)
		(end 200.63362 138.226)
		(width 0.09)
		(layer "In7.Cu")
		(net 132)
	)
	(segment
		(start 200.115294 119.969022)
		(end 199.525 120.559316)
		(width 0.09)
		(layer "In7.Cu")
		(net 132)
	)
	(segment
		(start 200.63362 138.226)
		(end 202.1 136.75962)
		(width 0.09)
		(layer "In7.Cu")
		(net 132)
	)
	(segment
		(start 200.12 117.683591)
		(end 199.865294 117.938297)
		(width 0.09)
		(layer "In7.Cu")
		(net 132)
	)
	(segment
		(start 199.38 138.106)
		(end 199.5 138.226)
		(width 0.09)
		(layer "In7.Cu")
		(net 132)
	)
	(segment
		(start 197.7 128.7)
		(end 197.365 129.035)
		(width 0.09)
		(layer "In7.Cu")
		(net 132)
	)
	(segment
		(start 199.525 121.61438)
		(end 197.7 123.43938)
		(width 0.09)
		(layer "In7.Cu")
		(net 132)
	)
	(segment
		(start 198.1 134.4)
		(end 199.567451 135.867451)
		(width 0.09)
		(layer "In7.Cu")
		(net 132)
	)
	(segment
		(start 199.865294 118.365294)
		(end 200.115294 118.615294)
		(width 0.09)
		(layer "In7.Cu")
		(net 132)
	)
	(segment
		(start 198.1 134.2)
		(end 198.1 134.4)
		(width 0.09)
		(layer "In7.Cu")
		(net 132)
	)
	(segment
		(start 197.365 129.035)
		(end 197.365 133.665)
		(width 0.09)
		(layer "In7.Cu")
		(net 132)
	)
	(segment
		(start 202.1 136.75962)
		(end 202.1 136.301)
		(width 0.09)
		(layer "In7.Cu")
		(net 132)
	)
	(segment
		(start 197.365 133.665)
		(end 197.6 133.9)
		(width 0.09)
		(layer "In7.Cu")
		(net 132)
	)
	(via
		(at 199.720588 116.84)
		(size 0.35)
		(drill 0.15)
		(layers "F.Cu" "B.Cu")
		(remove_unused_layers yes)
		(keep_end_layers yes)
		(zone_layer_connections)
		(net 133)
	)
	(via
		(at 201.3 135.5)
		(size 0.35)
		(drill 0.15)
		(layers "F.Cu" "B.Cu")
		(remove_unused_layers yes)
		(keep_end_layers yes)
		(zone_layer_connections)
		(net 133)
	)
	(segment
		(start 199.720588 117.459588)
		(end 199.722 117.461)
		(width 0.15)
		(layer "B.Cu")
		(net 133)
	)
	(segment
		(start 199.720588 116.84)
		(end 199.720588 117.459588)
		(width 0.15)
		(layer "B.Cu")
		(net 133)
	)
	(segment
		(start 196.175 132.17538)
		(end 196.175 130.3)
		(width 0.09)
		(layer "In7.Cu")
		(net 133)
	)
	(segment
		(start 198.7455 138.221)
		(end 198.25 137.7255)
		(width 0.09)
		(layer "In7.Cu")
		(net 133)
	)
	(segment
		(start 198.25 137.05)
		(end 198.45 136.85)
		(width 0.09)
		(layer "In7.Cu")
		(net 133)
	)
	(segment
		(start 202.42 136.694178)
		(end 202.3 136.814178)
		(width 0.09)
		(layer "In7.Cu")
		(net 133)
	)
	(segment
		(start 199.665294 116.895294)
		(end 199.720588 116.84)
		(width 0.09)
		(layer "In7.Cu")
		(net 133)
	)
	(segment
		(start 197.38 134.18)
		(end 197.02 133.82)
		(width 0.09)
		(layer "In7.Cu")
		(net 133)
	)
	(segment
		(start 198.45 136.85)
		(end 198.45 135.25)
		(width 0.09)
		(layer "In7.Cu")
		(net 133)
	)
	(segment
		(start 199.275 120.526474)
		(end 199.875 119.926474)
		(width 0.09)
		(layer "In7.Cu")
		(net 133)
	)
	(segment
		(start 199.665294 118.565294)
		(end 199.665294 116.895294)
		(width 0.09)
		(layer "In7.Cu")
		(net 133)
	)
	(segment
		(start 196.95 129.525)
		(end 196.95 123.425)
		(width 0.09)
		(layer "In7.Cu")
		(net 133)
	)
	(segment
		(start 199.875 118.775)
		(end 199.665294 118.565294)
		(width 0.09)
		(layer "In7.Cu")
		(net 133)
	)
	(segment
		(start 202.227549 135.976)
		(end 202.42 136.168451)
		(width 0.09)
		(layer "In7.Cu")
		(net 133)
	)
	(segment
		(start 198.921 138.221)
		(end 198.7455 138.221)
		(width 0.09)
		(layer "In7.Cu")
		(net 133)
	)
	(segment
		(start 200.824 138.83462)
		(end 200.55862 139.1)
		(width 0.09)
		(layer "In7.Cu")
		(net 133)
	)
	(segment
		(start 201.3 135.5)
		(end 201.776 135.976)
		(width 0.09)
		(layer "In7.Cu")
		(net 133)
	)
	(segment
		(start 200.824 138.476)
		(end 200.824 138.83462)
		(width 0.09)
		(layer "In7.Cu")
		(net 133)
	)
	(segment
		(start 197.567451 134.62)
		(end 197.38 134.432549)
		(width 0.09)
		(layer "In7.Cu")
		(net 133)
	)
	(segment
		(start 202.42 136.168451)
		(end 202.42 136.694178)
		(width 0.09)
		(layer "In7.Cu")
		(net 133)
	)
	(segment
		(start 196.54 133.592549)
		(end 196.54 132.54038)
		(width 0.09)
		(layer "In7.Cu")
		(net 133)
	)
	(segment
		(start 196.54 132.54038)
		(end 196.175 132.17538)
		(width 0.09)
		(layer "In7.Cu")
		(net 133)
	)
	(segment
		(start 196.175 130.3)
		(end 196.95 129.525)
		(width 0.09)
		(layer "In7.Cu")
		(net 133)
	)
	(segment
		(start 199.275 121.1)
		(end 199.275 120.526474)
		(width 0.09)
		(layer "In7.Cu")
		(net 133)
	)
	(segment
		(start 196.767451 133.82)
		(end 196.54 133.592549)
		(width 0.09)
		(layer "In7.Cu")
		(net 133)
	)
	(segment
		(start 197.02 133.82)
		(end 196.767451 133.82)
		(width 0.09)
		(layer "In7.Cu")
		(net 133)
	)
	(segment
		(start 199.875 119.926474)
		(end 199.875 118.775)
		(width 0.09)
		(layer "In7.Cu")
		(net 133)
	)
	(segment
		(start 198.25 137.7255)
		(end 198.25 137.05)
		(width 0.09)
		(layer "In7.Cu")
		(net 133)
	)
	(segment
		(start 201.776 135.976)
		(end 202.227549 135.976)
		(width 0.09)
		(layer "In7.Cu")
		(net 133)
	)
	(segment
		(start 197.38 134.432549)
		(end 197.38 134.18)
		(width 0.09)
		(layer "In7.Cu")
		(net 133)
	)
	(segment
		(start 200.55862 139.1)
		(end 199.8 139.1)
		(width 0.09)
		(layer "In7.Cu")
		(net 133)
	)
	(segment
		(start 198.45 135.25)
		(end 197.82 134.62)
		(width 0.09)
		(layer "In7.Cu")
		(net 133)
	)
	(segment
		(start 199.8 139.1)
		(end 198.921 138.221)
		(width 0.09)
		(layer "In7.Cu")
		(net 133)
	)
	(segment
		(start 196.95 123.425)
		(end 199.275 121.1)
		(width 0.09)
		(layer "In7.Cu")
		(net 133)
	)
	(segment
		(start 197.82 134.62)
		(end 197.567451 134.62)
		(width 0.09)
		(layer "In7.Cu")
		(net 133)
	)
	(segment
		(start 202.3 137)
		(end 200.824 138.476)
		(width 0.09)
		(layer "In7.Cu")
		(net 133)
	)
	(segment
		(start 202.3 136.814178)
		(end 202.3 137)
		(width 0.09)
		(layer "In7.Cu")
		(net 133)
	)
	(via
		(at 200.499 135.5)
		(size 0.35)
		(drill 0.15)
		(layers "F.Cu" "B.Cu")
		(remove_unused_layers yes)
		(keep_end_layers yes)
		(zone_layer_connections)
		(net 134)
	)
	(via
		(at 199.322 117.05)
		(size 0.35)
		(drill 0.15)
		(layers "F.Cu" "B.Cu")
		(remove_unused_layers yes)
		(keep_end_layers yes)
		(zone_layer_connections)
		(net 134)
	)
	(segment
		(start 193.779 131.619407)
		(end 193.779 122.062593)
		(width 0.09)
		(layer "In9.Cu")
		(net 134)
	)
	(segment
		(start 200.02 120.53)
		(end 200.775 119.775)
		(width 0.09)
		(layer "In9.Cu")
		(net 134)
	)
	(segment
		(start 200.775 119.775)
		(end 201.380332 119.775)
		(width 0.09)
		(layer "In9.Cu")
		(net 134)
	)
	(segment
		(start 201.686829 118.47)
		(end 201.095 118.47)
		(width 0.09)
		(layer "In9.Cu")
		(net 134)
	)
	(segment
		(start 200.499 135.5)
		(end 200.05 135.051)
		(width 0.09)
		(layer "In9.Cu")
		(net 134)
	)
	(segment
		(start 201.706481 118.489652)
		(end 201.686829 118.47)
		(width 0.09)
		(layer "In9.Cu")
		(net 134)
	)
	(segment
		(start 195.311593 120.53)
		(end 200.02 120.53)
		(width 0.09)
		(layer "In9.Cu")
		(net 134)
	)
	(segment
		(start 201.095 118.47)
		(end 200.125 117.5)
		(width 0.09)
		(layer "In9.Cu")
		(net 134)
	)
	(segment
		(start 195.685 131.96)
		(end 194.119593 131.96)
		(width 0.09)
		(layer "In9.Cu")
		(net 134)
	)
	(segment
		(start 199.772 117.5)
		(end 199.322 117.05)
		(width 0.09)
		(layer "In9.Cu")
		(net 134)
	)
	(segment
		(start 194.119593 131.96)
		(end 193.779 131.619407)
		(width 0.09)
		(layer "In9.Cu")
		(net 134)
	)
	(segment
		(start 200.05 133.3)
		(end 199.12 132.37)
		(width 0.09)
		(layer "In9.Cu")
		(net 134)
	)
	(segment
		(start 196.095 132.37)
		(end 195.685 131.96)
		(width 0.09)
		(layer "In9.Cu")
		(net 134)
	)
	(segment
		(start 200.05 135.051)
		(end 200.05 133.3)
		(width 0.09)
		(layer "In9.Cu")
		(net 134)
	)
	(segment
		(start 201.380332 119.775)
		(end 201.706481 119.448851)
		(width 0.09)
		(layer "In9.Cu")
		(net 134)
	)
	(segment
		(start 201.706481 119.448851)
		(end 201.706481 118.489652)
		(width 0.09)
		(layer "In9.Cu")
		(net 134)
	)
	(segment
		(start 199.12 132.37)
		(end 196.095 132.37)
		(width 0.09)
		(layer "In9.Cu")
		(net 134)
	)
	(segment
		(start 193.779 122.062593)
		(end 195.311593 120.53)
		(width 0.09)
		(layer "In9.Cu")
		(net 134)
	)
	(segment
		(start 200.125 117.5)
		(end 199.772 117.5)
		(width 0.09)
		(layer "In9.Cu")
		(net 134)
	)
	(via
		(at 206.1 128.3)
		(size 0.35)
		(drill 0.15)
		(layers "F.Cu" "B.Cu")
		(remove_unused_layers yes)
		(keep_end_layers yes)
		(zone_layer_connections)
		(net 135)
	)
	(segment
		(start 201.5 122.15)
		(end 201.65 122)
		(width 0.1)
		(layer "B.Cu")
		(net 135)
	)
	(segment
		(start 200.658924 121.500558)
		(end 200.468544 121.310178)
		(width 0.1)
		(layer "B.Cu")
		(net 135)
	)
	(segment
		(start 206.1 128.3)
		(end 205.775 127.975)
		(width 0.1)
		(layer "B.Cu")
		(net 135)
	)
	(segment
		(start 201.65 124.1)
		(end 201.5 123.95)
		(width 0.1)
		(layer "B.Cu")
		(net 135)
	)
	(segment
		(start 200.25 120.7)
		(end 199.021 120.7)
		(width 0.1)
		(layer "B.Cu")
		(net 135)
	)
	(segment
		(start 202.11538 127.975)
		(end 201.65 127.50962)
		(width 0.1)
		(layer "B.Cu")
		(net 135)
	)
	(segment
		(start 201.65 121.75)
		(end 201.400558 121.500558)
		(width 0.1)
		(layer "B.Cu")
		(net 135)
	)
	(segment
		(start 200.468544 121.310178)
		(end 200.468544 120.918544)
		(width 0.1)
		(layer "B.Cu")
		(net 135)
	)
	(segment
		(start 198.922 120.601)
		(end 198.922 120.171)
		(width 0.1)
		(layer "B.Cu")
		(net 135)
	)
	(segment
		(start 201.5 123.95)
		(end 201.5 122.15)
		(width 0.1)
		(layer "B.Cu")
		(net 135)
	)
	(segment
		(start 201.65 122)
		(end 201.65 121.75)
		(width 0.1)
		(layer "B.Cu")
		(net 135)
	)
	(segment
		(start 200.468544 120.918544)
		(end 200.25 120.7)
		(width 0.1)
		(layer "B.Cu")
		(net 135)
	)
	(segment
		(start 199.021 120.7)
		(end 198.922 120.601)
		(width 0.1)
		(layer "B.Cu")
		(net 135)
	)
	(segment
		(start 201.65 127.50962)
		(end 201.65 124.1)
		(width 0.1)
		(layer "B.Cu")
		(net 135)
	)
	(segment
		(start 205.775 127.975)
		(end 202.11538 127.975)
		(width 0.1)
		(layer "B.Cu")
		(net 135)
	)
	(segment
		(start 201.400558 121.500558)
		(end 200.658924 121.500558)
		(width 0.1)
		(layer "B.Cu")
		(net 135)
	)
	(via
		(at 190.1 141.101)
		(size 0.35)
		(drill 0.15)
		(layers "F.Cu" "B.Cu")
		(remove_unused_layers yes)
		(keep_end_layers yes)
		(zone_layer_connections)
		(net 136)
	)
	(via
		(at 201.1 144.8)
		(size 0.35)
		(drill 0.15)
		(layers "F.Cu" "B.Cu")
		(remove_unused_layers yes)
		(keep_end_layers yes)
		(zone_layer_connections)
		(net 136)
	)
	(segment
		(start 191.705 145.075)
		(end 191.45 144.82)
		(width 0.09)
		(layer "In9.Cu")
		(net 136)
	)
	(segment
		(start 193.755 145.075)
		(end 191.705 145.075)
		(width 0.09)
		(layer "In9.Cu")
		(net 136)
	)
	(segment
		(start 189.88 141.93)
		(end 189.88 141.321)
		(width 0.09)
		(layer "In9.Cu")
		(net 136)
	)
	(segment
		(start 197.31 145.68)
		(end 194.36 145.68)
		(width 0.09)
		(layer "In9.Cu")
		(net 136)
	)
	(segment
		(start 194.36 145.68)
		(end 193.755 145.075)
		(width 0.09)
		(layer "In9.Cu")
		(net 136)
	)
	(segment
		(start 191.45 144.82)
		(end 191.45 143.5)
		(width 0.09)
		(layer "In9.Cu")
		(net 136)
	)
	(segment
		(start 201.46 147.11)
		(end 201.02 147.55)
		(width 0.09)
		(layer "In9.Cu")
		(net 136)
	)
	(segment
		(start 201.1 144.8)
		(end 201.46 145.16)
		(width 0.09)
		(layer "In9.Cu")
		(net 136)
	)
	(segment
		(start 201.02 147.55)
		(end 199.18 147.55)
		(width 0.09)
		(layer "In9.Cu")
		(net 136)
	)
	(segment
		(start 199.18 147.55)
		(end 197.31 145.68)
		(width 0.09)
		(layer "In9.Cu")
		(net 136)
	)
	(segment
		(start 189.88 141.321)
		(end 190.1 141.101)
		(width 0.09)
		(layer "In9.Cu")
		(net 136)
	)
	(segment
		(start 191.45 143.5)
		(end 189.88 141.93)
		(width 0.09)
		(layer "In9.Cu")
		(net 136)
	)
	(segment
		(start 201.46 145.16)
		(end 201.46 147.11)
		(width 0.09)
		(layer "In9.Cu")
		(net 136)
	)
	(segment
		(start 212.9435 133.949)
		(end 212.9435 134.449)
		(width 0.177)
		(layer "F.Cu")
		(net 137)
	)
	(segment
		(start 212.9435 134.449)
		(end 212.9435 134.461653)
		(width 0.177)
		(layer "F.Cu")
		(net 137)
	)
	(segment
		(start 212.9435 134.461653)
		(end 213.509597 135.02775)
		(width 0.177)
		(layer "F.Cu")
		(net 137)
	)
	(segment
		(start 213.509597 135.02775)
		(end 213.52225 135.02775)
		(width 0.177)
		(layer "F.Cu")
		(net 137)
	)
	(segment
		(start 212.9435 134.449)
		(end 212.4435 134.949)
		(width 0.177)
		(layer "F.Cu")
		(net 137)
	)
	(via
		(at 213.9435 129.45)
		(size 0.35)
		(drill 0.15)
		(layers "F.Cu" "B.Cu")
		(remove_unused_layers yes)
		(keep_end_layers yes)
		(zone_layer_connections "In11.Cu")
		(net 137)
	)
	(via
		(at 199.699 127.5)
		(size 0.35)
		(drill 0.15)
		(layers "F.Cu" "B.Cu")
		(remove_unused_layers yes)
		(keep_end_layers yes)
		(zone_layer_connections "In11.Cu")
		(net 137)
	)
	(via
		(at 212.9435 133.949)
		(size 0.35)
		(drill 0.15)
		(layers "F.Cu" "B.Cu")
		(remove_unused_layers yes)
		(keep_end_layers yes)
		(zone_layer_connections "In11.Cu")
		(net 137)
	)
	(via
		(at 212.4435 134.949)
		(size 0.35)
		(drill 0.15)
		(layers "F.Cu" "B.Cu")
		(remove_unused_layers yes)
		(keep_end_layers yes)
		(zone_layer_connections "In11.Cu")
		(net 137)
	)
	(via
		(at 211.45 128.05)
		(size 0.35)
		(drill 0.15)
		(layers "F.Cu" "B.Cu")
		(remove_unused_layers yes)
		(keep_end_layers yes)
		(zone_layer_connections "In11.Cu")
		(net 137)
	)
	(via
		(at 198.899 125.101)
		(size 0.35)
		(drill 0.15)
		(layers "F.Cu" "B.Cu")
		(remove_unused_layers yes)
		(keep_end_layers yes)
		(zone_layer_connections "In11.Cu")
		(net 137)
	)
	(via
		(at 213.52225 135.02775)
		(size 0.35)
		(drill 0.15)
		(layers "F.Cu" "B.Cu")
		(remove_unused_layers yes)
		(keep_end_layers yes)
		(zone_layer_connections "In11.Cu")
		(net 137)
	)
	(segment
		(start 212.6725 132.2225)
		(end 212.41 131.96)
		(width 0.256)
		(layer "B.Cu")
		(net 137)
	)
	(segment
		(start 199.2745 124.7255)
		(end 198.899 125.101)
		(width 0.201)
		(layer "B.Cu")
		(net 137)
	)
	(segment
		(start 211.45 128.05)
		(end 211.35 128.15)
		(width 0.256)
		(layer "B.Cu")
		(net 137)
	)
	(segment
		(start 199.2745 124.2)
		(end 199.2745 123.4755)
		(width 0.201)
		(layer "B.Cu")
		(net 137)
	)
	(segment
		(start 212.9435 133.949)
		(end 212.9435 133.832794)
		(width 0.177)
		(layer "B.Cu")
		(net 137)
	)
	(segment
		(start 213.00325 135.02775)
		(end 212.6725 134.697)
		(width 0.4)
		(layer "B.Cu")
		(net 137)
	)
	(segment
		(start 210.6725 132.347)
		(end 210.6725 127.347)
		(width 0.256)
		(layer "B.Cu")
		(net 137)
	)
	(segment
		(start 216.2695 137.775)
		(end 218.495 137.775)
		(width 0.4)
		(layer "B.Cu")
		(net 137)
	)
	(segment
		(start 199.95 122.8)
		(end 199.95 122.18)
		(width 0.201)
		(layer "B.Cu")
		(net 137)
	)
	(segment
		(start 213.52225 135.02775)
		(end 216.2695 137.775)
		(width 0.4)
		(layer "B.Cu")
		(net 137)
	)
	(segment
		(start 212.4435 134.949)
		(end 212.0455 135.347)
		(width 0.177)
		(layer "B.Cu")
		(net 137)
	)
	(segment
		(start 211.35 128.15)
		(end 210.88 128.15)
		(width 0.256)
		(layer "B.Cu")
		(net 137)
	)
	(segment
		(start 212.5875 127.347)
		(end 212.6425 127.292)
		(width 0.256)
		(layer "B.Cu")
		(net 137)
	)
	(segment
		(start 198.5235 125.4765)
		(end 197.5075 125.4765)
		(width 0.201)
		(layer "B.Cu")
		(net 137)
	)
	(segment
		(start 199.2745 123.5705)
		(end 199.2745 124.2)
		(width 0.201)
		(layer "B.Cu")
		(net 137)
	)
	(segment
		(start 211.45 127.4845)
		(end 211.6425 127.292)
		(width 0.256)
		(layer "B.Cu")
		(net 137)
	)
	(segment
		(start 212.6725 134.697)
		(end 212.6725 132.697)
		(width 0.4)
		(layer "B.Cu")
		(net 137)
	)
	(segment
		(start 213.9435 129.45)
		(end 214.1615 129.668)
		(width 0.177)
		(layer "B.Cu")
		(net 137)
	)
	(segment
		(start 210.6575 134.347)
		(end 210.6575 135.347)
		(width 0.256)
		(layer "B.Cu")
		(net 137)
	)
	(segment
		(start 199.2745 123.4755)
		(end 199.95 122.8)
		(width 0.201)
		(layer "B.Cu")
		(net 137)
	)
	(segment
		(start 197.5075 125.4765)
		(end 197.299 125.268)
		(width 0.201)
		(layer "B.Cu")
		(net 137)
	)
	(segment
		(start 198.899 125.101)
		(end 198.5235 125.4765)
		(width 0.201)
		(layer "B.Cu")
		(net 137)
	)
	(segment
		(start 213.52225 135.02775)
		(end 213.00325 135.02775)
		(width 0.4)
		(layer "B.Cu")
		(net 137)
	)
	(segment
		(start 212.0455 135.347)
		(end 210.6575 135.347)
		(width 0.177)
		(layer "B.Cu")
		(net 137)
	)
	(segment
		(start 210.88 128.15)
		(end 210.68 128.35)
		(width 0.256)
		(layer "B.Cu")
		(net 137)
	)
	(segment
		(start 212.41 131.96)
		(end 211.64 131.96)
		(width 0.256)
		(layer "B.Cu")
		(net 137)
	)
	(segment
		(start 214.1615 129.668)
		(end 214.5905 129.668)
		(width 0.177)
		(layer "B.Cu")
		(net 137)
	)
	(segment
		(start 212.6725 132.697)
		(end 212.6725 132.2225)
		(width 0.256)
		(layer "B.Cu")
		(net 137)
	)
	(segment
		(start 211.45 128.05)
		(end 211.45 127.4845)
		(width 0.256)
		(layer "B.Cu")
		(net 137)
	)
	(segment
		(start 199.264 123.56)
		(end 199.2745 123.5705)
		(width 0.201)
		(layer "B.Cu")
		(net 137)
	)
	(segment
		(start 210.6725 127.347)
		(end 212.5875 127.347)
		(width 0.256)
		(layer "B.Cu")
		(net 137)
	)
	(segment
		(start 199.2745 124.2)
		(end 199.2745 124.7255)
		(width 0.201)
		(layer "B.Cu")
		(net 137)
	)
	(segment
		(start 211.027 131.347)
		(end 210.6725 131.347)
		(width 0.256)
		(layer "B.Cu")
		(net 137)
	)
	(segment
		(start 211.64 131.96)
		(end 211.027 131.347)
		(width 0.256)
		(layer "B.Cu")
		(net 137)
	)
	(via
		(at 198.872 154.9)
		(size 0.35)
		(drill 0.15)
		(layers "F.Cu" "B.Cu")
		(remove_unused_layers yes)
		(keep_end_layers yes)
		(zone_layer_connections)
		(net 138)
	)
	(via
		(at 198.899 140.3)
		(size 0.35)
		(drill 0.15)
		(layers "F.Cu" "B.Cu")
		(remove_unused_layers yes)
		(keep_end_layers yes)
		(zone_layer_connections)
		(net 138)
	)
	(segment
		(start 199.0145 154.4785)
		(end 199.0145 154.7575)
		(width 0.125)
		(layer "B.Cu")
		(net 138)
	)
	(segment
		(start 198.922 154.386)
		(end 199.0145 154.4785)
		(width 0.125)
		(layer "B.Cu")
		(net 138)
	)
	(segment
		(start 198.922 154.171)
		(end 198.922 154.386)
		(width 0.125)
		(layer "B.Cu")
		(net 138)
	)
	(segment
		(start 199.0145 154.7575)
		(end 198.872 154.9)
		(width 0.125)
		(layer "B.Cu")
		(net 138)
	)
	(segment
		(start 198.699 141.609578)
		(end 198.699 141.36062)
		(width 0.1)
		(layer "In4.Cu")
		(net 138)
	)
	(segment
		(start 198.2 142.108578)
		(end 198.699 141.609578)
		(width 0.1)
		(layer "In4.Cu")
		(net 138)
	)
	(segment
		(start 198.574 141.23562)
		(end 198.574 140.96638)
		(width 0.1)
		(layer "In4.Cu")
		(net 138)
	)
	(segment
		(start 198.2 148.681422)
		(end 198.2 142.108578)
		(width 0.1)
		(layer "In4.Cu")
		(net 138)
	)
	(segment
		(start 198.872 154.9)
		(end 199.022 154.75)
		(width 0.1)
		(layer "In4.Cu")
		(net 138)
	)
	(segment
		(start 198.699 140.5)
		(end 198.899 140.3)
		(width 0.1)
		(layer "In4.Cu")
		(net 138)
	)
	(segment
		(start 198.699 141.36062)
		(end 198.574 141.23562)
		(width 0.1)
		(layer "In4.Cu")
		(net 138)
	)
	(segment
		(start 199.022 149.503422)
		(end 198.2 148.681422)
		(width 0.1)
		(layer "In4.Cu")
		(net 138)
	)
	(segment
		(start 198.574 140.96638)
		(end 198.699 140.84138)
		(width 0.1)
		(layer "In4.Cu")
		(net 138)
	)
	(segment
		(start 199.022 154.75)
		(end 199.022 149.503422)
		(width 0.1)
		(layer "In4.Cu")
		(net 138)
	)
	(segment
		(start 198.699 140.84138)
		(end 198.699 140.5)
		(width 0.1)
		(layer "In4.Cu")
		(net 138)
	)
	(via
		(at 197.299 140.3)
		(size 0.35)
		(drill 0.15)
		(layers "F.Cu" "B.Cu")
		(remove_unused_layers yes)
		(keep_end_layers yes)
		(zone_layer_connections)
		(net 139)
	)
	(via
		(at 197.3245 153.2555)
		(size 0.35)
		(drill 0.15)
		(layers "F.Cu" "B.Cu")
		(remove_unused_layers yes)
		(keep_end_layers yes)
		(zone_layer_connections)
		(net 139)
	)
	(segment
		(start 198.0295 152.048501)
		(end 198.0295 152.797528)
		(width 0.125)
		(layer "B.Cu")
		(net 139)
	)
	(segment
		(start 198.122 151.461)
		(end 198.122 151.956001)
		(width 0.125)
		(layer "B.Cu")
		(net 139)
	)
	(segment
		(start 198.0295 152.797528)
		(end 197.691278 153.13575)
		(width 0.125)
		(layer "B.Cu")
		(net 139)
	)
	(segment
		(start 197.44425 153.13575)
		(end 197.3245 153.2555)
		(width 0.125)
		(layer "B.Cu")
		(net 139)
	)
	(segment
		(start 197.691278 153.13575)
		(end 197.44425 153.13575)
		(width 0.125)
		(layer "B.Cu")
		(net 139)
	)
	(segment
		(start 198.122 151.956001)
		(end 198.0295 152.048501)
		(width 0.125)
		(layer "B.Cu")
		(net 139)
	)
	(segment
		(start 196.2 145.981422)
		(end 197.57 144.611422)
		(width 0.1)
		(layer "In4.Cu")
		(net 139)
	)
	(segment
		(start 197.57 143.218578)
		(end 197.025728 142.674306)
		(width 0.1)
		(layer "In4.Cu")
		(net 139)
	)
	(segment
		(start 197.753172 153.12825)
		(end 197.45175 153.12825)
		(width 0.1)
		(layer "In4.Cu")
		(net 139)
	)
	(segment
		(start 197.45175 153.12825)
		(end 197.3245 153.2555)
		(width 0.1)
		(layer "In4.Cu")
		(net 139)
	)
	(segment
		(start 198.02 149.818578)
		(end 196.2 147.998578)
		(width 0.1)
		(layer "In4.Cu")
		(net 139)
	)
	(segment
		(start 196.2 147.998578)
		(end 196.2 145.981422)
		(width 0.1)
		(layer "In4.Cu")
		(net 139)
	)
	(segment
		(start 197.57 144.611422)
		(end 197.57 143.218578)
		(width 0.1)
		(layer "In4.Cu")
		(net 139)
	)
	(segment
		(start 197.025728 142.674306)
		(end 197.025728 142.140694)
		(width 0.1)
		(layer "In4.Cu")
		(net 139)
	)
	(segment
		(start 197.4 141.5)
		(end 197.624 141.276)
		(width 0.1)
		(layer "In4.Cu")
		(net 139)
	)
	(segment
		(start 197.499 140.84138)
		(end 197.499 140.5)
		(width 0.1)
		(layer "In4.Cu")
		(net 139)
	)
	(segment
		(start 197.753172 153.12825)
		(end 198.02 152.861422)
		(width 0.1)
		(layer "In4.Cu")
		(net 139)
	)
	(segment
		(start 197.624 140.96638)
		(end 197.499 140.84138)
		(width 0.1)
		(layer "In4.Cu")
		(net 139)
	)
	(segment
		(start 197.499 140.5)
		(end 197.299 140.3)
		(width 0.1)
		(layer "In4.Cu")
		(net 139)
	)
	(segment
		(start 197.4 141.766422)
		(end 197.4 141.5)
		(width 0.1)
		(layer "In4.Cu")
		(net 139)
	)
	(segment
		(start 197.624 141.276)
		(end 197.624 140.96638)
		(width 0.1)
		(layer "In4.Cu")
		(net 139)
	)
	(segment
		(start 197.025728 142.140694)
		(end 197.4 141.766422)
		(width 0.1)
		(layer "In4.Cu")
		(net 139)
	)
	(segment
		(start 198.02 152.861422)
		(end 198.02 149.818578)
		(width 0.1)
		(layer "In4.Cu")
		(net 139)
	)
	(via
		(at 197.299 141.101)
		(size 0.35)
		(drill 0.15)
		(layers "F.Cu" "B.Cu")
		(remove_unused_layers yes)
		(keep_end_layers yes)
		(zone_layer_connections)
		(net 140)
	)
	(via
		(at 197.3245 152.801)
		(size 0.35)
		(drill 0.15)
		(layers "F.Cu" "B.Cu")
		(remove_unused_layers yes)
		(keep_end_layers yes)
		(zone_layer_connections)
		(net 140)
	)
	(segment
		(start 197.8145 152.708472)
		(end 197.602222 152.92075)
		(width 0.125)
		(layer "B.Cu")
		(net 140)
	)
	(segment
		(start 197.722 151.956001)
		(end 197.8145 152.048501)
		(width 0.125)
		(layer "B.Cu")
		(net 140)
	)
	(segment
		(start 197.722 151.461)
		(end 197.722 151.956001)
		(width 0.125)
		(layer "B.Cu")
		(net 140)
	)
	(segment
		(start 197.8145 152.048501)
		(end 197.8145 152.708472)
		(width 0.125)
		(layer "B.Cu")
		(net 140)
	)
	(segment
		(start 197.602222 152.92075)
		(end 197.44425 152.92075)
		(width 0.125)
		(layer "B.Cu")
		(net 140)
	)
	(segment
		(start 197.44425 152.92075)
		(end 197.3245 152.801)
		(width 0.125)
		(layer "B.Cu")
		(net 140)
	)
	(segment
		(start 197.655839 151.75)
		(end 197.695 151.75)
		(width 0.1)
		(layer "In4.Cu")
		(net 140)
	)
	(segment
		(start 196.964 140.851)
		(end 197.039 140.776)
		(width 0.1)
		(layer "In4.Cu")
		(net 140)
	)
	(segment
		(start 197.2 141.5)
		(end 196.964 141.264)
		(width 0.1)
		(layer "In4.Cu")
		(net 140)
	)
	(segment
		(start 197.670328 152.92825)
		(end 197.82 152.778578)
		(width 0.1)
		(layer "In4.Cu")
		(net 140)
	)
	(segment
		(start 197.655839 151.25)
		(end 197.695 151.25)
		(width 0.1)
		(layer "In4.Cu")
		(net 140)
	)
	(segment
		(start 196.825728 142.05785)
		(end 197.2 141.683578)
		(width 0.1)
		(layer "In4.Cu")
		(net 140)
	)
	(segment
		(start 197.82 149.901422)
		(end 196 148.081422)
		(width 0.1)
		(layer "In4.Cu")
		(net 140)
	)
	(segment
		(start 197.2 141.683578)
		(end 197.2 141.5)
		(width 0.1)
		(layer "In4.Cu")
		(net 140)
	)
	(segment
		(start 197.289 141.091)
		(end 197.299 141.101)
		(width 0.1)
		(layer "In4.Cu")
		(net 140)
	)
	(segment
		(start 197.45175 152.92825)
		(end 197.670328 152.92825)
		(width 0.1)
		(layer "In4.Cu")
		(net 140)
	)
	(segment
		(start 197.289 140.8385)
		(end 197.289 141.091)
		(width 0.1)
		(layer "In4.Cu")
		(net 140)
	)
	(segment
		(start 197.37 144.528578)
		(end 197.37 143.301422)
		(width 0.1)
		(layer "In4.Cu")
		(net 140)
	)
	(segment
		(start 197.695 151.5)
		(end 197.655839 151.5)
		(width 0.1)
		(layer "In4.Cu")
		(net 140)
	)
	(segment
		(start 197.2265 140.776)
		(end 197.289 140.8385)
		(width 0.1)
		(layer "In4.Cu")
		(net 140)
	)
	(segment
		(start 196.964 141.264)
		(end 196.964 140.851)
		(width 0.1)
		(layer "In4.Cu")
		(net 140)
	)
	(segment
		(start 197.82 151.125)
		(end 197.82 149.901422)
		(width 0.1)
		(layer "In4.Cu")
		(net 140)
	)
	(segment
		(start 197.37 143.301422)
		(end 196.825728 142.75715)
		(width 0.1)
		(layer "In4.Cu")
		(net 140)
	)
	(segment
		(start 196.825728 142.75715)
		(end 196.825728 142.05785)
		(width 0.1)
		(layer "In4.Cu")
		(net 140)
	)
	(segment
		(start 196 145.898578)
		(end 197.37 144.528578)
		(width 0.1)
		(layer "In4.Cu")
		(net 140)
	)
	(segment
		(start 197.82 152.778578)
		(end 197.82 152.125)
		(width 0.1)
		(layer "In4.Cu")
		(net 140)
	)
	(segment
		(start 196 148.081422)
		(end 196 145.898578)
		(width 0.1)
		(layer "In4.Cu")
		(net 140)
	)
	(segment
		(start 197.3245 152.801)
		(end 197.45175 152.92825)
		(width 0.1)
		(layer "In4.Cu")
		(net 140)
	)
	(segment
		(start 197.695 152)
		(end 197.655839 152)
		(width 0.1)
		(layer "In4.Cu")
		(net 140)
	)
	(segment
		(start 197.039 140.776)
		(end 197.2265 140.776)
		(width 0.1)
		(layer "In4.Cu")
		(net 140)
	)
	(arc
		(start 197.530839 151.375)
		(mid 197.567451 151.286612)
		(end 197.655839 151.25)
		(width 0.1)
		(layer "In4.Cu")
		(net 140)
	)
	(arc
		(start 197.82 151.625)
		(mid 197.783388 151.536612)
		(end 197.695 151.5)
		(width 0.1)
		(layer "In4.Cu")
		(net 140)
	)
	(arc
		(start 197.655839 152)
		(mid 197.567451 151.963388)
		(end 197.530839 151.875)
		(width 0.1)
		(layer "In4.Cu")
		(net 140)
	)
	(arc
		(start 197.695 151.75)
		(mid 197.783388 151.713388)
		(end 197.82 151.625)
		(width 0.1)
		(layer "In4.Cu")
		(net 140)
	)
	(arc
		(start 197.655839 151.5)
		(mid 197.567451 151.463388)
		(end 197.530839 151.375)
		(width 0.1)
		(layer "In4.Cu")
		(net 140)
	)
	(arc
		(start 197.530839 151.875)
		(mid 197.567451 151.786612)
		(end 197.655839 151.75)
		(width 0.1)
		(layer "In4.Cu")
		(net 140)
	)
	(arc
		(start 197.82 152.125)
		(mid 197.783388 152.036612)
		(end 197.695 152)
		(width 0.1)
		(layer "In4.Cu")
		(net 140)
	)
	(arc
		(start 197.695 151.25)
		(mid 197.783388 151.213388)
		(end 197.82 151.125)
		(width 0.1)
		(layer "In4.Cu")
		(net 140)
	)
	(via
		(at 196.972 154.9)
		(size 0.35)
		(drill 0.15)
		(layers "F.Cu" "B.Cu")
		(remove_unused_layers yes)
		(keep_end_layers yes)
		(zone_layer_connections)
		(net 141)
	)
	(via
		(at 194.9 139.5)
		(size 0.35)
		(drill 0.15)
		(layers "F.Cu" "B.Cu")
		(remove_unused_layers yes)
		(keep_end_layers yes)
		(zone_layer_connections)
		(net 141)
	)
	(segment
		(start 196.922 154.171)
		(end 196.922 154.386)
		(width 0.125)
		(layer "B.Cu")
		(net 141)
	)
	(segment
		(start 196.922 154.386)
		(end 196.8295 154.4785)
		(width 0.125)
		(layer "B.Cu")
		(net 141)
	)
	(segment
		(start 196.8295 154.4785)
		(end 196.8295 154.7575)
		(width 0.125)
		(layer "B.Cu")
		(net 141)
	)
	(segment
		(start 196.8295 154.7575)
		(end 196.972 154.9)
		(width 0.125)
		(layer "B.Cu")
		(net 141)
	)
	(segment
		(start 193.671445 142.822111)
		(end 193.671444 142.822111)
		(width 0.1)
		(layer "In4.Cu")
		(net 141)
	)
	(segment
		(start 193.461557 143.036487)
		(end 193.459314 143.034244)
		(width 0.1)
		(layer "In4.Cu")
		(net 141)
	)
	(segment
		(start 194.491422 139.2)
		(end 194.423 139.268422)
		(width 0.1)
		(layer "In4.Cu")
		(net 141)
	)
	(segment
		(start 196.822 149.610578)
		(end 196.822 154.75)
		(width 0.1)
		(layer "In4.Cu")
		(net 141)
	)
	(segment
		(start 193.885816 142.612217)
		(end 193.883579 142.60998)
		(width 0.1)
		(layer "In4.Cu")
		(net 141)
	)
	(segment
		(start 192.561422 145.35)
		(end 196.822 149.610578)
		(width 0.1)
		(layer "In4.Cu")
		(net 141)
	)
	(segment
		(start 191.58 144.928578)
		(end 192.001422 145.35)
		(width 0.1)
		(layer "In4.Cu")
		(net 141)
	)
	(segment
		(start 194.21 142.071422)
		(end 194.095711 142.185711)
		(width 0.1)
		(layer "In4.Cu")
		(net 141)
	)
	(segment
		(start 194.097949 142.612216)
		(end 194.097949 142.612215)
		(width 0.1)
		(layer "In4.Cu")
		(net 141)
	)
	(segment
		(start 191.58 144.036422)
		(end 191.58 144.928578)
		(width 0.1)
		(layer "In4.Cu")
		(net 141)
	)
	(segment
		(start 194.9 139.5)
		(end 194.6 139.2)
		(width 0.1)
		(layer "In4.Cu")
		(net 141)
	)
	(segment
		(start 194.6 139.2)
		(end 194.491422 139.2)
		(width 0.1)
		(layer "In4.Cu")
		(net 141)
	)
	(segment
		(start 196.822 154.75)
		(end 196.972 154.9)
		(width 0.1)
		(layer "In4.Cu")
		(net 141)
	)
	(segment
		(start 194.423 141.235206)
		(end 194.21 141.448206)
		(width 0.1)
		(layer "In4.Cu")
		(net 141)
	)
	(segment
		(start 194.095711 142.397845)
		(end 194.09571 142.397845)
		(width 0.1)
		(layer "In4.Cu")
		(net 141)
	)
	(segment
		(start 193.671444 142.822111)
		(end 193.673688 142.824355)
		(width 0.1)
		(layer "In4.Cu")
		(net 141)
	)
	(segment
		(start 193.673688 143.036487)
		(end 193.673689 143.036487)
		(width 0.1)
		(layer "In4.Cu")
		(net 141)
	)
	(segment
		(start 192.001422 145.35)
		(end 192.561422 145.35)
		(width 0.1)
		(layer "In4.Cu")
		(net 141)
	)
	(segment
		(start 193.671447 142.609979)
		(end 193.671445 142.609977)
		(width 0.1)
		(layer "In4.Cu")
		(net 141)
	)
	(segment
		(start 194.09571 142.397845)
		(end 194.097948 142.400083)
		(width 0.1)
		(layer "In4.Cu")
		(net 141)
	)
	(segment
		(start 194.097949 142.612215)
		(end 194.097948 142.612217)
		(width 0.1)
		(layer "In4.Cu")
		(net 141)
	)
	(segment
		(start 192.216422 143.4)
		(end 191.58 144.036422)
		(width 0.1)
		(layer "In4.Cu")
		(net 141)
	)
	(segment
		(start 193.671446 142.609979)
		(end 193.671447 142.609979)
		(width 0.1)
		(layer "In4.Cu")
		(net 141)
	)
	(segment
		(start 194.423 139.268422)
		(end 194.423 141.235206)
		(width 0.1)
		(layer "In4.Cu")
		(net 141)
	)
	(segment
		(start 193.247182 143.034244)
		(end 193.24718 143.034243)
		(width 0.1)
		(layer "In4.Cu")
		(net 141)
	)
	(segment
		(start 194.21 141.448206)
		(end 194.21 142.071422)
		(width 0.1)
		(layer "In4.Cu")
		(net 141)
	)
	(segment
		(start 193.24718 143.034243)
		(end 192.881422 143.4)
		(width 0.1)
		(layer "In4.Cu")
		(net 141)
	)
	(segment
		(start 192.881422 143.4)
		(end 192.216422 143.4)
		(width 0.1)
		(layer "In4.Cu")
		(net 141)
	)
	(arc
		(start 194.095711 142.185711)
		(mid 194.051776 142.291779)
		(end 194.095711 142.397845)
		(width 0.1)
		(layer "In4.Cu")
		(net 141)
	)
	(arc
		(start 193.673689 143.036487)
		(mid 193.567623 143.080421)
		(end 193.461557 143.036487)
		(width 0.1)
		(layer "In4.Cu")
		(net 141)
	)
	(arc
		(start 194.097948 142.612217)
		(mid 193.991882 142.656151)
		(end 193.885816 142.612217)
		(width 0.1)
		(layer "In4.Cu")
		(net 141)
	)
	(arc
		(start 193.671445 142.609977)
		(mid 193.62751 142.716045)
		(end 193.671445 142.822111)
		(width 0.1)
		(layer "In4.Cu")
		(net 141)
	)
	(arc
		(start 193.673688 142.824355)
		(mid 193.717622 142.930421)
		(end 193.673688 143.036487)
		(width 0.1)
		(layer "In4.Cu")
		(net 141)
	)
	(arc
		(start 194.097948 142.400083)
		(mid 194.141884 142.506148)
		(end 194.097949 142.612216)
		(width 0.1)
		(layer "In4.Cu")
		(net 141)
	)
	(arc
		(start 193.459314 143.034244)
		(mid 193.353248 142.99031)
		(end 193.247182 143.034244)
		(width 0.1)
		(layer "In4.Cu")
		(net 141)
	)
	(arc
		(start 193.883579 142.60998)
		(mid 193.777514 142.566044)
		(end 193.671446 142.609979)
		(width 0.1)
		(layer "In4.Cu")
		(net 141)
	)
	(via
		(at 196.472 154.9)
		(size 0.35)
		(drill 0.15)
		(layers "F.Cu" "B.Cu")
		(remove_unused_layers yes)
		(keep_end_layers yes)
		(zone_layer_connections)
		(net 142)
	)
	(via
		(at 194.9 138.7)
		(size 0.35)
		(drill 0.15)
		(layers "F.Cu" "B.Cu")
		(remove_unused_layers yes)
		(keep_end_layers yes)
		(zone_layer_connections)
		(net 142)
	)
	(segment
		(start 196.522 154.386)
		(end 196.6145 154.4785)
		(width 0.125)
		(layer "B.Cu")
		(net 142)
	)
	(segment
		(start 196.522 154.171)
		(end 196.522 154.386)
		(width 0.125)
		(layer "B.Cu")
		(net 142)
	)
	(segment
		(start 196.6145 154.4785)
		(end 196.6145 154.7575)
		(width 0.125)
		(layer "B.Cu")
		(net 142)
	)
	(segment
		(start 196.6145 154.7575)
		(end 196.472 154.9)
		(width 0.125)
		(layer "B.Cu")
		(net 142)
	)
	(segment
		(start 192.798578 143.2)
		(end 194.01 141.988578)
		(width 0.1)
		(layer "In4.Cu")
		(net 142)
	)
	(segment
		(start 194.232578 139.176)
		(end 194.408578 139)
		(width 0.1)
		(layer "In4.Cu")
		(net 142)
	)
	(segment
		(start 193.964794 139.176)
		(end 194.232578 139.176)
		(width 0.1)
		(layer "In4.Cu")
		(net 142)
	)
	(segment
		(start 193.775 141.235206)
		(end 193.775 139.365794)
		(width 0.1)
		(layer "In4.Cu")
		(net 142)
	)
	(segment
		(start 194.01 141.988578)
		(end 194.01 141.470206)
		(width 0.1)
		(layer "In4.Cu")
		(net 142)
	)
	(segment
		(start 196.622 154.75)
		(end 196.622 149.693422)
		(width 0.1)
		(layer "In4.Cu")
		(net 142)
	)
	(segment
		(start 192.478578 145.55)
		(end 191.918578 145.55)
		(width 0.1)
		(layer "In4.Cu")
		(net 142)
	)
	(segment
		(start 194.01 141.470206)
		(end 193.775 141.235206)
		(width 0.1)
		(layer "In4.Cu")
		(net 142)
	)
	(segment
		(start 191.38 143.953578)
		(end 192.133578 143.2)
		(width 0.1)
		(layer "In4.Cu")
		(net 142)
	)
	(segment
		(start 192.133578 143.2)
		(end 192.798578 143.2)
		(width 0.1)
		(layer "In4.Cu")
		(net 142)
	)
	(segment
		(start 191.918578 145.55)
		(end 191.38 145.011422)
		(width 0.1)
		(layer "In4.Cu")
		(net 142)
	)
	(segment
		(start 191.38 145.011422)
		(end 191.38 143.953578)
		(width 0.1)
		(layer "In4.Cu")
		(net 142)
	)
	(segment
		(start 196.622 149.693422)
		(end 192.478578 145.55)
		(width 0.1)
		(layer "In4.Cu")
		(net 142)
	)
	(segment
		(start 194.6 139)
		(end 194.9 138.7)
		(width 0.1)
		(layer "In4.Cu")
		(net 142)
	)
	(segment
		(start 196.472 154.9)
		(end 196.622 154.75)
		(width 0.1)
		(layer "In4.Cu")
		(net 142)
	)
	(segment
		(start 193.775 139.365794)
		(end 193.964794 139.176)
		(width 0.1)
		(layer "In4.Cu")
		(net 142)
	)
	(segment
		(start 194.408578 139)
		(end 194.6 139)
		(width 0.1)
		(layer "In4.Cu")
		(net 142)
	)
	(segment
		(start 195.55 148.834586)
		(end 195.95 149.234586)
		(width 0.1)
		(layer "F.Cu")
		(net 143)
	)
	(segment
		(start 195.95 149.234586)
		(end 195.95 149.33)
		(width 0.1)
		(layer "F.Cu")
		(net 143)
	)
	(segment
		(start 195.39 148.4)
		(end 195.39 148.595)
		(width 0.1)
		(layer "F.Cu")
		(net 143)
	)
	(segment
		(start 195.842727 149.437273)
		(end 195.729635 149.437273)
		(width 0.1)
		(layer "F.Cu")
		(net 143)
	)
	(segment
		(start 195.729635 149.437273)
		(end 195.612385 149.320023)
		(width 0.1)
		(layer "F.Cu")
		(net 143)
	)
	(segment
		(start 195.95 149.33)
		(end 195.842727 149.437273)
		(width 0.1)
		(layer "F.Cu")
		(net 143)
	)
	(segment
		(start 195.55 148.755)
		(end 195.55 148.834586)
		(width 0.1)
		(layer "F.Cu")
		(net 143)
	)
	(segment
		(start 195.39 148.595)
		(end 195.55 148.755)
		(width 0.1)
		(layer "F.Cu")
		(net 143)
	)
	(via
		(at 195.772 154.9)
		(size 0.35)
		(drill 0.15)
		(layers "F.Cu" "B.Cu")
		(remove_unused_layers yes)
		(keep_end_layers yes)
		(zone_layer_connections)
		(net 143)
	)
	(via
		(at 195.612385 149.320023)
		(size 0.35)
		(drill 0.15)
		(layers "F.Cu" "B.Cu")
		(remove_unused_layers yes)
		(keep_end_layers yes)
		(zone_layer_connections)
		(net 143)
	)
	(segment
		(start 195.722 154.386)
		(end 195.632 154.476)
		(width 0.1)
		(layer "B.Cu")
		(net 143)
	)
	(segment
		(start 195.722 154.171)
		(end 195.722 154.386)
		(width 0.1)
		(layer "B.Cu")
		(net 143)
	)
	(segment
		(start 195.632 154.76)
		(end 195.772 154.9)
		(width 0.1)
		(layer "B.Cu")
		(net 143)
	)
	(segment
		(start 195.632 154.476)
		(end 195.632 154.76)
		(width 0.1)
		(layer "B.Cu")
		(net 143)
	)
	(segment
		(start 195.642 153.922294)
		(end 195.642 154.77)
		(width 0.09)
		(layer "In2.Cu")
		(net 143)
	)
	(segment
		(start 195.642 154.77)
		(end 195.772 154.9)
		(width 0.09)
		(layer "In2.Cu")
		(net 143)
	)
	(segment
		(start 195.13 151.559706)
		(end 195.13 153.410294)
		(width 0.09)
		(layer "In2.Cu")
		(net 143)
	)
	(segment
		(start 195.13 153.410294)
		(end 195.642 153.922294)
		(width 0.09)
		(layer "In2.Cu")
		(net 143)
	)
	(segment
		(start 195.612385 149.320023)
		(end 195.719635 149.427273)
		(width 0.09)
		(layer "In2.Cu")
		(net 143)
	)
	(segment
		(start 195.719635 149.427273)
		(end 195.956979 149.427273)
		(width 0.09)
		(layer "In2.Cu")
		(net 143)
	)
	(segment
		(start 196.294158 150.395548)
		(end 195.13 151.559706)
		(width 0.09)
		(layer "In2.Cu")
		(net 143)
	)
	(segment
		(start 196.294158 149.764452)
		(end 196.294158 150.395548)
		(width 0.09)
		(layer "In2.Cu")
		(net 143)
	)
	(segment
		(start 195.956979 149.427273)
		(end 196.294158 149.764452)
		(width 0.09)
		(layer "In2.Cu")
		(net 143)
	)
	(segment
		(start 195.79 148.763458)
		(end 195.79 148.4)
		(width 0.1)
		(layer "F.Cu")
		(net 144)
	)
	(segment
		(start 196.17 149.143458)
		(end 195.79 148.763458)
		(width 0.1)
		(layer "F.Cu")
		(net 144)
	)
	(segment
		(start 195.612385 149.774523)
		(end 195.729635 149.657273)
		(width 0.1)
		(layer "F.Cu")
		(net 144)
	)
	(segment
		(start 196.17 149.42)
		(end 196.17 149.143458)
		(width 0.1)
		(layer "F.Cu")
		(net 144)
	)
	(segment
		(start 195.932727 149.657273)
		(end 196.17 149.42)
		(width 0.1)
		(layer "F.Cu")
		(net 144)
	)
	(segment
		(start 195.729635 149.657273)
		(end 195.932727 149.657273)
		(width 0.1)
		(layer "F.Cu")
		(net 144)
	)
	(via
		(at 195.272 154.9)
		(size 0.35)
		(drill 0.15)
		(layers "F.Cu" "B.Cu")
		(remove_unused_layers yes)
		(keep_end_layers yes)
		(zone_layer_connections)
		(net 144)
	)
	(via
		(at 195.612385 149.774523)
		(size 0.35)
		(drill 0.15)
		(layers "F.Cu" "B.Cu")
		(remove_unused_layers yes)
		(keep_end_layers yes)
		(zone_layer_connections)
		(net 144)
	)
	(segment
		(start 195.412 154.76)
		(end 195.272 154.9)
		(width 0.1)
		(layer "B.Cu")
		(net 144)
	)
	(segment
		(start 195.412 154.476)
		(end 195.412 154.76)
		(width 0.1)
		(layer "B.Cu")
		(net 144)
	)
	(segment
		(start 195.322 154.171)
		(end 195.322 154.386)
		(width 0.1)
		(layer "B.Cu")
		(net 144)
	)
	(segment
		(start 195.322 154.386)
		(end 195.412 154.476)
		(width 0.1)
		(layer "B.Cu")
		(net 144)
	)
	(segment
		(start 195.402 154.021706)
		(end 195.402 154.77)
		(width 0.09)
		(layer "In2.Cu")
		(net 144)
	)
	(segment
		(start 194.89 153.509706)
		(end 195.402 154.021706)
		(width 0.09)
		(layer "In2.Cu")
		(net 144)
	)
	(segment
		(start 196.054158 150.21)
		(end 196.054158 150.296136)
		(width 0.09)
		(layer "In2.Cu")
		(net 144)
	)
	(segment
		(start 195.612385 149.774523)
		(end 195.719635 149.667273)
		(width 0.09)
		(layer "In2.Cu")
		(net 144)
	)
	(segment
		(start 195.719635 149.667273)
		(end 195.857567 149.667273)
		(width 0.09)
		(layer "In2.Cu")
		(net 144)
	)
	(segment
		(start 195.954158 150.03)
		(end 195.954158 150.11)
		(width 0.09)
		(layer "In2.Cu")
		(net 144)
	)
	(segment
		(start 196.054158 149.863864)
		(end 196.054158 149.93)
		(width 0.09)
		(layer "In2.Cu")
		(net 144)
	)
	(segment
		(start 196.054158 150.296136)
		(end 194.89 151.460294)
		(width 0.09)
		(layer "In2.Cu")
		(net 144)
	)
	(segment
		(start 194.89 151.460294)
		(end 194.89 153.509706)
		(width 0.09)
		(layer "In2.Cu")
		(net 144)
	)
	(segment
		(start 195.857567 149.667273)
		(end 196.054158 149.863864)
		(width 0.09)
		(layer "In2.Cu")
		(net 144)
	)
	(segment
		(start 195.402 154.77)
		(end 195.272 154.9)
		(width 0.09)
		(layer "In2.Cu")
		(net 144)
	)
	(arc
		(start 195.954158 150.11)
		(mid 195.968803 150.145355)
		(end 196.004158 150.16)
		(width 0.09)
		(layer "In2.Cu")
		(net 144)
	)
	(arc
		(start 196.004158 150.16)
		(mid 196.039513 150.174645)
		(end 196.054158 150.21)
		(width 0.09)
		(layer "In2.Cu")
		(net 144)
	)
	(arc
		(start 196.004158 149.98)
		(mid 195.968803 149.994645)
		(end 195.954158 150.03)
		(width 0.09)
		(layer "In2.Cu")
		(net 144)
	)
	(arc
		(start 196.054158 149.93)
		(mid 196.039513 149.965355)
		(end 196.004158 149.98)
		(width 0.09)
		(layer "In2.Cu")
		(net 144)
	)
	(via
		(at 189.299 137.901)
		(size 0.35)
		(drill 0.15)
		(layers "F.Cu" "B.Cu")
		(remove_unused_layers yes)
		(keep_end_layers yes)
		(zone_layer_connections)
		(net 145)
	)
	(via
		(at 200.449 144.151)
		(size 0.35)
		(drill 0.15)
		(layers "F.Cu" "B.Cu")
		(remove_unused_layers yes)
		(keep_end_layers yes)
		(zone_layer_connections)
		(net 145)
	)
	(segment
		(start 195 137.51)
		(end 195.26 137.77)
		(width 0.09)
		(layer "In9.Cu")
		(net 145)
	)
	(segment
		(start 197.69 139.438451)
		(end 197.69 139.61)
		(width 0.09)
		(layer "In9.Cu")
		(net 145)
	)
	(segment
		(start 197.69 139.61)
		(end 198.02 139.94)
		(width 0.09)
		(layer "In9.Cu")
		(net 145)
	)
	(segment
		(start 189.935 136.455)
		(end 189.935 136.097701)
		(width 0.09)
		(layer "In9.Cu")
		(net 145)
	)
	(segment
		(start 197.351549 139.1)
		(end 197.69 139.438451)
		(width 0.09)
		(layer "In9.Cu")
		(net 145)
	)
	(segment
		(start 198.78 140.7)
		(end 199 140.7)
		(width 0.09)
		(layer "In9.Cu")
		(net 145)
	)
	(segment
		(start 193.68 136.94)
		(end 193.68 137.25)
		(width 0.09)
		(layer "In9.Cu")
		(net 145)
	)
	(segment
		(start 196.446451 139.1)
		(end 197.351549 139.1)
		(width 0.09)
		(layer "In9.Cu")
		(net 145)
	)
	(segment
		(start 200.21 142.26)
		(end 200.21 143.912)
		(width 0.09)
		(layer "In9.Cu")
		(net 145)
	)
	(segment
		(start 190.385 136.097701)
		(end 190.385 136.455)
		(width 0.09)
		(layer "In9.Cu")
		(net 145)
	)
	(segment
		(start 199.31 141.01)
		(end 199.31 141.36)
		(width 0.09)
		(layer "In9.Cu")
		(net 145)
	)
	(segment
		(start 189.299 136.981)
		(end 189.6 136.68)
		(width 0.09)
		(layer "In9.Cu")
		(net 145)
	)
	(segment
		(start 200.21 143.912)
		(end 200.449 144.151)
		(width 0.09)
		(layer "In9.Cu")
		(net 145)
	)
	(segment
		(start 189.299 137.901)
		(end 189.299 136.981)
		(width 0.09)
		(layer "In9.Cu")
		(net 145)
	)
	(segment
		(start 198.48 140.19)
		(end 198.48 140.4)
		(width 0.09)
		(layer "In9.Cu")
		(net 145)
	)
	(segment
		(start 193.68 137.25)
		(end 193.94 137.51)
		(width 0.09)
		(layer "In9.Cu")
		(net 145)
	)
	(segment
		(start 193.94 137.51)
		(end 195 137.51)
		(width 0.09)
		(layer "In9.Cu")
		(net 145)
	)
	(segment
		(start 191.51 136.68)
		(end 193.42 136.68)
		(width 0.09)
		(layer "In9.Cu")
		(net 145)
	)
	(segment
		(start 191.285 136.097701)
		(end 191.285 136.455)
		(width 0.09)
		(layer "In9.Cu")
		(net 145)
	)
	(segment
		(start 193.42 136.68)
		(end 193.68 136.94)
		(width 0.09)
		(layer "In9.Cu")
		(net 145)
	)
	(segment
		(start 199.31 141.36)
		(end 200.21 142.26)
		(width 0.09)
		(layer "In9.Cu")
		(net 145)
	)
	(segment
		(start 195.26 137.913549)
		(end 196.446451 139.1)
		(width 0.09)
		(layer "In9.Cu")
		(net 145)
	)
	(segment
		(start 198.48 140.4)
		(end 198.78 140.7)
		(width 0.09)
		(layer "In9.Cu")
		(net 145)
	)
	(segment
		(start 195.26 137.77)
		(end 195.26 137.913549)
		(width 0.09)
		(layer "In9.Cu")
		(net 145)
	)
	(segment
		(start 199 140.7)
		(end 199.31 141.01)
		(width 0.09)
		(layer "In9.Cu")
		(net 145)
	)
	(segment
		(start 190.835 136.455)
		(end 190.835 136.097701)
		(width 0.09)
		(layer "In9.Cu")
		(net 145)
	)
	(segment
		(start 189.6 136.68)
		(end 189.71 136.68)
		(width 0.09)
		(layer "In9.Cu")
		(net 145)
	)
	(segment
		(start 198.02 139.94)
		(end 198.23 139.94)
		(width 0.09)
		(layer "In9.Cu")
		(net 145)
	)
	(segment
		(start 198.23 139.94)
		(end 198.48 140.19)
		(width 0.09)
		(layer "In9.Cu")
		(net 145)
	)
	(arc
		(start 190.16 135.872701)
		(mid 190.319099 135.938602)
		(end 190.385 136.097701)
		(width 0.09)
		(layer "In9.Cu")
		(net 145)
	)
	(arc
		(start 189.71 136.68)
		(mid 189.869099 136.614099)
		(end 189.935 136.455)
		(width 0.09)
		(layer "In9.Cu")
		(net 145)
	)
	(arc
		(start 191.06 135.872701)
		(mid 191.219099 135.938602)
		(end 191.285 136.097701)
		(width 0.09)
		(layer "In9.Cu")
		(net 145)
	)
	(arc
		(start 190.385 136.455)
		(mid 190.450901 136.614099)
		(end 190.61 136.68)
		(width 0.09)
		(layer "In9.Cu")
		(net 145)
	)
	(arc
		(start 190.61 136.68)
		(mid 190.769099 136.614099)
		(end 190.835 136.455)
		(width 0.09)
		(layer "In9.Cu")
		(net 145)
	)
	(arc
		(start 189.935 136.097701)
		(mid 190.000901 135.938602)
		(end 190.16 135.872701)
		(width 0.09)
		(layer "In9.Cu")
		(net 145)
	)
	(arc
		(start 191.285 136.455)
		(mid 191.350901 136.614099)
		(end 191.51 136.68)
		(width 0.09)
		(layer "In9.Cu")
		(net 145)
	)
	(arc
		(start 190.835 136.097701)
		(mid 190.900901 135.938602)
		(end 191.06 135.872701)
		(width 0.09)
		(layer "In9.Cu")
		(net 145)
	)
	(segment
		(start 200.175 152.225)
		(end 200.175 152.980683)
		(width 0.11)
		(layer "F.Cu")
		(net 146)
	)
	(segment
		(start 198.775 152.225)
		(end 198.775 152.380651)
		(width 0.11)
		(layer "F.Cu")
		(net 146)
	)
	(segment
		(start 195.891422 151.975)
		(end 197.625 151.975)
		(width 0.11)
		(layer "F.Cu")
		(net 146)
	)
	(segment
		(start 205.649 150.623514)
		(end 205.649 150.734078)
		(width 0.11)
		(layer "F.Cu")
		(net 146)
	)
	(segment
		(start 194.9 152.925)
		(end 195.3 152.925)
		(width 0.11)
		(layer "F.Cu")
		(net 146)
	)
	(segment
		(start 195.416422 153.825)
		(end 194.358578 153.825)
		(width 0.11)
		(layer "F.Cu")
		(net 146)
	)
	(segment
		(start 194.125 153.291422)
		(end 193.961828 153.12825)
		(width 0.11)
		(layer "F.Cu")
		(net 146)
	)
	(segment
		(start 195.891422 151.975)
		(end 195.675 152.191422)
		(width 0.11)
		(layer "F.Cu")
		(net 146)
	)
	(segment
		(start 193.961828 153.12825)
		(end 193.85175 153.12825)
		(width 0.11)
		(layer "F.Cu")
		(net 146)
	)
	(segment
		(start 195.675 153.566422)
		(end 195.416422 153.825)
		(width 0.11)
		(layer "F.Cu")
		(net 146)
	)
	(segment
		(start 195.675 152.191422)
		(end 195.675 152.2)
		(width 0.11)
		(layer "F.Cu")
		(net 146)
	)
	(segment
		(start 205.649 150.001)
		(end 205.649 150.225)
		(width 0.11)
		(layer "F.Cu")
		(net 146)
	)
	(segment
		(start 193.85175 153.12825)
		(end 193.7245 153.2555)
		(width 0.11)
		(layer "F.Cu")
		(net 146)
	)
	(segment
		(start 205.649 150.734078)
		(end 204.408078 151.975)
		(width 0.11)
		(layer "F.Cu")
		(net 146)
	)
	(segment
		(start 199.275 152.980683)
		(end 199.275 152.225)
		(width 0.11)
		(layer "F.Cu")
		(net 146)
	)
	(segment
		(start 194.358578 153.825)
		(end 194.125 153.591422)
		(width 0.11)
		(layer "F.Cu")
		(net 146)
	)
	(segment
		(start 205.797515 150.373514)
		(end 205.797515 150.475)
		(width 0.11)
		(layer "F.Cu")
		(net 146)
	)
	(segment
		(start 205.723257 150.299257)
		(end 205.723258 150.299257)
		(width 0.11)
		(layer "F.Cu")
		(net 146)
	)
	(segment
		(start 195.675 153.3)
		(end 195.675 153.566422)
		(width 0.11)
		(layer "F.Cu")
		(net 146)
	)
	(segment
		(start 204.408078 151.975)
		(end 200.425 151.975)
		(width 0.11)
		(layer "F.Cu")
		(net 146)
	)
	(segment
		(start 197.875 152.380651)
		(end 197.875 152.225)
		(width 0.11)
		(layer "F.Cu")
		(net 146)
	)
	(segment
		(start 205.723258 150.549257)
		(end 205.723257 150.549257)
		(width 0.11)
		(layer "F.Cu")
		(net 146)
	)
	(segment
		(start 195.3 152.575)
		(end 194.9 152.575)
		(width 0.11)
		(layer "F.Cu")
		(net 146)
	)
	(segment
		(start 194.125 153.591422)
		(end 194.125 153.291422)
		(width 0.11)
		(layer "F.Cu")
		(net 146)
	)
	(via
		(at 193.7245 153.2555)
		(size 0.35)
		(drill 0.15)
		(layers "F.Cu" "B.Cu")
		(remove_unused_layers yes)
		(keep_end_layers yes)
		(zone_layer_connections)
		(net 146)
	)
	(arc
		(start 199.725 153.430683)
		(mid 199.406802 153.298881)
		(end 199.275 152.980683)
		(width 0.11)
		(layer "F.Cu")
		(net 146)
	)
	(arc
		(start 205.649 150.225)
		(mid 205.670749 150.277508)
		(end 205.723257 150.299257)
		(width 0.11)
		(layer "F.Cu")
		(net 146)
	)
	(arc
		(start 195.3 152.925)
		(mid 195.565165 153.034835)
		(end 195.675 153.3)
		(width 0.11)
		(layer "F.Cu")
		(net 146)
	)
	(arc
		(start 200.425 151.975)
		(mid 200.248223 152.048223)
		(end 200.175 152.225)
		(width 0.11)
		(layer "F.Cu")
		(net 146)
	)
	(arc
		(start 198.325 152.830651)
		(mid 198.006802 152.698849)
		(end 197.875 152.380651)
		(width 0.11)
		(layer "F.Cu")
		(net 146)
	)
	(arc
		(start 205.797515 150.475)
		(mid 205.775766 150.527508)
		(end 205.723258 150.549257)
		(width 0.11)
		(layer "F.Cu")
		(net 146)
	)
	(arc
		(start 197.875 152.225)
		(mid 197.801777 152.048223)
		(end 197.625 151.975)
		(width 0.11)
		(layer "F.Cu")
		(net 146)
	)
	(arc
		(start 194.9 152.575)
		(mid 194.776256 152.626256)
		(end 194.725 152.75)
		(width 0.11)
		(layer "F.Cu")
		(net 146)
	)
	(arc
		(start 199.025 151.975)
		(mid 198.848223 152.048223)
		(end 198.775 152.225)
		(width 0.11)
		(layer "F.Cu")
		(net 146)
	)
	(arc
		(start 205.723257 150.549257)
		(mid 205.670749 150.571006)
		(end 205.649 150.623514)
		(width 0.11)
		(layer "F.Cu")
		(net 146)
	)
	(arc
		(start 198.775 152.380651)
		(mid 198.643198 152.698849)
		(end 198.325 152.830651)
		(width 0.11)
		(layer "F.Cu")
		(net 146)
	)
	(arc
		(start 195.675 152.2)
		(mid 195.565165 152.465165)
		(end 195.3 152.575)
		(width 0.11)
		(layer "F.Cu")
		(net 146)
	)
	(arc
		(start 199.275 152.225)
		(mid 199.201777 152.048223)
		(end 199.025 151.975)
		(width 0.11)
		(layer "F.Cu")
		(net 146)
	)
	(arc
		(start 194.725 152.75)
		(mid 194.776256 152.873744)
		(end 194.9 152.925)
		(width 0.11)
		(layer "F.Cu")
		(net 146)
	)
	(arc
		(start 200.175 152.980683)
		(mid 200.043198 153.298881)
		(end 199.725 153.430683)
		(width 0.11)
		(layer "F.Cu")
		(net 146)
	)
	(arc
		(start 205.723258 150.299257)
		(mid 205.775766 150.321006)
		(end 205.797515 150.373514)
		(width 0.11)
		(layer "F.Cu")
		(net 146)
	)
	(segment
		(start 194.522 151.676)
		(end 194.422 151.776)
		(width 0.11)
		(layer "B.Cu")
		(net 146)
	)
	(segment
		(start 194.063172 153.12825)
		(end 193.85175 153.12825)
		(width 0.11)
		(layer "B.Cu")
		(net 146)
	)
	(segment
		(start 194.522 151.461)
		(end 194.522 151.676)
		(width 0.11)
		(layer "B.Cu")
		(net 146)
	)
	(segment
		(start 194.422 151.776)
		(end 194.422 152.769422)
		(width 0.11)
		(layer "B.Cu")
		(net 146)
	)
	(segment
		(start 194.422 152.769422)
		(end 194.063172 153.12825)
		(width 0.11)
		(layer "B.Cu")
		(net 146)
	)
	(segment
		(start 193.85175 153.12825)
		(end 193.7245 153.2555)
		(width 0.11)
		(layer "B.Cu")
		(net 146)
	)
	(segment
		(start 194.59 148.6)
		(end 194.59 148.4)
		(width 0.1)
		(layer "F.Cu")
		(net 147)
	)
	(segment
		(start 194.68 149.264436)
		(end 194.68 148.69)
		(width 0.1)
		(layer "F.Cu")
		(net 147)
	)
	(segment
		(start 194.216 149.544515)
		(end 194.399921 149.544515)
		(width 0.1)
		(layer "F.Cu")
		(net 147)
	)
	(segment
		(start 194.399921 149.544515)
		(end 194.68 149.264436)
		(width 0.1)
		(layer "F.Cu")
		(net 147)
	)
	(segment
		(start 194.68 148.69)
		(end 194.59 148.6)
		(width 0.1)
		(layer "F.Cu")
		(net 147)
	)
	(segment
		(start 194.09875 149.427265)
		(end 194.216 149.544515)
		(width 0.1)
		(layer "F.Cu")
		(net 147)
	)
	(via
		(at 194.572 154.9)
		(size 0.35)
		(drill 0.15)
		(layers "F.Cu" "B.Cu")
		(remove_unused_layers yes)
		(keep_end_layers yes)
		(zone_layer_connections)
		(net 147)
	)
	(via
		(at 194.09875 149.427265)
		(size 0.35)
		(drill 0.15)
		(layers "F.Cu" "B.Cu")
		(remove_unused_layers yes)
		(keep_end_layers yes)
		(zone_layer_connections)
		(net 147)
	)
	(segment
		(start 194.522 154.171)
		(end 194.522 154.386)
		(width 0.1)
		(layer "B.Cu")
		(net 147)
	)
	(segment
		(start 194.432 154.476)
		(end 194.432 154.76)
		(width 0.1)
		(layer "B.Cu")
		(net 147)
	)
	(segment
		(start 194.522 154.386)
		(end 194.432 154.476)
		(width 0.1)
		(layer "B.Cu")
		(net 147)
	)
	(segment
		(start 194.432 154.76)
		(end 194.572 154.9)
		(width 0.1)
		(layer "B.Cu")
		(net 147)
	)
	(segment
		(start 194.206 149.534515)
		(end 194.424221 149.534515)
		(width 0.09)
		(layer "In2.Cu")
		(net 147)
	)
	(segment
		(start 194.74 149.850294)
		(end 194.74 150.349706)
		(width 0.09)
		(layer "In2.Cu")
		(net 147)
	)
	(segment
		(start 194.157 151.115)
		(end 194.037 151.115)
		(width 0.09)
		(layer "In2.Cu")
		(net 147)
	)
	(segment
		(start 193.992 151.16)
		(end 193.992 151.36)
		(width 0.09)
		(layer "In2.Cu")
		(net 147)
	)
	(segment
		(start 194.442 150.647706)
		(end 194.442 150.83)
		(width 0.09)
		(layer "In2.Cu")
		(net 147)
	)
	(segment
		(start 194.442 151.69)
		(end 194.442 154.77)
		(width 0.09)
		(layer "In2.Cu")
		(net 147)
	)
	(segment
		(start 194.037 151.405)
		(end 194.157 151.405)
		(width 0.09)
		(layer "In2.Cu")
		(net 147)
	)
	(segment
		(start 194.74 150.349706)
		(end 194.442 150.647706)
		(width 0.09)
		(layer "In2.Cu")
		(net 147)
	)
	(segment
		(start 194.424221 149.534515)
		(end 194.74 149.850294)
		(width 0.09)
		(layer "In2.Cu")
		(net 147)
	)
	(segment
		(start 194.442 154.77)
		(end 194.572 154.9)
		(width 0.09)
		(layer "In2.Cu")
		(net 147)
	)
	(segment
		(start 194.09875 149.427265)
		(end 194.206 149.534515)
		(width 0.09)
		(layer "In2.Cu")
		(net 147)
	)
	(arc
		(start 194.037 151.115)
		(mid 194.00518 151.12818)
		(end 193.992 151.16)
		(width 0.09)
		(layer "In2.Cu")
		(net 147)
	)
	(arc
		(start 194.442 150.83)
		(mid 194.358525 151.031525)
		(end 194.157 151.115)
		(width 0.09)
		(layer "In2.Cu")
		(net 147)
	)
	(arc
		(start 194.157 151.405)
		(mid 194.358525 151.488475)
		(end 194.442 151.69)
		(width 0.09)
		(layer "In2.Cu")
		(net 147)
	)
	(arc
		(start 193.992 151.36)
		(mid 194.00518 151.39182)
		(end 194.037 151.405)
		(width 0.09)
		(layer "In2.Cu")
		(net 147)
	)
	(segment
		(start 183.358904 152.680031)
		(end 183.358904 151.980531)
		(width 0.174)
		(layer "F.Cu")
		(net 148)
	)
	(segment
		(start 183.250404 152.788531)
		(end 183.358904 152.680031)
		(width 0.174)
		(layer "F.Cu")
		(net 148)
	)
	(segment
		(start 183.250404 153.204531)
		(end 183.250404 152.788531)
		(width 0.174)
		(layer "F.Cu")
		(net 148)
	)
	(segment
		(start 184.725404 152.760467)
		(end 184.4 152.435063)
		(width 0.174)
		(layer "F.Cu")
		(net 149)
	)
	(segment
		(start 184.4 152.435063)
		(end 184.4 150.769627)
		(width 0.174)
		(layer "F.Cu")
		(net 149)
	)
	(segment
		(start 184.725404 154.273281)
		(end 184.725404 152.760467)
		(width 0.174)
		(layer "F.Cu")
		(net 149)
	)
	(segment
		(start 184.4 150.769627)
		(end 184.259904 150.629531)
		(width 0.174)
		(layer "F.Cu")
		(net 149)
	)
	(segment
		(start 185.693404 152.956596)
		(end 185.85 152.8)
		(width 0.174)
		(layer "F.Cu")
		(net 150)
	)
	(segment
		(start 187.523935 152.8)
		(end 187.784404 152.539531)
		(width 0.174)
		(layer "F.Cu")
		(net 150)
	)
	(segment
		(start 185.85 152.8)
		(end 187.523935 152.8)
		(width 0.174)
		(layer "F.Cu")
		(net 150)
	)
	(segment
		(start 186.665 152.535)
		(end 188 152.535)
		(width 0.174)
		(layer "F.Cu")
		(net 150)
	)
	(segment
		(start 185.693404 154.273281)
		(end 185.693404 152.956596)
		(width 0.174)
		(layer "F.Cu")
		(net 150)
	)
	(via
		(at 218.6265 146.542)
		(size 0.35)
		(drill 0.15)
		(layers "F.Cu" "B.Cu")
		(remove_unused_layers yes)
		(keep_end_layers yes)
		(zone_layer_connections)
		(net 151)
	)
	(segment
		(start 218.57 148.27)
		(end 218.5 148.2)
		(width 0.256)
		(layer "B.Cu")
		(net 151)
	)
	(segment
		(start 218.6265 146.542)
		(end 218.6265 147.3435)
		(width 0.15)
		(layer "B.Cu")
		(net 151)
	)
	(segment
		(start 218.5 148.2)
		(end 218.5 146.945)
		(width 0.256)
		(layer "B.Cu")
		(net 151)
	)
	(via
		(at 214.115 140.8755)
		(size 0.35)
		(drill 0.15)
		(layers "F.Cu" "B.Cu")
		(remove_unused_layers yes)
		(keep_end_layers yes)
		(zone_layer_connections)
		(net 152)
	)
	(segment
		(start 214.493 142.233)
		(end 214.493 141.2835)
		(width 0.174)
		(layer "B.Cu")
		(net 152)
	)
	(segment
		(start 216.015 143.085)
		(end 215.384 143.085)
		(width 0.174)
		(layer "B.Cu")
		(net 152)
	)
	(segment
		(start 214.508 142.248)
		(end 214.493 142.233)
		(width 0.174)
		(layer "B.Cu")
		(net 152)
	)
	(segment
		(start 214.926 142.666)
		(end 214.508 142.248)
		(width 0.174)
		(layer "B.Cu")
		(net 152)
	)
	(segment
		(start 215.015 140.7615)
		(end 214.508 141.2685)
		(width 0.174)
		(layer "B.Cu")
		(net 152)
	)
	(segment
		(start 213.956 142.8)
		(end 214.508 142.248)
		(width 0.174)
		(layer "B.Cu")
		(net 152)
	)
	(segment
		(start 214.493 141.2835)
		(end 214.508 141.2685)
		(width 0.174)
		(layer "B.Cu")
		(net 152)
	)
	(segment
		(start 215.384 143.085)
		(end 214.965 142.666)
		(width 0.174)
		(layer "B.Cu")
		(net 152)
	)
	(segment
		(start 214.965 142.666)
		(end 214.926 142.666)
		(width 0.174)
		(layer "B.Cu")
		(net 152)
	)
	(segment
		(start 214.508 141.2685)
		(end 214.115 140.8755)
		(width 0.174)
		(layer "B.Cu")
		(net 152)
	)
	(via
		(at 215.115 144.75)
		(size 0.35)
		(drill 0.15)
		(layers "F.Cu" "B.Cu")
		(remove_unused_layers yes)
		(keep_end_layers yes)
		(zone_layer_connections)
		(net 153)
	)
	(segment
		(start 215.115 144.75)
		(end 215.115 144.9)
		(width 0.174)
		(layer "B.Cu")
		(net 153)
	)
	(segment
		(start 215.415 145.2)
		(end 216.665 145.2)
		(width 0.174)
		(layer "B.Cu")
		(net 153)
	)
	(segment
		(start 216.665 145.2)
		(end 217.099 144.766)
		(width 0.174)
		(layer "B.Cu")
		(net 153)
	)
	(segment
		(start 215.115 144.9)
		(end 215.415 145.2)
		(width 0.174)
		(layer "B.Cu")
		(net 153)
	)
	(segment
		(start 217.099 144.766)
		(end 217.099 144.05)
		(width 0.174)
		(layer "B.Cu")
		(net 153)
	)
	(via
		(at 201.1 148.05)
		(size 0.35)
		(drill 0.15)
		(layers "F.Cu" "B.Cu")
		(remove_unused_layers yes)
		(keep_end_layers yes)
		(zone_layer_connections)
		(net 154)
	)
	(via
		(at 189.299 138.7)
		(size 0.35)
		(drill 0.15)
		(layers "F.Cu" "B.Cu")
		(remove_unused_layers yes)
		(keep_end_layers yes)
		(zone_layer_connections)
		(net 154)
	)
	(segment
		(start 188.975 141.605)
		(end 191.22 143.85)
		(width 0.09)
		(layer "In9.Cu")
		(net 154)
	)
	(segment
		(start 191.68 145.41)
		(end 193.479509 145.41)
		(width 0.09)
		(layer "In9.Cu")
		(net 154)
	)
	(segment
		(start 188.975 139.024)
		(end 188.975 141.605)
		(width 0.09)
		(layer "In9.Cu")
		(net 154)
	)
	(segment
		(start 197.851274 146.639216)
		(end 197.851274 146.648726)
		(width 0.09)
		(layer "In9.Cu")
		(net 154)
	)
	(segment
		(start 197.222549 146.010491)
		(end 197.851274 146.639216)
		(width 0.09)
		(layer "In9.Cu")
		(net 154)
	)
	(segment
		(start 199.252549 148.05)
		(end 201.1 148.05)
		(width 0.09)
		(layer "In9.Cu")
		(net 154)
	)
	(segment
		(start 189.299 138.7)
		(end 188.975 139.024)
		(width 0.09)
		(layer "In9.Cu")
		(net 154)
	)
	(segment
		(start 194.08 146.010491)
		(end 197.222549 146.010491)
		(width 0.09)
		(layer "In9.Cu")
		(net 154)
	)
	(segment
		(start 193.479509 145.41)
		(end 194.08 146.010491)
		(width 0.09)
		(layer "In9.Cu")
		(net 154)
	)
	(segment
		(start 191.22 144.95)
		(end 191.68 145.41)
		(width 0.09)
		(layer "In9.Cu")
		(net 154)
	)
	(segment
		(start 197.851274 146.648726)
		(end 199.252549 148.05)
		(width 0.09)
		(layer "In9.Cu")
		(net 154)
	)
	(segment
		(start 191.22 143.85)
		(end 191.22 144.95)
		(width 0.09)
		(layer "In9.Cu")
		(net 154)
	)
	(segment
		(start 198.075 152.380651)
		(end 198.075 152.225)
		(width 0.11)
		(layer "F.Cu")
		(net 156)
	)
	(segment
		(start 205.329 150.133549)
		(end 205.449 150.253549)
		(width 0.11)
		(layer "F.Cu")
		(net 156)
	)
	(segment
		(start 194.044672 152.92825)
		(end 193.85175 152.92825)
		(width 0.11)
		(layer "F.Cu")
		(net 156)
	)
	(segment
		(start 193.85175 152.92825)
		(end 193.7245 152.801)
		(width 0.11)
		(layer "F.Cu")
		(net 156)
	)
	(segment
		(start 195.333578 153.625)
		(end 194.441422 153.625)
		(width 0.11)
		(layer "F.Cu")
		(net 156)
	)
	(segment
		(start 204.325234 151.775)
		(end 200.425 151.775)
		(width 0.11)
		(layer "F.Cu")
		(net 156)
	)
	(segment
		(start 194.9 153.125)
		(end 195.3 153.125)
		(width 0.11)
		(layer "F.Cu")
		(net 156)
	)
	(segment
		(start 199.475 152.980683)
		(end 199.475 152.225)
		(width 0.11)
		(layer "F.Cu")
		(net 156)
	)
	(segment
		(start 194.325 153.208578)
		(end 194.044672 152.92825)
		(width 0.11)
		(layer "F.Cu")
		(net 156)
	)
	(segment
		(start 195.808578 151.775)
		(end 195.475 152.108578)
		(width 0.11)
		(layer "F.Cu")
		(net 156)
	)
	(segment
		(start 195.808578 151.775)
		(end 197.625 151.775)
		(width 0.11)
		(layer "F.Cu")
		(net 156)
	)
	(segment
		(start 194.325 153.508578)
		(end 194.325 153.208578)
		(width 0.11)
		(layer "F.Cu")
		(net 156)
	)
	(segment
		(start 194.441422 153.625)
		(end 194.325 153.508578)
		(width 0.11)
		(layer "F.Cu")
		(net 156)
	)
	(segment
		(start 195.475 152.108578)
		(end 195.475 152.2)
		(width 0.11)
		(layer "F.Cu")
		(net 156)
	)
	(segment
		(start 205.449 150.253549)
		(end 205.449 150.651234)
		(width 0.11)
		(layer "F.Cu")
		(net 156)
	)
	(segment
		(start 205.449 149.551)
		(end 205.449 149.748451)
		(width 0.11)
		(layer "F.Cu")
		(net 156)
	)
	(segment
		(start 198.575 152.225)
		(end 198.575 152.380651)
		(width 0.11)
		(layer "F.Cu")
		(net 156)
	)
	(segment
		(start 205.449 150.651234)
		(end 204.325234 151.775)
		(width 0.11)
		(layer "F.Cu")
		(net 156)
	)
	(segment
		(start 195.3 152.375)
		(end 194.9 152.375)
		(width 0.11)
		(layer "F.Cu")
		(net 156)
	)
	(segment
		(start 205.329 149.868451)
		(end 205.329 150.133549)
		(width 0.11)
		(layer "F.Cu")
		(net 156)
	)
	(segment
		(start 205.449 149.748451)
		(end 205.329 149.868451)
		(width 0.11)
		(layer "F.Cu")
		(net 156)
	)
	(segment
		(start 199.975 152.225)
		(end 199.975 152.980683)
		(width 0.11)
		(layer "F.Cu")
		(net 156)
	)
	(segment
		(start 205.649 149.351)
		(end 205.449 149.551)
		(width 0.11)
		(layer "F.Cu")
		(net 156)
	)
	(segment
		(start 195.475 153.3)
		(end 195.475 153.483578)
		(width 0.11)
		(layer "F.Cu")
		(net 156)
	)
	(segment
		(start 195.475 153.483578)
		(end 195.333578 153.625)
		(width 0.11)
		(layer "F.Cu")
		(net 156)
	)
	(via
		(at 193.7245 152.801)
		(size 0.35)
		(drill 0.15)
		(layers "F.Cu" "B.Cu")
		(remove_unused_layers yes)
		(keep_end_layers yes)
		(zone_layer_connections)
		(net 156)
	)
	(arc
		(start 194.9 152.375)
		(mid 194.634835 152.484835)
		(end 194.525 152.75)
		(width 0.11)
		(layer "F.Cu")
		(net 156)
	)
	(arc
		(start 198.325 152.630651)
		(mid 198.148223 152.557428)
		(end 198.075 152.380651)
		(width 0.11)
		(layer "F.Cu")
		(net 156)
	)
	(arc
		(start 199.475 152.225)
		(mid 199.343198 151.906802)
		(end 199.025 151.775)
		(width 0.11)
		(layer "F.Cu")
		(net 156)
	)
	(arc
		(start 199.025 151.775)
		(mid 198.706802 151.906802)
		(end 198.575 152.225)
		(width 0.11)
		(layer "F.Cu")
		(net 156)
	)
	(arc
		(start 195.3 153.125)
		(mid 195.423744 153.176256)
		(end 195.475 153.3)
		(width 0.11)
		(layer "F.Cu")
		(net 156)
	)
	(arc
		(start 198.075 152.225)
		(mid 197.943198 151.906802)
		(end 197.625 151.775)
		(width 0.11)
		(layer "F.Cu")
		(net 156)
	)
	(arc
		(start 198.575 152.380651)
		(mid 198.501777 152.557428)
		(end 198.325 152.630651)
		(width 0.11)
		(layer "F.Cu")
		(net 156)
	)
	(arc
		(start 194.525 152.75)
		(mid 194.634835 153.015165)
		(end 194.9 153.125)
		(width 0.11)
		(layer "F.Cu")
		(net 156)
	)
	(arc
		(start 199.725 153.230683)
		(mid 199.548223 153.15746)
		(end 199.475 152.980683)
		(width 0.11)
		(layer "F.Cu")
		(net 156)
	)
	(arc
		(start 200.425 151.775)
		(mid 200.106802 151.906802)
		(end 199.975 152.225)
		(width 0.11)
		(layer "F.Cu")
		(net 156)
	)
	(arc
		(start 199.975 152.980683)
		(mid 199.901777 153.15746)
		(end 199.725 153.230683)
		(width 0.11)
		(layer "F.Cu")
		(net 156)
	)
	(arc
		(start 195.475 152.2)
		(mid 195.423744 152.323744)
		(end 195.3 152.375)
		(width 0.11)
		(layer "F.Cu")
		(net 156)
	)
	(segment
		(start 193.980328 152.92825)
		(end 193.85175 152.92825)
		(width 0.11)
		(layer "B.Cu")
		(net 156)
	)
	(segment
		(start 194.122 151.461)
		(end 194.122 151.676)
		(width 0.11)
		(layer "B.Cu")
		(net 156)
	)
	(segment
		(start 194.222 152.686578)
		(end 193.980328 152.92825)
		(width 0.11)
		(layer "B.Cu")
		(net 156)
	)
	(segment
		(start 194.122 151.676)
		(end 194.222 151.776)
		(width 0.11)
		(layer "B.Cu")
		(net 156)
	)
	(segment
		(start 193.85175 152.92825)
		(end 193.7245 152.801)
		(width 0.11)
		(layer "B.Cu")
		(net 156)
	)
	(segment
		(start 194.222 151.776)
		(end 194.222 152.686578)
		(width 0.11)
		(layer "B.Cu")
		(net 156)
	)
	(segment
		(start 194.09875 149.881765)
		(end 194.216 149.764515)
		(width 0.1)
		(layer "F.Cu")
		(net 157)
	)
	(segment
		(start 194.9 148.69)
		(end 194.99 148.6)
		(width 0.1)
		(layer "F.Cu")
		(net 157)
	)
	(segment
		(start 194.9 149.355564)
		(end 194.9 148.69)
		(width 0.1)
		(layer "F.Cu")
		(net 157)
	)
	(segment
		(start 194.491049 149.764515)
		(end 194.9 149.355564)
		(width 0.1)
		(layer "F.Cu")
		(net 157)
	)
	(segment
		(start 194.216 149.764515)
		(end 194.491049 149.764515)
		(width 0.1)
		(layer "F.Cu")
		(net 157)
	)
	(segment
		(start 194.99 148.6)
		(end 194.99 148.4)
		(width 0.1)
		(layer "F.Cu")
		(net 157)
	)
	(via
		(at 194.072 154.9)
		(size 0.35)
		(drill 0.15)
		(layers "F.Cu" "B.Cu")
		(remove_unused_layers yes)
		(keep_end_layers yes)
		(zone_layer_connections)
		(net 157)
	)
	(via
		(at 194.09875 149.881765)
		(size 0.35)
		(drill 0.15)
		(layers "F.Cu" "B.Cu")
		(remove_unused_layers yes)
		(keep_end_layers yes)
		(zone_layer_connections)
		(net 157)
	)
	(segment
		(start 194.122 154.386)
		(end 194.212 154.476)
		(width 0.1)
		(layer "B.Cu")
		(net 157)
	)
	(segment
		(start 194.212 154.476)
		(end 194.212 154.76)
		(width 0.1)
		(layer "B.Cu")
		(net 157)
	)
	(segment
		(start 194.212 154.76)
		(end 194.072 154.9)
		(width 0.1)
		(layer "B.Cu")
		(net 157)
	)
	(segment
		(start 194.122 154.171)
		(end 194.122 154.386)
		(width 0.1)
		(layer "B.Cu")
		(net 157)
	)
	(segment
		(start 194.206 149.774515)
		(end 194.324809 149.774515)
		(width 0.09)
		(layer "In2.Cu")
		(net 157)
	)
	(segment
		(start 194.037 151.645)
		(end 194.157 151.645)
		(width 0.09)
		(layer "In2.Cu")
		(net 157)
	)
	(segment
		(start 194.324809 149.774515)
		(end 194.5 149.949706)
		(width 0.09)
		(layer "In2.Cu")
		(net 157)
	)
	(segment
		(start 194.202 150.548294)
		(end 194.202 150.83)
		(width 0.09)
		(layer "In2.Cu")
		(net 157)
	)
	(segment
		(start 194.202 151.69)
		(end 194.202 154.77)
		(width 0.09)
		(layer "In2.Cu")
		(net 157)
	)
	(segment
		(start 194.157 150.875)
		(end 194.037 150.875)
		(width 0.09)
		(layer "In2.Cu")
		(net 157)
	)
	(segment
		(start 194.5 149.949706)
		(end 194.5 150.250294)
		(width 0.09)
		(layer "In2.Cu")
		(net 157)
	)
	(segment
		(start 194.202 154.77)
		(end 194.072 154.9)
		(width 0.09)
		(layer "In2.Cu")
		(net 157)
	)
	(segment
		(start 194.5 150.250294)
		(end 194.202 150.548294)
		(width 0.09)
		(layer "In2.Cu")
		(net 157)
	)
	(segment
		(start 193.752 151.16)
		(end 193.752 151.36)
		(width 0.09)
		(layer "In2.Cu")
		(net 157)
	)
	(segment
		(start 194.09875 149.881765)
		(end 194.206 149.774515)
		(width 0.09)
		(layer "In2.Cu")
		(net 157)
	)
	(arc
		(start 194.037 150.875)
		(mid 193.835475 150.958475)
		(end 193.752 151.16)
		(width 0.09)
		(layer "In2.Cu")
		(net 157)
	)
	(arc
		(start 194.157 151.645)
		(mid 194.18882 151.65818)
		(end 194.202 151.69)
		(width 0.09)
		(layer "In2.Cu")
		(net 157)
	)
	(arc
		(start 194.202 150.83)
		(mid 194.18882 150.86182)
		(end 194.157 150.875)
		(width 0.09)
		(layer "In2.Cu")
		(net 157)
	)
	(arc
		(start 193.752 151.36)
		(mid 193.835475 151.561525)
		(end 194.037 151.645)
		(width 0.09)
		(layer "In2.Cu")
		(net 157)
	)
	(segment
		(start 192.65175 153.12825)
		(end 192.5245 153.2555)
		(width 0.11)
		(layer "F.Cu")
		(net 158)
	)
	(segment
		(start 203.966422 151.4)
		(end 199.15 151.4)
		(width 0.11)
		(layer "F.Cu")
		(net 158)
	)
	(segment
		(start 197.25 150.717333)
		(end 197.25 151.025)
		(width 0.11)
		(layer "F.Cu")
		(net 158)
	)
	(segment
		(start 197.6 151.025)
		(end 197.6 150.717333)
		(width 0.11)
		(layer "F.Cu")
		(net 158)
	)
	(segment
		(start 193.3 152.691422)
		(end 192.863172 153.12825)
		(width 0.11)
		(layer "F.Cu")
		(net 158)
	)
	(segment
		(start 198.775 151.025)
		(end 198.775 148.977671)
		(width 0.11)
		(layer "F.Cu")
		(net 158)
	)
	(segment
		(start 198.05 151.4)
		(end 197.975 151.4)
		(width 0.11)
		(layer "F.Cu")
		(net 158)
	)
	(segment
		(start 192.863172 153.12825)
		(end 192.65175 153.12825)
		(width 0.11)
		(layer "F.Cu")
		(net 158)
	)
	(segment
		(start 193.916422 151.4)
		(end 193.3 152.016422)
		(width 0.11)
		(layer "F.Cu")
		(net 158)
	)
	(segment
		(start 198.425 148.977671)
		(end 198.425 151.025)
		(width 0.11)
		(layer "F.Cu")
		(net 158)
	)
	(segment
		(start 204.480049 150.431048)
		(end 204.480049 150.6)
		(width 0.11)
		(layer "F.Cu")
		(net 158)
	)
	(segment
		(start 204.349 150.731048)
		(end 204.349 151.017422)
		(width 0.11)
		(layer "F.Cu")
		(net 158)
	)
	(segment
		(start 204.349 150.001)
		(end 204.349 150.3)
		(width 0.11)
		(layer "F.Cu")
		(net 158)
	)
	(segment
		(start 204.349 151.017422)
		(end 203.966422 151.4)
		(width 0.11)
		(layer "F.Cu")
		(net 158)
	)
	(segment
		(start 193.3 152.016422)
		(end 193.3 152.691422)
		(width 0.11)
		(layer "F.Cu")
		(net 158)
	)
	(segment
		(start 204.414525 150.665524)
		(end 204.414524 150.665524)
		(width 0.11)
		(layer "F.Cu")
		(net 158)
	)
	(segment
		(start 196.875 151.4)
		(end 193.916422 151.4)
		(width 0.11)
		(layer "F.Cu")
		(net 158)
	)
	(segment
		(start 204.414524 150.365524)
		(end 204.414525 150.365524)
		(width 0.11)
		(layer "F.Cu")
		(net 158)
	)
	(via
		(at 192.5245 153.2555)
		(size 0.35)
		(drill 0.15)
		(layers "F.Cu" "B.Cu")
		(remove_unused_layers yes)
		(keep_end_layers yes)
		(zone_layer_connections)
		(net 158)
	)
	(arc
		(start 197.25 151.025)
		(mid 197.140165 151.290165)
		(end 196.875 151.4)
		(width 0.11)
		(layer "F.Cu")
		(net 158)
	)
	(arc
		(start 197.425 150.542333)
		(mid 197.301256 150.593589)
		(end 197.25 150.717333)
		(width 0.11)
		(layer "F.Cu")
		(net 158)
	)
	(arc
		(start 199.15 151.4)
		(mid 198.884835 151.290165)
		(end 198.775 151.025)
		(width 0.11)
		(layer "F.Cu")
		(net 158)
	)
	(arc
		(start 204.414525 150.365524)
		(mid 204.460857 150.384716)
		(end 204.480049 150.431048)
		(width 0.11)
		(layer "F.Cu")
		(net 158)
	)
	(arc
		(start 198.425 151.025)
		(mid 198.315165 151.290165)
		(end 198.05 151.4)
		(width 0.11)
		(layer "F.Cu")
		(net 158)
	)
	(arc
		(start 204.414524 150.665524)
		(mid 204.368192 150.684716)
		(end 204.349 150.731048)
		(width 0.11)
		(layer "F.Cu")
		(net 158)
	)
	(arc
		(start 204.480049 150.6)
		(mid 204.460857 150.646332)
		(end 204.414525 150.665524)
		(width 0.11)
		(layer "F.Cu")
		(net 158)
	)
	(arc
		(start 197.6 150.717333)
		(mid 197.548744 150.593589)
		(end 197.425 150.542333)
		(width 0.11)
		(layer "F.Cu")
		(net 158)
	)
	(arc
		(start 204.349 150.3)
		(mid 204.368192 150.346332)
		(end 204.414524 150.365524)
		(width 0.11)
		(layer "F.Cu")
		(net 158)
	)
	(arc
		(start 197.975 151.4)
		(mid 197.709835 151.290165)
		(end 197.6 151.025)
		(width 0.11)
		(layer "F.Cu")
		(net 158)
	)
	(arc
		(start 198.6 148.802671)
		(mid 198.476256 148.853927)
		(end 198.425 148.977671)
		(width 0.11)
		(layer "F.Cu")
		(net 158)
	)
	(arc
		(start 198.775 148.977671)
		(mid 198.723744 148.853927)
		(end 198.6 148.802671)
		(width 0.11)
		(layer "F.Cu")
		(net 158)
	)
	(segment
		(start 193.322 151.676)
		(end 193.222 151.776)
		(width 0.11)
		(layer "B.Cu")
		(net 158)
	)
	(segment
		(start 193.222 152.769422)
		(end 192.863172 153.12825)
		(width 0.11)
		(layer "B.Cu")
		(net 158)
	)
	(segment
		(start 192.65175 153.12825)
		(end 192.5245 153.2555)
		(width 0.11)
		(layer "B.Cu")
		(net 158)
	)
	(segment
		(start 193.222 151.776)
		(end 193.222 152.769422)
		(width 0.11)
		(layer "B.Cu")
		(net 158)
	)
	(segment
		(start 193.322 151.461)
		(end 193.322 151.676)
		(width 0.11)
		(layer "B.Cu")
		(net 158)
	)
	(segment
		(start 192.863172 153.12825)
		(end 192.65175 153.12825)
		(width 0.11)
		(layer "B.Cu")
		(net 158)
	)
	(segment
		(start 193.209413 149.485023)
		(end 193.48 149.214436)
		(width 0.1)
		(layer "F.Cu")
		(net 159)
	)
	(segment
		(start 192.76868 149.367773)
		(end 192.88593 149.485023)
		(width 0.1)
		(layer "F.Cu")
		(net 159)
	)
	(segment
		(start 193.48 148.69)
		(end 193.39 148.6)
		(width 0.1)
		(layer "F.Cu")
		(net 159)
	)
	(segment
		(start 193.39 148.6)
		(end 193.39 148.4)
		(width 0.1)
		(layer "F.Cu")
		(net 159)
	)
	(segment
		(start 192.88593 149.485023)
		(end 193.209413 149.485023)
		(width 0.1)
		(layer "F.Cu")
		(net 159)
	)
	(segment
		(start 193.48 149.214436)
		(end 193.48 148.69)
		(width 0.1)
		(layer "F.Cu")
		(net 159)
	)
	(via
		(at 192.76868 149.367773)
		(size 0.35)
		(drill 0.15)
		(layers "F.Cu" "B.Cu")
		(remove_unused_layers yes)
		(keep_end_layers yes)
		(zone_layer_connections)
		(net 159)
	)
	(via
		(at 193.372 154.9)
		(size 0.35)
		(drill 0.15)
		(layers "F.Cu" "B.Cu")
		(remove_unused_layers yes)
		(keep_end_layers yes)
		(zone_layer_connections)
		(net 159)
	)
	(segment
		(start 193.322 154.386)
		(end 193.232 154.476)
		(width 0.1)
		(layer "B.Cu")
		(net 159)
	)
	(segment
		(start 193.322 154.171)
		(end 193.322 154.386)
		(width 0.1)
		(layer "B.Cu")
		(net 159)
	)
	(segment
		(start 193.232 154.76)
		(end 193.372 154.9)
		(width 0.1)
		(layer "B.Cu")
		(net 159)
	)
	(segment
		(start 193.232 154.476)
		(end 193.232 154.76)
		(width 0.1)
		(layer "B.Cu")
		(net 159)
	)
	(segment
		(start 193.075495 149.475023)
		(end 193.395504 149.795032)
		(width 0.09)
		(layer "In2.Cu")
		(net 159)
	)
	(segment
		(start 192.952975 151.199025)
		(end 192.832974 151.199025)
		(width 0.09)
		(layer "In2.Cu")
		(net 159)
	)
	(segment
		(start 193.242 151.77805)
		(end 193.242 154.77)
		(width 0.09)
		(layer "In2.Cu")
		(net 159)
	)
	(segment
		(start 192.832974 151.489025)
		(end 192.952975 151.489025)
		(width 0.09)
		(layer "In2.Cu")
		(net 159)
	)
	(segment
		(start 193.395504 149.795032)
		(end 193.395504 150.324202)
		(width 0.09)
		(layer "In2.Cu")
		(net 159)
	)
	(segment
		(start 193.242 150.477706)
		(end 193.242 150.91)
		(width 0.09)
		(layer "In2.Cu")
		(net 159)
	)
	(segment
		(start 193.395504 150.324202)
		(end 193.242 150.477706)
		(width 0.09)
		(layer "In2.Cu")
		(net 159)
	)
	(segment
		(start 192.87593 149.475023)
		(end 193.075495 149.475023)
		(width 0.09)
		(layer "In2.Cu")
		(net 159)
	)
	(segment
		(start 192.76868 149.367773)
		(end 192.87593 149.475023)
		(width 0.09)
		(layer "In2.Cu")
		(net 159)
	)
	(segment
		(start 193.242 154.77)
		(end 193.372 154.9)
		(width 0.09)
		(layer "In2.Cu")
		(net 159)
	)
	(segment
		(start 192.783949 151.24805)
		(end 192.783949 151.44)
		(width 0.09)
		(layer "In2.Cu")
		(net 159)
	)
	(arc
		(start 192.783949 151.44)
		(mid 192.798308 151.474666)
		(end 192.832974 151.489025)
		(width 0.09)
		(layer "In2.Cu")
		(net 159)
	)
	(arc
		(start 192.952975 151.489025)
		(mid 193.157347 151.573678)
		(end 193.242 151.77805)
		(width 0.09)
		(layer "In2.Cu")
		(net 159)
	)
	(arc
		(start 193.242 150.91)
		(mid 193.157347 151.114372)
		(end 192.952975 151.199025)
		(width 0.09)
		(layer "In2.Cu")
		(net 159)
	)
	(arc
		(start 192.832974 151.199025)
		(mid 192.798308 151.213384)
		(end 192.783949 151.24805)
		(width 0.09)
		(layer "In2.Cu")
		(net 159)
	)
	(segment
		(start 198.05 151.2)
		(end 197.975 151.2)
		(width 0.11)
		(layer "F.Cu")
		(net 160)
	)
	(segment
		(start 204.125 150.958578)
		(end 203.883578 151.2)
		(width 0.11)
		(layer "F.Cu")
		(net 160)
	)
	(segment
		(start 204.349 149.351)
		(end 204.029 149.671)
		(width 0.11)
		(layer "F.Cu")
		(net 160)
	)
	(segment
		(start 192.780328 152.92825)
		(end 192.65175 152.92825)
		(width 0.11)
		(layer "F.Cu")
		(net 160)
	)
	(segment
		(start 198.975 151.025)
		(end 198.975 148.977671)
		(width 0.11)
		(layer "F.Cu")
		(net 160)
	)
	(segment
		(start 193.1 151.933578)
		(end 193.1 152.608578)
		(width 0.11)
		(layer "F.Cu")
		(net 160)
	)
	(segment
		(start 204.029 150.286586)
		(end 204.125 150.382586)
		(width 0.11)
		(layer "F.Cu")
		(net 160)
	)
	(segment
		(start 197.05 150.717333)
		(end 197.05 151.025)
		(width 0.11)
		(layer "F.Cu")
		(net 160)
	)
	(segment
		(start 204.029 149.671)
		(end 204.029 150.286586)
		(width 0.11)
		(layer "F.Cu")
		(net 160)
	)
	(segment
		(start 198.225 148.977671)
		(end 198.225 151.025)
		(width 0.11)
		(layer "F.Cu")
		(net 160)
	)
	(segment
		(start 197.8 151.025)
		(end 197.8 150.717333)
		(width 0.11)
		(layer "F.Cu")
		(net 160)
	)
	(segment
		(start 196.875 151.2)
		(end 193.833578 151.2)
		(width 0.11)
		(layer "F.Cu")
		(net 160)
	)
	(segment
		(start 203.883578 151.2)
		(end 199.15 151.2)
		(width 0.11)
		(layer "F.Cu")
		(net 160)
	)
	(segment
		(start 193.1 152.608578)
		(end 192.780328 152.92825)
		(width 0.11)
		(layer "F.Cu")
		(net 160)
	)
	(segment
		(start 192.65175 152.92825)
		(end 192.5245 152.801)
		(width 0.11)
		(layer "F.Cu")
		(net 160)
	)
	(segment
		(start 193.833578 151.2)
		(end 193.1 151.933578)
		(width 0.11)
		(layer "F.Cu")
		(net 160)
	)
	(segment
		(start 204.125 150.382586)
		(end 204.125 150.958578)
		(width 0.11)
		(layer "F.Cu")
		(net 160)
	)
	(via
		(at 192.5245 152.801)
		(size 0.35)
		(drill 0.15)
		(layers "F.Cu" "B.Cu")
		(remove_unused_layers yes)
		(keep_end_layers yes)
		(zone_layer_connections)
		(net 160)
	)
	(arc
		(start 198.225 151.025)
		(mid 198.173744 151.148744)
		(end 198.05 151.2)
		(width 0.11)
		(layer "F.Cu")
		(net 160)
	)
	(arc
		(start 197.8 150.717333)
		(mid 197.690165 150.452168)
		(end 197.425 150.342333)
		(width 0.11)
		(layer "F.Cu")
		(net 160)
	)
	(arc
		(start 198.975 148.977671)
		(mid 198.865165 148.712506)
		(end 198.6 148.602671)
		(width 0.11)
		(layer "F.Cu")
		(net 160)
	)
	(arc
		(start 197.05 151.025)
		(mid 196.998744 151.148744)
		(end 196.875 151.2)
		(width 0.11)
		(layer "F.Cu")
		(net 160)
	)
	(arc
		(start 197.975 151.2)
		(mid 197.851256 151.148744)
		(end 197.8 151.025)
		(width 0.11)
		(layer "F.Cu")
		(net 160)
	)
	(arc
		(start 199.15 151.2)
		(mid 199.026256 151.148744)
		(end 198.975 151.025)
		(width 0.11)
		(layer "F.Cu")
		(net 160)
	)
	(arc
		(start 198.6 148.602671)
		(mid 198.334835 148.712506)
		(end 198.225 148.977671)
		(width 0.11)
		(layer "F.Cu")
		(net 160)
	)
	(arc
		(start 197.425 150.342333)
		(mid 197.159835 150.452168)
		(end 197.05 150.717333)
		(width 0.11)
		(layer "F.Cu")
		(net 160)
	)
	(segment
		(start 192.922 151.461)
		(end 192.922 151.676)
		(width 0.11)
		(layer "B.Cu")
		(net 160)
	)
	(segment
		(start 193.022 151.776)
		(end 193.022 152.686578)
		(width 0.11)
		(layer "B.Cu")
		(net 160)
	)
	(segment
		(start 192.922 151.676)
		(end 193.022 151.776)
		(width 0.11)
		(layer "B.Cu")
		(net 160)
	)
	(segment
		(start 192.65175 152.92825)
		(end 192.5245 152.801)
		(width 0.11)
		(layer "B.Cu")
		(net 160)
	)
	(segment
		(start 192.780328 152.92825)
		(end 192.65175 152.92825)
		(width 0.11)
		(layer "B.Cu")
		(net 160)
	)
	(segment
		(start 193.022 152.686578)
		(end 192.780328 152.92825)
		(width 0.11)
		(layer "B.Cu")
		(net 160)
	)
	(segment
		(start 193.7 149.305564)
		(end 193.7 148.69)
		(width 0.1)
		(layer "F.Cu")
		(net 161)
	)
	(segment
		(start 193.7 148.69)
		(end 193.79 148.6)
		(width 0.1)
		(layer "F.Cu")
		(net 161)
	)
	(segment
		(start 192.88593 149.705023)
		(end 193.300541 149.705023)
		(width 0.1)
		(layer "F.Cu")
		(net 161)
	)
	(segment
		(start 193.300541 149.705023)
		(end 193.7 149.305564)
		(width 0.1)
		(layer "F.Cu")
		(net 161)
	)
	(segment
		(start 193.79 148.6)
		(end 193.79 148.4)
		(width 0.1)
		(layer "F.Cu")
		(net 161)
	)
	(segment
		(start 192.76868 149.822273)
		(end 192.88593 149.705023)
		(width 0.1)
		(layer "F.Cu")
		(net 161)
	)
	(via
		(at 192.76868 149.822273)
		(size 0.35)
		(drill 0.15)
		(layers "F.Cu" "B.Cu")
		(remove_unused_layers yes)
		(keep_end_layers yes)
		(zone_layer_connections)
		(net 161)
	)
	(via
		(at 192.872 154.9)
		(size 0.35)
		(drill 0.15)
		(layers "F.Cu" "B.Cu")
		(remove_unused_layers yes)
		(keep_end_layers yes)
		(zone_layer_connections)
		(net 161)
	)
	(segment
		(start 193.012 154.76)
		(end 192.872 154.9)
		(width 0.1)
		(layer "B.Cu")
		(net 161)
	)
	(segment
		(start 192.922 154.386)
		(end 193.012 154.476)
		(width 0.1)
		(layer "B.Cu")
		(net 161)
	)
	(segment
		(start 192.922 154.171)
		(end 192.922 154.386)
		(width 0.1)
		(layer "B.Cu")
		(net 161)
	)
	(segment
		(start 193.012 154.476)
		(end 193.012 154.76)
		(width 0.1)
		(layer "B.Cu")
		(net 161)
	)
	(segment
		(start 192.87593 149.715023)
		(end 192.976083 149.715023)
		(width 0.09)
		(layer "In2.Cu")
		(net 161)
	)
	(segment
		(start 192.543949 151.24805)
		(end 192.543949 151.44)
		(width 0.09)
		(layer "In2.Cu")
		(net 161)
	)
	(segment
		(start 192.976083 149.715023)
		(end 193.155504 149.894444)
		(width 0.09)
		(layer "In2.Cu")
		(net 161)
	)
	(segment
		(start 192.952975 150.959025)
		(end 192.832974 150.959025)
		(width 0.09)
		(layer "In2.Cu")
		(net 161)
	)
	(segment
		(start 193.002 151.77805)
		(end 193.002 154.77)
		(width 0.09)
		(layer "In2.Cu")
		(net 161)
	)
	(segment
		(start 192.832974 151.729025)
		(end 192.952975 151.729025)
		(width 0.09)
		(layer "In2.Cu")
		(net 161)
	)
	(segment
		(start 192.76868 149.822273)
		(end 192.87593 149.715023)
		(width 0.09)
		(layer "In2.Cu")
		(net 161)
	)
	(segment
		(start 193.155504 149.894444)
		(end 193.155504 150.22479)
		(width 0.09)
		(layer "In2.Cu")
		(net 161)
	)
	(segment
		(start 193.002 150.378294)
		(end 193.002 150.91)
		(width 0.09)
		(layer "In2.Cu")
		(net 161)
	)
	(segment
		(start 193.155504 150.22479)
		(end 193.002 150.378294)
		(width 0.09)
		(layer "In2.Cu")
		(net 161)
	)
	(segment
		(start 193.002 154.77)
		(end 192.872 154.9)
		(width 0.09)
		(layer "In2.Cu")
		(net 161)
	)
	(arc
		(start 192.832974 150.959025)
		(mid 192.628602 151.043678)
		(end 192.543949 151.24805)
		(width 0.09)
		(layer "In2.Cu")
		(net 161)
	)
	(arc
		(start 193.002 150.91)
		(mid 192.987641 150.944666)
		(end 192.952975 150.959025)
		(width 0.09)
		(layer "In2.Cu")
		(net 161)
	)
	(arc
		(start 192.543949 151.44)
		(mid 192.628602 151.644372)
		(end 192.832974 151.729025)
		(width 0.09)
		(layer "In2.Cu")
		(net 161)
	)
	(arc
		(start 192.952975 151.729025)
		(mid 192.987641 151.743384)
		(end 193.002 151.77805)
		(width 0.09)
		(layer "In2.Cu")
		(net 161)
	)
	(via
		(at 204.999 150.001)
		(size 0.35)
		(drill 0.15)
		(layers "F.Cu" "B.Cu")
		(remove_unused_layers yes)
		(keep_end_layers yes)
		(zone_layer_connections)
		(net 162)
	)
	(via
		(at 191.865816 150.384184)
		(size 0.35)
		(drill 0.15)
		(layers "F.Cu" "B.Cu")
		(remove_unused_layers yes)
		(keep_end_layers yes)
		(zone_layer_connections)
		(net 162)
	)
	(segment
		(start 192.022 150.720326)
		(end 191.865816 150.564142)
		(width 0.11)
		(layer "B.Cu")
		(net 162)
	)
	(segment
		(start 192.022 151.146)
		(end 192.022 150.720326)
		(width 0.11)
		(layer "B.Cu")
		(net 162)
	)
	(segment
		(start 191.865816 150.564142)
		(end 191.865816 150.384184)
		(width 0.11)
		(layer "B.Cu")
		(net 162)
	)
	(segment
		(start 192.122 151.246)
		(end 192.022 151.146)
		(width 0.11)
		(layer "B.Cu")
		(net 162)
	)
	(segment
		(start 192.122 151.461)
		(end 192.122 151.246)
		(width 0.11)
		(layer "B.Cu")
		(net 162)
	)
	(segment
		(start 205.550844 149.876193)
		(end 205.550844 150.161456)
		(width 0.09)
		(layer "In9.Cu")
		(net 162)
	)
	(segment
		(start 201.540648 150.375)
		(end 203.47785 150.375)
		(width 0.09)
		(layer "In9.Cu")
		(net 162)
	)
	(segment
		(start 203.913925 150.238925)
		(end 203.913925 150.238924)
		(width 0.09)
		(layer "In9.Cu")
		(net 162)
	)
	(segment
		(start 205.229 149.771)
		(end 205.445651 149.771)
		(width 0.09)
		(layer "In9.Cu")
		(net 162)
	)
	(segment
		(start 205.445651 149.771)
		(end 205.550844 149.876193)
		(width 0.09)
		(layer "In9.Cu")
		(net 162)
	)
	(segment
		(start 192.289351 151.005)
		(end 198.659652 151.005)
		(width 0.09)
		(layer "In9.Cu")
		(net 162)
	)
	(segment
		(start 205.3373 150.375)
		(end 204.65 150.375)
		(width 0.09)
		(layer "In9.Cu")
		(net 162)
	)
	(segment
		(start 191.855564 150.571213)
		(end 191.855564 150.394436)
		(width 0.09)
		(layer "In9.Cu")
		(net 162)
	)
	(segment
		(start 199.509652 151.910349)
		(end 199.47 151.910349)
		(width 0.09)
		(layer "In9.Cu")
		(net 162)
	)
	(segment
		(start 204.37785 150.102849)
		(end 204.35 150.102849)
		(width 0.09)
		(layer "In9.Cu")
		(net 162)
	)
	(segment
		(start 199.159826 151.600175)
		(end 199.159826 151.505174)
		(width 0.09)
		(layer "In9.Cu")
		(net 162)
	)
	(segment
		(start 192.289351 151.005)
		(end 191.855564 150.571213)
		(width 0.09)
		(layer "In9.Cu")
		(net 162)
	)
	(segment
		(start 204.07785 150.375)
		(end 204.05 150.375)
		(width 0.09)
		(layer "In9.Cu")
		(net 162)
	)
	(segment
		(start 203.77785 150.102849)
		(end 203.75 150.102849)
		(width 0.09)
		(layer "In9.Cu")
		(net 162)
	)
	(segment
		(start 205.550844 150.161456)
		(end 205.3373 150.375)
		(width 0.09)
		(layer "In9.Cu")
		(net 162)
	)
	(segment
		(start 200.910648 151.005)
		(end 200.32 151.005)
		(width 0.09)
		(layer "In9.Cu")
		(net 162)
	)
	(segment
		(start 199.819826 151.505174)
		(end 199.819826 151.600175)
		(width 0.09)
		(layer "In9.Cu")
		(net 162)
	)
	(segment
		(start 204.513925 150.238925)
		(end 204.513925 150.238924)
		(width 0.09)
		(layer "In9.Cu")
		(net 162)
	)
	(segment
		(start 204.213925 150.238924)
		(end 204.213925 150.238925)
		(width 0.09)
		(layer "In9.Cu")
		(net 162)
	)
	(segment
		(start 201.540648 150.375)
		(end 200.910648 151.005)
		(width 0.09)
		(layer "In9.Cu")
		(net 162)
	)
	(segment
		(start 203.613925 150.238924)
		(end 203.613925 150.238925)
		(width 0.09)
		(layer "In9.Cu")
		(net 162)
	)
	(segment
		(start 204.999 150.001)
		(end 205.229 149.771)
		(width 0.09)
		(layer "In9.Cu")
		(net 162)
	)
	(arc
		(start 204.35 150.102849)
		(mid 204.25378 150.142704)
		(end 204.213925 150.238924)
		(width 0.09)
		(layer "In9.Cu")
		(net 162)
	)
	(arc
		(start 203.75 150.102849)
		(mid 203.65378 150.142704)
		(end 203.613925 150.238924)
		(width 0.09)
		(layer "In9.Cu")
		(net 162)
	)
	(arc
		(start 199.819826 151.600175)
		(mid 199.728978 151.819501)
		(end 199.509652 151.910349)
		(width 0.09)
		(layer "In9.Cu")
		(net 162)
	)
	(arc
		(start 204.05 150.375)
		(mid 203.95378 150.335145)
		(end 203.913925 150.238925)
		(width 0.09)
		(layer "In9.Cu")
		(net 162)
	)
	(arc
		(start 204.65 150.375)
		(mid 204.55378 150.335145)
		(end 204.513925 150.238925)
		(width 0.09)
		(layer "In9.Cu")
		(net 162)
	)
	(arc
		(start 199.47 151.910349)
		(mid 199.250674 151.819501)
		(end 199.159826 151.600175)
		(width 0.09)
		(layer "In9.Cu")
		(net 162)
	)
	(arc
		(start 203.913925 150.238924)
		(mid 203.87407 150.142704)
		(end 203.77785 150.102849)
		(width 0.09)
		(layer "In9.Cu")
		(net 162)
	)
	(arc
		(start 199.159826 151.505174)
		(mid 199.013328 151.151498)
		(end 198.659652 151.005)
		(width 0.09)
		(layer "In9.Cu")
		(net 162)
	)
	(arc
		(start 204.213925 150.238925)
		(mid 204.17407 150.335145)
		(end 204.07785 150.375)
		(width 0.09)
		(layer "In9.Cu")
		(net 162)
	)
	(arc
		(start 200.32 151.005)
		(mid 199.966324 151.151498)
		(end 199.819826 151.505174)
		(width 0.09)
		(layer "In9.Cu")
		(net 162)
	)
	(arc
		(start 203.613925 150.238925)
		(mid 203.57407 150.335145)
		(end 203.47785 150.375)
		(width 0.09)
		(layer "In9.Cu")
		(net 162)
	)
	(arc
		(start 204.513925 150.238924)
		(mid 204.47407 150.142704)
		(end 204.37785 150.102849)
		(width 0.09)
		(layer "In9.Cu")
		(net 162)
	)
	(segment
		(start 191.859413 149.485023)
		(end 191.426784 149.485023)
		(width 0.1)
		(layer "F.Cu")
		(net 163)
	)
	(segment
		(start 191.426784 149.485023)
		(end 191.309534 149.367773)
		(width 0.1)
		(layer "F.Cu")
		(net 163)
	)
	(segment
		(start 192.59 148.4)
		(end 192.59 148.754436)
		(width 0.1)
		(layer "F.Cu")
		(net 163)
	)
	(segment
		(start 192.59 148.754436)
		(end 191.859413 149.485023)
		(width 0.1)
		(layer "F.Cu")
		(net 163)
	)
	(via
		(at 192.172 154.9)
		(size 0.35)
		(drill 0.15)
		(layers "F.Cu" "B.Cu")
		(remove_unused_layers yes)
		(keep_end_layers yes)
		(zone_layer_connections)
		(net 163)
	)
	(via
		(at 191.309534 149.367773)
		(size 0.35)
		(drill 0.15)
		(layers "F.Cu" "B.Cu")
		(remove_unused_layers yes)
		(keep_end_layers yes)
		(zone_layer_connections)
		(net 163)
	)
	(segment
		(start 192.032 154.76)
		(end 192.172 154.9)
		(width 0.1)
		(layer "B.Cu")
		(net 163)
	)
	(segment
		(start 192.122 154.386)
		(end 192.032 154.476)
		(width 0.1)
		(layer "B.Cu")
		(net 163)
	)
	(segment
		(start 192.122 154.171)
		(end 192.122 154.386)
		(width 0.1)
		(layer "B.Cu")
		(net 163)
	)
	(segment
		(start 192.032 154.476)
		(end 192.032 154.76)
		(width 0.1)
		(layer "B.Cu")
		(net 163)
	)
	(segment
		(start 191.309534 149.367773)
		(end 191.416784 149.475023)
		(width 0.09)
		(layer "In2.Cu")
		(net 163)
	)
	(segment
		(start 192.038233 152.028527)
		(end 192.042 152.032294)
		(width 0.09)
		(layer "In2.Cu")
		(net 163)
	)
	(segment
		(start 191.531142 148.450848)
		(end 190.958858 148.450848)
		(width 0.09)
		(layer "In2.Cu")
		(net 163)
	)
	(segment
		(start 190.80324 151.18)
		(end 191.189706 151.18)
		(width 0.09)
		(layer "In2.Cu")
		(net 163)
	)
	(segment
		(start 192.042 154.77)
		(end 192.172 154.9)
		(width 0.09)
		(layer "In2.Cu")
		(net 163)
	)
	(segment
		(start 191.615271 149.475023)
		(end 191.78 149.310294)
		(width 0.09)
		(layer "In2.Cu")
		(net 163)
	)
	(segment
		(start 190.56 148.849706)
		(end 190.56 149.08)
		(width 0.09)
		(layer "In2.Cu")
		(net 163)
	)
	(segment
		(start 191.376062 151.18)
		(end 191.376063 151.18)
		(width 0.09)
		(layer "In2.Cu")
		(net 163)
	)
	(segment
		(start 191.588194 151.39213)
		(end 191.588195 151.392132)
		(width 0.09)
		(layer "In2.Cu")
		(net 163)
	)
	(segment
		(start 191.562419 151.18)
		(end 191.562419 151.179999)
		(width 0.09)
		(layer "In2.Cu")
		(net 163)
	)
	(segment
		(start 190.56 150.93676)
		(end 190.80324 151.18)
		(width 0.09)
		(layer "In2.Cu")
		(net 163)
	)
	(segment
		(start 191.588193 151.578487)
		(end 191.61397 151.604264)
		(width 0.09)
		(layer "In2.Cu")
		(net 163)
	)
	(segment
		(start 191.588195 151.392132)
		(end 191.588193 151.392131)
		(width 0.09)
		(layer "In2.Cu")
		(net 163)
	)
	(segment
		(start 191.826102 151.604264)
		(end 191.882098 151.548269)
		(width 0.09)
		(layer "In2.Cu")
		(net 163)
	)
	(segment
		(start 190.56 150.23)
		(end 190.56 150.28)
		(width 0.09)
		(layer "In2.Cu")
		(net 163)
	)
	(segment
		(start 190.71 149.23)
		(end 190.81 149.23)
		(width 0.09)
		(layer "In2.Cu")
		(net 163)
	)
	(segment
		(start 190.56 150.78)
		(end 190.56 150.93676)
		(width 0.09)
		(layer "In2.Cu")
		(net 163)
	)
	(segment
		(start 192.094229 151.760402)
		(end 192.09423 151.760401)
		(width 0.09)
		(layer "In2.Cu")
		(net 163)
	)
	(segment
		(start 191.376063 151.179999)
		(end 191.376062 151.18)
		(width 0.09)
		(layer "In2.Cu")
		(net 163)
	)
	(segment
		(start 190.958858 148.450848)
		(end 190.56 148.849706)
		(width 0.09)
		(layer "In2.Cu")
		(net 163)
	)
	(segment
		(start 191.562419 151.179999)
		(end 191.588194 151.205774)
		(width 0.09)
		(layer "In2.Cu")
		(net 163)
	)
	(segment
		(start 191.78 148.699706)
		(end 191.531142 148.450848)
		(width 0.09)
		(layer "In2.Cu")
		(net 163)
	)
	(segment
		(start 191.78 149.310294)
		(end 191.78 148.699706)
		(width 0.09)
		(layer "In2.Cu")
		(net 163)
	)
	(segment
		(start 192.09423 151.760401)
		(end 192.038233 151.816395)
		(width 0.09)
		(layer "In2.Cu")
		(net 163)
	)
	(segment
		(start 191.416784 149.475023)
		(end 191.615271 149.475023)
		(width 0.09)
		(layer "In2.Cu")
		(net 163)
	)
	(segment
		(start 190.76 150.48)
		(end 190.76 150.58)
		(width 0.09)
		(layer "In2.Cu")
		(net 163)
	)
	(segment
		(start 190.81 149.93)
		(end 190.81 149.98)
		(width 0.09)
		(layer "In2.Cu")
		(net 163)
	)
	(segment
		(start 191.826103 151.604263)
		(end 191.826102 151.604264)
		(width 0.09)
		(layer "In2.Cu")
		(net 163)
	)
	(segment
		(start 192.042 152.032294)
		(end 192.042 154.77)
		(width 0.09)
		(layer "In2.Cu")
		(net 163)
	)
	(segment
		(start 190.81 149.53)
		(end 190.71 149.53)
		(width 0.09)
		(layer "In2.Cu")
		(net 163)
	)
	(arc
		(start 190.96 149.38)
		(mid 190.916066 149.486066)
		(end 190.81 149.53)
		(width 0.09)
		(layer "In2.Cu")
		(net 163)
	)
	(arc
		(start 190.56 149.08)
		(mid 190.603934 149.186066)
		(end 190.71 149.23)
		(width 0.09)
		(layer "In2.Cu")
		(net 163)
	)
	(arc
		(start 190.81 149.98)
		(mid 190.773388 150.068388)
		(end 190.685 150.105)
		(width 0.09)
		(layer "In2.Cu")
		(net 163)
	)
	(arc
		(start 191.189706 151.18)
		(mid 191.282885 151.218595)
		(end 191.376063 151.179999)
		(width 0.09)
		(layer "In2.Cu")
		(net 163)
	)
	(arc
		(start 190.56 150.28)
		(mid 190.589289 150.350711)
		(end 190.66 150.38)
		(width 0.09)
		(layer "In2.Cu")
		(net 163)
	)
	(arc
		(start 191.882098 151.548269)
		(mid 191.988164 151.504335)
		(end 192.09423 151.548269)
		(width 0.09)
		(layer "In2.Cu")
		(net 163)
	)
	(arc
		(start 190.76 150.58)
		(mid 190.730711 150.650711)
		(end 190.66 150.68)
		(width 0.09)
		(layer "In2.Cu")
		(net 163)
	)
	(arc
		(start 191.61397 151.604264)
		(mid 191.720038 151.648199)
		(end 191.826103 151.604263)
		(width 0.09)
		(layer "In2.Cu")
		(net 163)
	)
	(arc
		(start 190.56 149.68)
		(mid 190.596612 149.768388)
		(end 190.685 149.805)
		(width 0.09)
		(layer "In2.Cu")
		(net 163)
	)
	(arc
		(start 190.71 149.53)
		(mid 190.603934 149.573934)
		(end 190.56 149.68)
		(width 0.09)
		(layer "In2.Cu")
		(net 163)
	)
	(arc
		(start 190.685 150.105)
		(mid 190.596612 150.141612)
		(end 190.56 150.23)
		(width 0.09)
		(layer "In2.Cu")
		(net 163)
	)
	(arc
		(start 190.81 149.23)
		(mid 190.916066 149.273934)
		(end 190.96 149.38)
		(width 0.09)
		(layer "In2.Cu")
		(net 163)
	)
	(arc
		(start 192.038233 151.816395)
		(mid 191.994299 151.922461)
		(end 192.038233 152.028527)
		(width 0.09)
		(layer "In2.Cu")
		(net 163)
	)
	(arc
		(start 191.588194 151.205774)
		(mid 191.62679 151.298952)
		(end 191.588194 151.39213)
		(width 0.09)
		(layer "In2.Cu")
		(net 163)
	)
	(arc
		(start 190.685 149.805)
		(mid 190.773388 149.841612)
		(end 190.81 149.93)
		(width 0.09)
		(layer "In2.Cu")
		(net 163)
	)
	(arc
		(start 192.09423 151.548269)
		(mid 192.138163 151.654335)
		(end 192.094229 151.760402)
		(width 0.09)
		(layer "In2.Cu")
		(net 163)
	)
	(arc
		(start 191.376063 151.18)
		(mid 191.469241 151.141404)
		(end 191.562419 151.18)
		(width 0.09)
		(layer "In2.Cu")
		(net 163)
	)
	(arc
		(start 190.66 150.38)
		(mid 190.730711 150.409289)
		(end 190.76 150.48)
		(width 0.09)
		(layer "In2.Cu")
		(net 163)
	)
	(arc
		(start 191.588193 151.392131)
		(mid 191.549597 151.485309)
		(end 191.588193 151.578487)
		(width 0.09)
		(layer "In2.Cu")
		(net 163)
	)
	(arc
		(start 190.66 150.68)
		(mid 190.589289 150.709289)
		(end 190.56 150.78)
		(width 0.09)
		(layer "In2.Cu")
		(net 163)
	)
	(segment
		(start 213.04 118.65)
		(end 212.9 118.79)
		(width 0.1)
		(layer "F.Cu")
		(net 164)
	)
	(segment
		(start 212.388416 118.79)
		(end 212.263416 118.665)
		(width 0.1)
		(layer "F.Cu")
		(net 164)
	)
	(segment
		(start 212.9 118.79)
		(end 212.388416 118.79)
		(width 0.1)
		(layer "F.Cu")
		(net 164)
	)
	(segment
		(start 213.325 118.65)
		(end 213.04 118.65)
		(width 0.1)
		(layer "F.Cu")
		(net 164)
	)
	(via
		(at 212.263416 118.665)
		(size 0.35)
		(drill 0.15)
		(layers "F.Cu" "B.Cu")
		(remove_unused_layers yes)
		(keep_end_layers yes)
		(zone_layer_connections)
		(net 164)
	)
	(segment
		(start 213.325 122.15)
		(end 213.04 122.15)
		(width 0.1)
		(layer "F.Cu")
		(net 165)
	)
	(segment
		(start 212.388416 122.01)
		(end 212.263416 122.135)
		(width 0.1)
		(layer "F.Cu")
		(net 165)
	)
	(segment
		(start 212.9 122.01)
		(end 212.388416 122.01)
		(width 0.1)
		(layer "F.Cu")
		(net 165)
	)
	(segment
		(start 213.04 122.15)
		(end 212.9 122.01)
		(width 0.1)
		(layer "F.Cu")
		(net 165)
	)
	(via
		(at 212.263416 122.135)
		(size 0.35)
		(drill 0.15)
		(layers "F.Cu" "B.Cu")
		(remove_unused_layers yes)
		(keep_end_layers yes)
		(zone_layer_connections)
		(net 165)
	)
	(segment
		(start 212.149716 122.0213)
		(end 212.263416 122.135)
		(width 0.1)
		(layer "B.Cu")
		(net 165)
	)
	(segment
		(start 211.4419 122.0213)
		(end 212.149716 122.0213)
		(width 0.1)
		(layer "B.Cu")
		(net 165)
	)
	(segment
		(start 211.0316 122.4066)
		(end 211.0566 122.4066)
		(width 0.1)
		(layer "B.Cu")
		(net 165)
	)
	(segment
		(start 211.0566 122.4066)
		(end 211.4419 122.0213)
		(width 0.1)
		(layer "B.Cu")
		(net 165)
	)
	(segment
		(start 212.529176 123.226388)
		(end 212.529176 123.403166)
		(width 0.1)
		(layer "F.Cu")
		(net 166)
	)
	(segment
		(start 213.325 123.15)
		(end 213.04 123.15)
		(width 0.1)
		(layer "F.Cu")
		(net 166)
	)
	(segment
		(start 212.9 123.01)
		(end 212.745564 123.01)
		(width 0.1)
		(layer "F.Cu")
		(net 166)
	)
	(segment
		(start 212.745564 123.01)
		(end 212.529176 123.226388)
		(width 0.1)
		(layer "F.Cu")
		(net 166)
	)
	(segment
		(start 213.04 123.15)
		(end 212.9 123.01)
		(width 0.1)
		(layer "F.Cu")
		(net 166)
	)
	(via
		(at 212.529176 123.403166)
		(size 0.35)
		(drill 0.15)
		(layers "F.Cu" "B.Cu")
		(remove_unused_layers yes)
		(keep_end_layers yes)
		(zone_layer_connections)
		(net 166)
	)
	(segment
		(start 212.352398 123.403166)
		(end 211.753064 124.0025)
		(width 0.1)
		(layer "B.Cu")
		(net 166)
	)
	(segment
		(start 211.082 124.3878)
		(end 211.057 124.3878)
		(width 0.1)
		(layer "B.Cu")
		(net 166)
	)
	(segment
		(start 212.529176 123.403166)
		(end 212.352398 123.403166)
		(width 0.1)
		(layer "B.Cu")
		(net 166)
	)
	(segment
		(start 211.4673 124.0025)
		(end 211.082 124.3878)
		(width 0.1)
		(layer "B.Cu")
		(net 166)
	)
	(segment
		(start 211.753064 124.0025)
		(end 211.4673 124.0025)
		(width 0.1)
		(layer "B.Cu")
		(net 166)
	)
	(segment
		(start 213.325 119.15)
		(end 213.04 119.15)
		(width 0.1)
		(layer "F.Cu")
		(net 167)
	)
	(segment
		(start 212.9 119.01)
		(end 212.388416 119.01)
		(width 0.1)
		(layer "F.Cu")
		(net 167)
	)
	(segment
		(start 213.04 119.15)
		(end 212.9 119.01)
		(width 0.1)
		(layer "F.Cu")
		(net 167)
	)
	(segment
		(start 212.388416 119.01)
		(end 212.263416 119.135)
		(width 0.1)
		(layer "F.Cu")
		(net 167)
	)
	(via
		(at 212.263416 119.135)
		(size 0.35)
		(drill 0.15)
		(layers "F.Cu" "B.Cu")
		(remove_unused_layers yes)
		(keep_end_layers yes)
		(zone_layer_connections)
		(net 167)
	)
	(segment
		(start 212.388416 121.79)
		(end 212.263416 121.665)
		(width 0.1)
		(layer "F.Cu")
		(net 169)
	)
	(segment
		(start 213.325 121.65)
		(end 213.04 121.65)
		(width 0.1)
		(layer "F.Cu")
		(net 169)
	)
	(segment
		(start 213.04 121.65)
		(end 212.9 121.79)
		(width 0.1)
		(layer "F.Cu")
		(net 169)
	)
	(segment
		(start 212.9 121.79)
		(end 212.388416 121.79)
		(width 0.1)
		(layer "F.Cu")
		(net 169)
	)
	(via
		(at 212.263416 121.665)
		(size 0.35)
		(drill 0.15)
		(layers "F.Cu" "B.Cu")
		(remove_unused_layers yes)
		(keep_end_layers yes)
		(zone_layer_connections)
		(net 169)
	)
	(segment
		(start 211.0316 121.416)
		(end 211.0566 121.416)
		(width 0.1)
		(layer "B.Cu")
		(net 169)
	)
	(segment
		(start 211.4419 121.8013)
		(end 212.127116 121.8013)
		(width 0.1)
		(layer "B.Cu")
		(net 169)
	)
	(segment
		(start 212.127116 121.8013)
		(end 212.263416 121.665)
		(width 0.1)
		(layer "B.Cu")
		(net 169)
	)
	(segment
		(start 211.0566 121.416)
		(end 211.4419 121.8013)
		(width 0.1)
		(layer "B.Cu")
		(net 169)
	)
	(segment
		(start 213.325 122.65)
		(end 213.04 122.65)
		(width 0.1)
		(layer "F.Cu")
		(net 170)
	)
	(segment
		(start 213.04 122.65)
		(end 212.9 122.79)
		(width 0.1)
		(layer "F.Cu")
		(net 170)
	)
	(segment
		(start 212.9 122.79)
		(end 212.654436 122.79)
		(width 0.1)
		(layer "F.Cu")
		(net 170)
	)
	(segment
		(start 212.373612 123.070824)
		(end 212.196834 123.070824)
		(width 0.1)
		(layer "F.Cu")
		(net 170)
	)
	(segment
		(start 212.654436 122.79)
		(end 212.373612 123.070824)
		(width 0.1)
		(layer "F.Cu")
		(net 170)
	)
	(via
		(at 212.196834 123.070824)
		(size 0.35)
		(drill 0.15)
		(layers "F.Cu" "B.Cu")
		(remove_unused_layers yes)
		(keep_end_layers yes)
		(zone_layer_connections)
		(net 170)
	)
	(segment
		(start 211.661936 123.7825)
		(end 211.4673 123.7825)
		(width 0.1)
		(layer "B.Cu")
		(net 170)
	)
	(segment
		(start 212.196834 123.070824)
		(end 212.196834 123.247602)
		(width 0.1)
		(layer "B.Cu")
		(net 170)
	)
	(segment
		(start 212.196834 123.247602)
		(end 211.661936 123.7825)
		(width 0.1)
		(layer "B.Cu")
		(net 170)
	)
	(segment
		(start 211.4673 123.7825)
		(end 211.082 123.3972)
		(width 0.1)
		(layer "B.Cu")
		(net 170)
	)
	(segment
		(start 211.082 123.3972)
		(end 211.057 123.3972)
		(width 0.1)
		(layer "B.Cu")
		(net 170)
	)
	(segment
		(start 220.6015 147.592001)
		(end 220.6015 147.817)
		(width 0.15)
		(layer "F.Cu")
		(net 171)
	)
	(segment
		(start 222.100746 147.046314)
		(end 221.147187 147.046314)
		(width 0.15)
		(layer "F.Cu")
		(net 171)
	)
	(segment
		(start 221.147187 147.046314)
		(end 220.6015 147.592001)
		(width 0.15)
		(layer "F.Cu")
		(net 171)
	)
	(via
		(at 191.57 116.78)
		(size 0.35)
		(drill 0.15)
		(layers "F.Cu" "B.Cu")
		(remove_unused_layers yes)
		(keep_end_layers yes)
		(zone_layer_connections)
		(net 171)
	)
	(via
		(at 222.100746 147.046314)
		(size 0.35)
		(drill 0.15)
		(layers "F.Cu" "B.Cu")
		(remove_unused_layers yes)
		(keep_end_layers yes)
		(zone_layer_connections)
		(net 171)
	)
	(segment
		(start 222.311429 146.606429)
		(end 222.141071 146.606429)
		(width 0.15)
		(layer "B.Cu")
		(net 171)
	)
	(segment
		(start 222.55 145.92353)
		(end 222.55 146.367858)
		(width 0.15)
		(layer "B.Cu")
		(net 171)
	)
	(segment
		(start 191.724 117.461)
		(end 191.724 116.934)
		(width 0.15)
		(layer "B.Cu")
		(net 171)
	)
	(segment
		(start 191.724 116.934)
		(end 191.57 116.78)
		(width 0.15)
		(layer "B.Cu")
		(net 171)
	)
	(segment
		(start 221.7175 145.375)
		(end 222.040013 145.697513)
		(width 0.15)
		(layer "B.Cu")
		(net 171)
	)
	(segment
		(start 222.040013 145.697513)
		(end 222.323983 145.697513)
		(width 0.15)
		(layer "B.Cu")
		(net 171)
	)
	(segment
		(start 222.141071 146.606429)
		(end 221.9325 146.815)
		(width 0.15)
		(layer "B.Cu")
		(net 171)
	)
	(segment
		(start 222.323983 145.697513)
		(end 222.55 145.92353)
		(width 0.15)
		(layer "B.Cu")
		(net 171)
	)
	(segment
		(start 222.55 146.367858)
		(end 222.311429 146.606429)
		(width 0.15)
		(layer "B.Cu")
		(net 171)
	)
	(segment
		(start 211.822 147.920794)
		(end 211.822 148.279743)
		(width 0.1)
		(layer "In4.Cu")
		(net 171)
	)
	(segment
		(start 204.55762 131.1)
		(end 204.974 131.51638)
		(width 0.1)
		(layer "In4.Cu")
		(net 171)
	)
	(segment
		(start 208.25 136)
		(end 209.2 136.95)
		(width 0.1)
		(layer "In4.Cu")
		(net 171)
	)
	(segment
		(start 196.825 128.28562)
		(end 197.32438 128.785)
		(width 0.1)
		(layer "In4.Cu")
		(net 171)
	)
	(segment
		(start 198.24462 128.785)
		(end 198.49231 129.03269)
		(width 0.1)
		(layer "In4.Cu")
		(net 171)
	)
	(segment
		(start 202.03938 131.1)
		(end 204.55762 131.1)
		(width 0.1)
		(layer "In4.Cu")
		(net 171)
	)
	(segment
		(start 205.275 131.975)
		(end 205.575 131.975)
		(width 0.1)
		(layer "In4.Cu")
		(net 171)
	)
	(segment
		(start 198.9 129.6)
		(end 199.1 129.8)
		(width 0.1)
		(layer "In4.Cu")
		(net 171)
	)
	(segment
		(start 198.49231 129.49231)
		(end 198.6 129.6)
		(width 0.1)
		(layer "In4.Cu")
		(net 171)
	)
	(segment
		(start 190.8 118.9)
		(end 191.375 119.475)
		(width 0.1)
		(layer "In4.Cu")
		(net 171)
	)
	(segment
		(start 190.8 117.55)
		(end 190.8 118.9)
		(width 0.1)
		(layer "In4.Cu")
		(net 171)
	)
	(segment
		(start 211.824 144.484)
		(end 211.824 147.918794)
		(width 0.1)
		(layer "In4.Cu")
		(net 171)
	)
	(segment
		(start 199.1 129.8)
		(end 199.99519 129.8)
		(width 0.1)
		(layer "In4.Cu")
		(net 171)
	)
	(segment
		(start 209.2 136.95)
		(end 210.3 136.95)
		(width 0.1)
		(layer "In4.Cu")
		(net 171)
	)
	(segment
		(start 211.65 144.31)
		(end 211.824 144.484)
		(width 0.1)
		(layer "In4.Cu")
		(net 171)
	)
	(segment
		(start 198.49231 129.03269)
		(end 198.49231 129.49231)
		(width 0.1)
		(layer "In4.Cu")
		(net 171)
	)
	(segment
		(start 198.6 129.6)
		(end 198.9 129.6)
		(width 0.1)
		(layer "In4.Cu")
		(net 171)
	)
	(segment
		(start 199.99519 129.8)
		(end 200.32019 129.475)
		(width 0.1)
		(layer "In4.Cu")
		(net 171)
	)
	(segment
		(start 195.76 126.43)
		(end 195.76 126.71)
		(width 0.1)
		(layer "In4.Cu")
		(net 171)
	)
	(segment
		(start 204.974 131.674)
		(end 205.275 131.975)
		(width 0.1)
		(layer "In4.Cu")
		(net 171)
	)
	(segment
		(start 196.825 127.775)
		(end 196.825 128.28562)
		(width 0.1)
		(layer "In4.Cu")
		(net 171)
	)
	(segment
		(start 201.65 130.71062)
		(end 202.03938 131.1)
		(width 0.1)
		(layer "In4.Cu")
		(net 171)
	)
	(segment
		(start 212.46 148.57)
		(end 214.69 150.8)
		(width 0.1)
		(layer "In4.Cu")
		(net 171)
	)
	(segment
		(start 191.57 116.78)
		(end 190.8 117.55)
		(width 0.1)
		(layer "In4.Cu")
		(net 171)
	)
	(segment
		(start 208.25 134.65)
		(end 208.25 136)
		(width 0.1)
		(layer "In4.Cu")
		(net 171)
	)
	(segment
		(start 219.55 150.8)
		(end 222.100746 148.249254)
		(width 0.1)
		(layer "In4.Cu")
		(net 171)
	)
	(segment
		(start 212.112257 148.57)
		(end 212.46 148.57)
		(width 0.1)
		(layer "In4.Cu")
		(net 171)
	)
	(segment
		(start 201.175 129.475)
		(end 201.65 129.95)
		(width 0.1)
		(layer "In4.Cu")
		(net 171)
	)
	(segment
		(start 191.975 119.475)
		(end 194.45 121.95)
		(width 0.1)
		(layer "In4.Cu")
		(net 171)
	)
	(segment
		(start 205.575 131.975)
		(end 208.25 134.65)
		(width 0.1)
		(layer "In4.Cu")
		(net 171)
	)
	(segment
		(start 201.65 129.95)
		(end 201.65 130.71062)
		(width 0.1)
		(layer "In4.Cu")
		(net 171)
	)
	(segment
		(start 191.375 119.475)
		(end 191.975 119.475)
		(width 0.1)
		(layer "In4.Cu")
		(net 171)
	)
	(segment
		(start 197.32438 128.785)
		(end 198.24462 128.785)
		(width 0.1)
		(layer "In4.Cu")
		(net 171)
	)
	(segment
		(start 204.974 131.51638)
		(end 204.974 131.674)
		(width 0.1)
		(layer "In4.Cu")
		(net 171)
	)
	(segment
		(start 194.45 125.12)
		(end 195.76 126.43)
		(width 0.1)
		(layer "In4.Cu")
		(net 171)
	)
	(segment
		(start 222.100746 148.249254)
		(end 222.100746 147.046314)
		(width 0.1)
		(layer "In4.Cu")
		(net 171)
	)
	(segment
		(start 211.824 147.918794)
		(end 211.822 147.920794)
		(width 0.1)
		(layer "In4.Cu")
		(net 171)
	)
	(segment
		(start 211.65 138.3)
		(end 211.65 144.31)
		(width 0.1)
		(layer "In4.Cu")
		(net 171)
	)
	(segment
		(start 200.32019 129.475)
		(end 201.175 129.475)
		(width 0.1)
		(layer "In4.Cu")
		(net 171)
	)
	(segment
		(start 194.45 121.95)
		(end 194.45 125.12)
		(width 0.1)
		(layer "In4.Cu")
		(net 171)
	)
	(segment
		(start 195.76 126.71)
		(end 196.825 127.775)
		(width 0.1)
		(layer "In4.Cu")
		(net 171)
	)
	(segment
		(start 214.69 150.8)
		(end 219.55 150.8)
		(width 0.1)
		(layer "In4.Cu")
		(net 171)
	)
	(segment
		(start 211.822 148.279743)
		(end 212.112257 148.57)
		(width 0.1)
		(layer "In4.Cu")
		(net 171)
	)
	(segment
		(start 210.3 136.95)
		(end 211.65 138.3)
		(width 0.1)
		(layer "In4.Cu")
		(net 171)
	)
	(via
		(at 220.067563 145.972411)
		(size 0.35)
		(drill 0.15)
		(layers "F.Cu" "B.Cu")
		(remove_unused_layers yes)
		(keep_end_layers yes)
		(zone_layer_connections)
		(net 172)
	)
	(via
		(at 191.055 116.815)
		(size 0.35)
		(drill 0.15)
		(layers "F.Cu" "B.Cu")
		(remove_unused_layers yes)
		(keep_end_layers yes)
		(zone_layer_connections)
		(net 172)
	)
	(segment
		(start 191.055 116.815)
		(end 191.055 116.88)
		(width 0.15)
		(layer "B.Cu")
		(net 172)
	)
	(segment
		(start 191.322 117.147)
		(end 191.322 117.461)
		(width 0.15)
		(layer "B.Cu")
		(net 172)
	)
	(segment
		(start 191.055 116.88)
		(end 191.322 117.147)
		(width 0.15)
		(layer "B.Cu")
		(net 172)
	)
	(segment
		(start 220.067563 145.972411)
		(end 220.120089 145.972411)
		(width 0.15)
		(layer "B.Cu")
		(net 172)
	)
	(segment
		(start 220.114911 145.972411)
		(end 220.9575 146.815)
		(width 0.15)
		(layer "B.Cu")
		(net 172)
	)
	(segment
		(start 220.067563 145.972411)
		(end 220.114911 145.972411)
		(width 0.256)
		(layer "B.Cu")
		(net 172)
	)
	(segment
		(start 220.120089 145.972411)
		(end 220.7175 145.375)
		(width 0.15)
		(layer "B.Cu")
		(net 172)
	)
	(segment
		(start 202.03938 131.9)
		(end 201.775 131.63562)
		(width 0.1)
		(layer "In4.Cu")
		(net 172)
	)
	(segment
		(start 205.775 132.975)
		(end 205.55 132.75)
		(width 0.1)
		(layer "In4.Cu")
		(net 172)
	)
	(segment
		(start 194.15 122.05)
		(end 194.15 125.3)
		(width 0.1)
		(layer "In4.Cu")
		(net 172)
	)
	(segment
		(start 205.28938 132.75)
		(end 204.974 132.43462)
		(width 0.1)
		(layer "In4.Cu")
		(net 172)
	)
	(segment
		(start 219.65 151.05)
		(end 214.62462 151.05)
		(width 0.1)
		(layer "In4.Cu")
		(net 172)
	)
	(segment
		(start 222.35 147.25668)
		(end 222.35 148.35)
		(width 0.1)
		(layer "In4.Cu")
		(net 172)
	)
	(segment
		(start 207.85 135)
		(end 206.4 133.55)
		(width 0.1)
		(layer "In4.Cu")
		(net 172)
	)
	(segment
		(start 211.804794 148.82)
		(end 211.13 148.145206)
		(width 0.1)
		(layer "In4.Cu")
		(net 172)
	)
	(segment
		(start 201.25 130.8)
		(end 201.25 130.5)
		(width 0.1)
		(layer "In4.Cu")
		(net 172)
	)
	(segment
		(start 195.215 127.55)
		(end 195.215 126.365)
		(width 0.1)
		(layer "In4.Cu")
		(net 172)
	)
	(segment
		(start 195.215 126.365)
		(end 194.15 125.3)
		(width 0.1)
		(layer "In4.Cu")
		(net 172)
	)
	(segment
		(start 198.925 129.95)
		(end 197.525 129.95)
		(width 0.1)
		(layer "In4.Cu")
		(net 172)
	)
	(segment
		(start 211.4 146.91)
		(end 211.176 146.686)
		(width 0.1)
		(layer "In4.Cu")
		(net 172)
	)
	(segment
		(start 222.25 145.5)
		(end 222.525 145.775)
		(width 0.1)
		(layer "In4.Cu")
		(net 172)
	)
	(segment
		(start 214.62462 151.05)
		(end 212.39462 148.82)
		(width 0.1)
		(layer "In4.Cu")
		(net 172)
	)
	(segment
		(start 206.08938 133.55)
		(end 205.775 133.23562)
		(width 0.1)
		(layer "In4.Cu")
		(net 172)
	)
	(segment
		(start 191.055 116.815)
		(end 190.5 117.37)
		(width 0.1)
		(layer "In4.Cu")
		(net 172)
	)
	(segment
		(start 211.4 147.43)
		(end 211.4 146.91)
		(width 0.1)
		(layer "In4.Cu")
		(net 172)
	)
	(segment
		(start 200.976 130.226)
		(end 199.201 130.226)
		(width 0.1)
		(layer "In4.Cu")
		(net 172)
	)
	(segment
		(start 199.201 130.226)
		(end 198.925 129.95)
		(width 0.1)
		(layer "In4.Cu")
		(net 172)
	)
	(segment
		(start 211.56 144.82)
		(end 211.425 144.685)
		(width 0.1)
		(layer "In4.Cu")
		(net 172)
	)
	(segment
		(start 222.525 147.08168)
		(end 222.35 147.25668)
		(width 0.1)
		(layer "In4.Cu")
		(net 172)
	)
	(segment
		(start 211.425 144.685)
		(end 211.425 138.595377)
		(width 0.1)
		(layer "In4.Cu")
		(net 172)
	)
	(segment
		(start 197.525 129.95)
		(end 196.975 129.4)
		(width 0.1)
		(layer "In4.Cu")
		(net 172)
	)
	(segment
		(start 211.425 138.595377)
		(end 210.129623 137.3)
		(width 0.1)
		(layer "In4.Cu")
		(net 172)
	)
	(segment
		(start 191.2 119.8)
		(end 191.9 119.8)
		(width 0.1)
		(layer "In4.Cu")
		(net 172)
	)
	(segment
		(start 191.9 119.8)
		(end 194.15 122.05)
		(width 0.1)
		(layer "In4.Cu")
		(net 172)
	)
	(segment
		(start 222.35 148.35)
		(end 219.65 151.05)
		(width 0.1)
		(layer "In4.Cu")
		(net 172)
	)
	(segment
		(start 205.55 132.75)
		(end 205.28938 132.75)
		(width 0.1)
		(layer "In4.Cu")
		(net 172)
	)
	(segment
		(start 206.4 133.55)
		(end 206.08938 133.55)
		(width 0.1)
		(layer "In4.Cu")
		(net 172)
	)
	(segment
		(start 201.775 131.63562)
		(end 201.775 131.325)
		(width 0.1)
		(layer "In4.Cu")
		(net 172)
	)
	(segment
		(start 222.525 145.775)
		(end 222.525 147.08168)
		(width 0.1)
		(layer "In4.Cu")
		(net 172)
	)
	(segment
		(start 196.975 129.4)
		(end 196.975 128.975)
		(width 0.1)
		(layer "In4.Cu")
		(net 172)
	)
	(segment
		(start 220.539974 145.5)
		(end 222.25 145.5)
		(width 0.1)
		(layer "In4.Cu")
		(net 172)
	)
	(segment
		(start 190.5 119.1)
		(end 191.2 119.8)
		(width 0.1)
		(layer "In4.Cu")
		(net 172)
	)
	(segment
		(start 211.176 146.686)
		(end 211.176 146.244)
		(width 0.1)
		(layer "In4.Cu")
		(net 172)
	)
	(segment
		(start 204.974 132.43462)
		(end 204.974 132.224)
		(width 0.1)
		(layer "In4.Cu")
		(net 172)
	)
	(segment
		(start 210.129623 137.3)
		(end 209.1 137.3)
		(width 0.1)
		(layer "In4.Cu")
		(net 172)
	)
	(segment
		(start 205.775 133.23562)
		(end 205.775 132.975)
		(width 0.1)
		(layer "In4.Cu")
		(net 172)
	)
	(segment
		(start 196.7 128.7)
		(end 196.365 128.7)
		(width 0.1)
		(layer "In4.Cu")
		(net 172)
	)
	(segment
		(start 196.975 128.975)
		(end 196.7 128.7)
		(width 0.1)
		(layer "In4.Cu")
		(net 172)
	)
	(segment
		(start 209.1 137.3)
		(end 207.85 136.05)
		(width 0.1)
		(layer "In4.Cu")
		(net 172)
	)
	(segment
		(start 211.13 147.7)
		(end 211.4 147.43)
		(width 0.1)
		(layer "In4.Cu")
		(net 172)
	)
	(segment
		(start 204.974 132.224)
		(end 204.65 131.9)
		(width 0.1)
		(layer "In4.Cu")
		(net 172)
	)
	(segment
		(start 212.39462 148.82)
		(end 211.804794 148.82)
		(width 0.1)
		(layer "In4.Cu")
		(net 172)
	)
	(segment
		(start 201.775 131.325)
		(end 201.25 130.8)
		(width 0.1)
		(layer "In4.Cu")
		(net 172)
	)
	(segment
		(start 211.56 145.86)
		(end 211.56 144.82)
		(width 0.1)
		(layer "In4.Cu")
		(net 172)
	)
	(segment
		(start 196.365 128.7)
		(end 195.215 127.55)
		(width 0.1)
		(layer "In4.Cu")
		(net 172)
	)
	(segment
		(start 201.25 130.5)
		(end 200.976 130.226)
		(width 0.1)
		(layer "In4.Cu")
		(net 172)
	)
	(segment
		(start 190.5 117.37)
		(end 190.5 119.1)
		(width 0.1)
		(layer "In4.Cu")
		(net 172)
	)
	(segment
		(start 220.067563 145.972411)
		(end 220.539974 145.5)
		(width 0.1)
		(layer "In4.Cu")
		(net 172)
	)
	(segment
		(start 211.176 146.244)
		(end 211.56 145.86)
		(width 0.1)
		(layer "In4.Cu")
		(net 172)
	)
	(segment
		(start 204.65 131.9)
		(end 202.03938 131.9)
		(width 0.1)
		(layer "In4.Cu")
		(net 172)
	)
	(segment
		(start 211.13 148.145206)
		(end 211.13 147.7)
		(width 0.1)
		(layer "In4.Cu")
		(net 172)
	)
	(segment
		(start 207.85 136.05)
		(end 207.85 135)
		(width 0.1)
		(layer "In4.Cu")
		(net 172)
	)
	(via
		(at 206.1 129.05)
		(size 0.35)
		(drill 0.15)
		(layers "F.Cu" "B.Cu")
		(remove_unused_layers yes)
		(keep_end_layers yes)
		(zone_layer_connections)
		(net 173)
	)
	(via
		(at 198.519 117.05)
		(size 0.35)
		(drill 0.15)
		(layers "F.Cu" "B.Cu")
		(remove_unused_layers yes)
		(keep_end_layers yes)
		(zone_layer_connections)
		(net 173)
	)
	(segment
		(start 198.7075 129.0825)
		(end 198.7075 128.9325)
		(width 0.1)
		(layer "In4.Cu")
		(net 173)
	)
	(segment
		(start 197.2 117.35)
		(end 198.219 117.35)
		(width 0.1)
		(layer "In4.Cu")
		(net 173)
	)
	(segment
		(start 200.525 128.775)
		(end 199.875 129.425)
		(width 0.1)
		(layer "In4.Cu")
		(net 173)
	)
	(segment
		(start 203.075 128.775)
		(end 200.525 128.775)
		(width 0.1)
		(layer "In4.Cu")
		(net 173)
	)
	(segment
		(start 194.84 121.865478)
		(end 194.535 121.560478)
		(width 0.1)
		(layer "In4.Cu")
		(net 173)
	)
	(segment
		(start 198.219 117.35)
		(end 198.519 117.05)
		(width 0.1)
		(layer "In4.Cu")
		(net 173)
	)
	(segment
		(start 194.535 120.905)
		(end 195.43 120.01)
		(width 0.1)
		(layer "In4.Cu")
		(net 173)
	)
	(segment
		(start 196.185 126.345)
		(end 196.185 125.885)
		(width 0.1)
		(layer "In4.Cu")
		(net 173)
	)
	(segment
		(start 194.84 124.54)
		(end 194.84 121.865478)
		(width 0.1)
		(layer "In4.Cu")
		(net 173)
	)
	(segment
		(start 198.45 128.675)
		(end 198.45 128.15)
		(width 0.1)
		(layer "In4.Cu")
		(net 173)
	)
	(segment
		(start 197.75 127.91)
		(end 196.185 126.345)
		(width 0.1)
		(layer "In4.Cu")
		(net 173)
	)
	(segment
		(start 195.43 119.12)
		(end 197.2 117.35)
		(width 0.1)
		(layer "In4.Cu")
		(net 173)
	)
	(segment
		(start 196.185 125.885)
		(end 194.84 124.54)
		(width 0.1)
		(layer "In4.Cu")
		(net 173)
	)
	(segment
		(start 206.1 129.05)
		(end 203.35 129.05)
		(width 0.1)
		(layer "In4.Cu")
		(net 173)
	)
	(segment
		(start 198.7075 128.9325)
		(end 198.45 128.675)
		(width 0.1)
		(layer "In4.Cu")
		(net 173)
	)
	(segment
		(start 198.21 127.91)
		(end 197.75 127.91)
		(width 0.1)
		(layer "In4.Cu")
		(net 173)
	)
	(segment
		(start 199.05 129.425)
		(end 198.7075 129.0825)
		(width 0.1)
		(layer "In4.Cu")
		(net 173)
	)
	(segment
		(start 195.43 120.01)
		(end 195.43 119.12)
		(width 0.1)
		(layer "In4.Cu")
		(net 173)
	)
	(segment
		(start 194.535 121.560478)
		(end 194.535 120.905)
		(width 0.1)
		(layer "In4.Cu")
		(net 173)
	)
	(segment
		(start 198.45 128.15)
		(end 198.21 127.91)
		(width 0.1)
		(layer "In4.Cu")
		(net 173)
	)
	(segment
		(start 203.35 129.05)
		(end 203.075 128.775)
		(width 0.1)
		(layer "In4.Cu")
		(net 173)
	)
	(segment
		(start 199.875 129.425)
		(end 199.05 129.425)
		(width 0.1)
		(layer "In4.Cu")
		(net 173)
	)
	(via
		(at 197.8 118.135)
		(size 0.35)
		(drill 0.15)
		(layers "F.Cu" "B.Cu")
		(remove_unused_layers yes)
		(keep_end_layers yes)
		(zone_layer_connections)
		(net 174)
	)
	(via
		(at 203.699 137.101)
		(size 0.35)
		(drill 0.15)
		(layers "F.Cu" "B.Cu")
		(remove_unused_layers yes)
		(keep_end_layers yes)
		(zone_layer_connections)
		(net 174)
	)
	(segment
		(start 198.522 118.382)
		(end 198.522 120.171)
		(width 0.15)
		(layer "B.Cu")
		(net 174)
	)
	(segment
		(start 198.275 118.135)
		(end 198.522 118.382)
		(width 0.15)
		(layer "B.Cu")
		(net 174)
	)
	(segment
		(start 197.8 118.135)
		(end 198.275 118.135)
		(width 0.15)
		(layer "B.Cu")
		(net 174)
	)
	(segment
		(start 195.05 133.05)
		(end 195.825 133.825)
		(width 0.1)
		(layer "In9.Cu")
		(net 174)
	)
	(segment
		(start 198.925 135.86738)
		(end 199.92831 136.87069)
		(width 0.1)
		(layer "In9.Cu")
		(net 174)
	)
	(segment
		(start 202.64569 136.7)
		(end 203.298 136.7)
		(width 0.1)
		(layer "In9.Cu")
		(net 174)
	)
	(segment
		(start 198.65 133.825)
		(end 198.925 134.1)
		(width 0.1)
		(layer "In9.Cu")
		(net 174)
	)
	(segment
		(start 195.825 133.825)
		(end 198.65 133.825)
		(width 0.1)
		(layer "In9.Cu")
		(net 174)
	)
	(segment
		(start 192.61 133.05)
		(end 195.05 133.05)
		(width 0.1)
		(layer "In9.Cu")
		(net 174)
	)
	(segment
		(start 197.05 119.230051)
		(end 196.200051 120.08)
		(width 0.1)
		(layer "In9.Cu")
		(net 174)
	)
	(segment
		(start 192.14 122.84)
		(end 192.14 132.58)
		(width 0.1)
		(layer "In9.Cu")
		(net 174)
	)
	(segment
		(start 194.9 120.08)
		(end 192.14 122.84)
		(width 0.1)
		(layer "In9.Cu")
		(net 174)
	)
	(segment
		(start 197.05 118.885)
		(end 197.05 119.230051)
		(width 0.1)
		(layer "In9.Cu")
		(net 174)
	)
	(segment
		(start 199.92831 136.87069)
		(end 202.475 136.87069)
		(width 0.1)
		(layer "In9.Cu")
		(net 174)
	)
	(segment
		(start 203.298 136.7)
		(end 203.699 137.101)
		(width 0.1)
		(layer "In9.Cu")
		(net 174)
	)
	(segment
		(start 196.200051 120.08)
		(end 194.9 120.08)
		(width 0.1)
		(layer "In9.Cu")
		(net 174)
	)
	(segment
		(start 202.475 136.87069)
		(end 202.64569 136.7)
		(width 0.1)
		(layer "In9.Cu")
		(net 174)
	)
	(segment
		(start 198.925 134.1)
		(end 198.925 135.86738)
		(width 0.1)
		(layer "In9.Cu")
		(net 174)
	)
	(segment
		(start 197.8 118.135)
		(end 197.05 118.885)
		(width 0.1)
		(layer "In9.Cu")
		(net 174)
	)
	(segment
		(start 192.14 132.58)
		(end 192.61 133.05)
		(width 0.1)
		(layer "In9.Cu")
		(net 174)
	)
	(segment
		(start 206.526 146.426)
		(end 205.442962 146.426)
		(width 0.1)
		(layer "F.Cu")
		(net 176)
	)
	(segment
		(start 206.701 146.426)
		(end 206.526 146.426)
		(width 0.201)
		(layer "F.Cu")
		(net 176)
	)
	(segment
		(start 207.55 147.775)
		(end 207.55 147.566234)
		(width 0.201)
		(layer "F.Cu")
		(net 176)
	)
	(segment
		(start 204.349 147.401)
		(end 204.024 147.726)
		(width 0.1)
		(layer "F.Cu")
		(net 176)
	)
	(segment
		(start 203.374 147.726)
		(end 203.049 147.401)
		(width 0.1)
		(layer "F.Cu")
		(net 176)
	)
	(segment
		(start 204.024 147.726)
		(end 203.374 147.726)
		(width 0.1)
		(layer "F.Cu")
		(net 176)
	)
	(segment
		(start 207.55 147.566234)
		(end 206.925 146.941234)
		(width 0.201)
		(layer "F.Cu")
		(net 176)
	)
	(segment
		(start 205.324 146.426)
		(end 204.349 147.401)
		(width 0.201)
		(layer "F.Cu")
		(net 176)
	)
	(segment
		(start 206.925 146.65)
		(end 206.701 146.426)
		(width 0.201)
		(layer "F.Cu")
		(net 176)
	)
	(segment
		(start 206.925 146.941234)
		(end 206.925 146.65)
		(width 0.201)
		(layer "F.Cu")
		(net 176)
	)
	(segment
		(start 205.324 146.426)
		(end 205.442962 146.426)
		(width 0.201)
		(layer "F.Cu")
		(net 176)
	)
	(via
		(at 203.049 147.401)
		(size 0.35)
		(drill 0.15)
		(layers "F.Cu" "B.Cu")
		(remove_unused_layers yes)
		(keep_end_layers yes)
		(zone_layer_connections)
		(net 176)
	)
	(via
		(at 207.55 147.775)
		(size 0.35)
		(drill 0.15)
		(layers "F.Cu" "B.Cu")
		(remove_unused_layers yes)
		(keep_end_layers yes)
		(zone_layer_connections)
		(net 176)
	)
	(via
		(at 204.349 147.401)
		(size 0.35)
		(drill 0.15)
		(layers "F.Cu" "B.Cu")
		(remove_unused_layers yes)
		(keep_end_layers yes)
		(zone_layer_connections)
		(net 176)
	)
	(via
		(at 204.45 136.3)
		(size 0.35)
		(drill 0.15)
		(layers "F.Cu" "B.Cu")
		(remove_unused_layers yes)
		(keep_end_layers yes)
		(zone_layer_connections)
		(net 177)
	)
	(via
		(at 197.717 118.71)
		(size 0.35)
		(drill 0.15)
		(layers "F.Cu" "B.Cu")
		(remove_unused_layers yes)
		(keep_end_layers yes)
		(zone_layer_connections)
		(net 177)
	)
	(segment
		(start 198.122 119.122)
		(end 198.122 120.171)
		(width 0.15)
		(layer "B.Cu")
		(net 177)
	)
	(segment
		(start 197.717 118.717)
		(end 198.122 119.122)
		(width 0.15)
		(layer "B.Cu")
		(net 177)
	)
	(segment
		(start 197.717 118.71)
		(end 197.717 118.717)
		(width 0.15)
		(layer "B.Cu")
		(net 177)
	)
	(segment
		(start 192.89 132.47)
		(end 192.89 122.55)
		(width 0.09)
		(layer "In9.Cu")
		(net 177)
	)
	(segment
		(start 199.352549 133.1)
		(end 195.84 133.1)
		(width 0.09)
		(layer "In9.Cu")
		(net 177)
	)
	(segment
		(start 200.316025 136.621)
		(end 199.685012 135.989988)
		(width 0.09)
		(layer "In9.Cu")
		(net 177)
	)
	(segment
		(start 199.685012 133.432463)
		(end 199.352549 133.1)
		(width 0.09)
		(layer "In9.Cu")
		(net 177)
	)
	(segment
		(start 197.35 119.077)
		(end 197.717 118.71)
		(width 0.09)
		(layer "In9.Cu")
		(net 177)
	)
	(segment
		(start 203.081275 135.98)
		(end 202.67 135.98)
		(width 0.09)
		(layer "In9.Cu")
		(net 177)
	)
	(segment
		(start 193.11 132.69)
		(end 192.89 132.47)
		(width 0.09)
		(layer "In9.Cu")
		(net 177)
	)
	(segment
		(start 195.43 132.69)
		(end 193.11 132.69)
		(width 0.09)
		(layer "In9.Cu")
		(net 177)
	)
	(segment
		(start 197.35 119.6)
		(end 197.35 119.077)
		(width 0.09)
		(layer "In9.Cu")
		(net 177)
	)
	(segment
		(start 195.84 133.1)
		(end 195.43 132.69)
		(width 0.09)
		(layer "In9.Cu")
		(net 177)
	)
	(segment
		(start 204.45 136.3)
		(end 203.401275 136.3)
		(width 0.09)
		(layer "In9.Cu")
		(net 177)
	)
	(segment
		(start 202.45 136.475)
		(end 202.304 136.621)
		(width 0.09)
		(layer "In9.Cu")
		(net 177)
	)
	(segment
		(start 202.67 135.98)
		(end 202.45 136.2)
		(width 0.09)
		(layer "In9.Cu")
		(net 177)
	)
	(segment
		(start 192.89 122.55)
		(end 195.135 120.305)
		(width 0.09)
		(layer "In9.Cu")
		(net 177)
	)
	(segment
		(start 203.401275 136.3)
		(end 203.081275 135.98)
		(width 0.09)
		(layer "In9.Cu")
		(net 177)
	)
	(segment
		(start 196.645 120.305)
		(end 197.35 119.6)
		(width 0.09)
		(layer "In9.Cu")
		(net 177)
	)
	(segment
		(start 195.135 120.305)
		(end 196.645 120.305)
		(width 0.09)
		(layer "In9.Cu")
		(net 177)
	)
	(segment
		(start 202.304 136.621)
		(end 200.316025 136.621)
		(width 0.09)
		(layer "In9.Cu")
		(net 177)
	)
	(segment
		(start 202.45 136.2)
		(end 202.45 136.475)
		(width 0.09)
		(layer "In9.Cu")
		(net 177)
	)
	(segment
		(start 199.685012 135.989988)
		(end 199.685012 133.432463)
		(width 0.09)
		(layer "In9.Cu")
		(net 177)
	)
	(segment
		(start 226.888 138.707)
		(end 226.888 139.351604)
		(width 0.59)
		(layer "F.Cu")
		(net 178)
	)
	(segment
		(start 227.159839 139.93774)
		(end 227.159839 140.779839)
		(width 0.59)
		(layer "F.Cu")
		(net 178)
	)
	(segment
		(start 227.019802 139.669802)
		(end 227.028698 139.678698)
		(width 0.59)
		(layer "F.Cu")
		(net 178)
	)
	(segment
		(start 227.159839 140.779839)
		(end 227.16 140.78)
		(width 0.59)
		(layer "F.Cu")
		(net 178)
	)
	(arc
		(start 227.028698 139.678698)
		(mid 227.114094 139.797866)
		(end 227.159839 139.93774)
		(width 0.59)
		(layer "F.Cu")
		(net 178)
	)
	(arc
		(start 226.888 139.351604)
		(mid 226.922254 139.523812)
		(end 227.019802 139.669802)
		(width 0.59)
		(layer "F.Cu")
		(net 178)
	)
	(segment
		(start 214.115 146.112)
		(end 214.115 145.5)
		(width 0.174)
		(layer "F.Cu")
		(net 179)
	)
	(via
		(at 214.115 145.5)
		(size 0.35)
		(drill 0.15)
		(layers "F.Cu" "B.Cu")
		(remove_unused_layers yes)
		(keep_end_layers yes)
		(zone_layer_connections)
		(net 179)
	)
	(segment
		(start 214.299 145.5)
		(end 214.115 145.5)
		(width 0.15)
		(layer "B.Cu")
		(net 179)
	)
	(segment
		(start 214.865 146.066)
		(end 214.299 145.5)
		(width 0.15)
		(layer "B.Cu")
		(net 179)
	)
	(segment
		(start 204.8 145.335)
		(end 205.165 145.335)
		(width 0.174)
		(layer "F.Cu")
		(net 180)
	)
	(segment
		(start 207.484 142.96)
		(end 207.015 143.429)
		(width 0.201)
		(layer "F.Cu")
		(net 180)
	)
	(segment
		(start 207.015 143.429)
		(end 207.015 144.825)
		(width 0.201)
		(layer "F.Cu")
		(net 180)
	)
	(segment
		(start 207.015 144.825)
		(end 207.6 144.825)
		(width 0.201)
		(layer "F.Cu")
		(net 180)
	)
	(segment
		(start 203.815 145.335)
		(end 204.8 145.335)
		(width 0.174)
		(layer "F.Cu")
		(net 180)
	)
	(segment
		(start 204.8 145.335)
		(end 204.945 145.335)
		(width 0.174)
		(layer "F.Cu")
		(net 180)
	)
	(segment
		(start 206.505038 145.126)
		(end 205.462054 145.126)
		(width 0.1)
		(layer "F.Cu")
		(net 180)
	)
	(segment
		(start 205.165 145.335)
		(end 204.945 145.335)
		(width 0.1)
		(layer "F.Cu")
		(net 180)
	)
	(segment
		(start 206.714 145.126)
		(end 207.015 144.825)
		(width 0.201)
		(layer "F.Cu")
		(net 180)
	)
	(segment
		(start 205.374 145.126)
		(end 205.165 145.335)
		(width 0.174)
		(layer "F.Cu")
		(net 180)
	)
	(segment
		(start 203.049 146.101)
		(end 203.815 145.335)
		(width 0.174)
		(layer "F.Cu")
		(net 180)
	)
	(segment
		(start 205.462054 145.126)
		(end 205.374 145.126)
		(width 0.174)
		(layer "F.Cu")
		(net 180)
	)
	(segment
		(start 206.505038 145.126)
		(end 206.714 145.126)
		(width 0.201)
		(layer "F.Cu")
		(net 180)
	)
	(via
		(at 207.484 142.96)
		(size 0.35)
		(drill 0.15)
		(layers "F.Cu" "B.Cu")
		(remove_unused_layers yes)
		(keep_end_layers yes)
		(zone_layer_connections)
		(net 180)
	)
	(via
		(at 203.049 146.101)
		(size 0.35)
		(drill 0.15)
		(layers "F.Cu" "B.Cu")
		(remove_unused_layers yes)
		(keep_end_layers yes)
		(zone_layer_connections)
		(net 180)
	)
	(segment
		(start 203.049 146.101)
		(end 203.049 145.549)
		(width 0.201)
		(layer "B.Cu")
		(net 180)
	)
	(segment
		(start 203.049 145.549)
		(end 202.916 145.416)
		(width 0.201)
		(layer "B.Cu")
		(net 180)
	)
	(via
		(at 215.113 149.987)
		(size 0.35)
		(drill 0.15)
		(layers "F.Cu" "B.Cu")
		(remove_unused_layers yes)
		(keep_end_layers yes)
		(zone_layer_connections)
		(net 182)
	)
	(via
		(at 207.55 146.8)
		(size 0.35)
		(drill 0.15)
		(layers "F.Cu" "B.Cu")
		(remove_unused_layers yes)
		(keep_end_layers yes)
		(zone_layer_connections)
		(net 183)
	)
	(via
		(at 204.349 146.751)
		(size 0.35)
		(drill 0.15)
		(layers "F.Cu" "B.Cu")
		(remove_unused_layers yes)
		(keep_end_layers yes)
		(zone_layer_connections)
		(net 183)
	)
	(segment
		(start 204.633 146.751)
		(end 205 146.384)
		(width 0.201)
		(layer "B.Cu")
		(net 183)
	)
	(segment
		(start 206.66 146.426)
		(end 207.567 146.426)
		(width 0.256)
		(layer "B.Cu")
		(net 183)
	)
	(segment
		(start 205.404071 146.426)
		(end 206.66 146.426)
		(width 0.1)
		(layer "B.Cu")
		(net 183)
	)
	(segment
		(start 205.042 146.426)
		(end 205 146.384)
		(width 0.256)
		(layer "B.Cu")
		(net 183)
	)
	(segment
		(start 204.349 146.751)
		(end 204.633 146.751)
		(width 0.201)
		(layer "B.Cu")
		(net 183)
	)
	(segment
		(start 207.616 146.475)
		(end 207.567 146.426)
		(width 0.1)
		(layer "B.Cu")
		(net 183)
	)
	(segment
		(start 205.404071 146.426)
		(end 205.042 146.426)
		(width 0.256)
		(layer "B.Cu")
		(net 183)
	)
	(segment
		(start 204.349 146.101)
		(end 204.56 145.89)
		(width 0.256)
		(layer "F.Cu")
		(net 185)
	)
	(segment
		(start 205.4 145.776)
		(end 206.52 145.776)
		(width 0.1)
		(layer "F.Cu")
		(net 185)
	)
	(segment
		(start 204.674 145.776)
		(end 205.4 145.776)
		(width 0.256)
		(layer "F.Cu")
		(net 185)
	)
	(segment
		(start 207.58 145.78)
		(end 206.524 145.78)
		(width 0.201)
		(layer "F.Cu")
		(net 185)
	)
	(segment
		(start 207.6 145.8)
		(end 207.58 145.78)
		(width 0.201)
		(layer "F.Cu")
		(net 185)
	)
	(segment
		(start 206.524 145.78)
		(end 206.52 145.776)
		(width 0.201)
		(layer "F.Cu")
		(net 185)
	)
	(segment
		(start 204.56 145.89)
		(end 204.674 145.776)
		(width 0.256)
		(layer "F.Cu")
		(net 185)
	)
	(segment
		(start 203.699 146.751)
		(end 204.349 146.101)
		(width 0.256)
		(layer "F.Cu")
		(net 185)
	)
	(via
		(at 207.55 145.8)
		(size 0.35)
		(drill 0.15)
		(layers "F.Cu" "B.Cu")
		(remove_unused_layers yes)
		(keep_end_layers yes)
		(zone_layer_connections)
		(net 185)
	)
	(segment
		(start 207.626 144.54)
		(end 207.626 145.494)
		(width 0.198)
		(layer "B.Cu")
		(net 185)
	)
	(segment
		(start 207.626 145.494)
		(end 207.632 145.5)
		(width 0.198)
		(layer "B.Cu")
		(net 185)
	)
	(segment
		(start 220.0995 129.3495)
		(end 220.0995 129.16)
		(width 0.256)
		(layer "B.Cu")
		(net 186)
	)
	(segment
		(start 220.425 132.775)
		(end 220.825 132.775)
		(width 0.256)
		(layer "B.Cu")
		(net 186)
	)
	(segment
		(start 221.35 133.275)
		(end 222.35 133.275)
		(width 0.256)
		(layer "B.Cu")
		(net 186)
	)
	(segment
		(start 221.35 133.275)
		(end 220.85 132.775)
		(width 0.256)
		(layer "B.Cu")
		(net 186)
	)
	(segment
		(start 220.1 132.25)
		(end 220.1 132.45)
		(width 0.256)
		(layer "B.Cu")
		(net 186)
	)
	(segment
		(start 220.1 132.45)
		(end 220.425 132.775)
		(width 0.256)
		(layer "B.Cu")
		(net 186)
	)
	(segment
		(start 220.825 130.075)
		(end 220.0995 129.3495)
		(width 0.256)
		(layer "B.Cu")
		(net 186)
	)
	(segment
		(start 220.825 132.775)
		(end 220.825 130.075)
		(width 0.256)
		(layer "B.Cu")
		(net 186)
	)
	(segment
		(start 220.85 132.775)
		(end 220.825 132.775)
		(width 0.256)
		(layer "B.Cu")
		(net 186)
	)
	(via
		(at 177.57 144.32)
		(size 0.35)
		(drill 0.15)
		(layers "F.Cu" "B.Cu")
		(remove_unused_layers yes)
		(keep_end_layers yes)
		(zone_layer_connections)
		(net 187)
	)
	(via
		(at 181.64 120.53)
		(size 0.35)
		(drill 0.15)
		(layers "F.Cu" "B.Cu")
		(remove_unused_layers yes)
		(keep_end_layers yes)
		(zone_layer_connections)
		(net 187)
	)
	(via
		(at 182.858904 147.831531)
		(size 0.35)
		(drill 0.15)
		(layers "F.Cu" "B.Cu")
		(remove_unused_layers yes)
		(keep_end_layers yes)
		(zone_layer_connections)
		(net 187)
	)
	(via
		(at 179.1 140.45)
		(size 0.35)
		(drill 0.15)
		(layers "F.Cu" "B.Cu")
		(remove_unused_layers yes)
		(keep_end_layers yes)
		(zone_layer_connections)
		(net 187)
	)
	(segment
		(start 182.44 121.33)
		(end 184.75 121.33)
		(width 0.1)
		(layer "B.Cu")
		(net 187)
	)
	(segment
		(start 181.64 120.53)
		(end 182.44 121.33)
		(width 0.1)
		(layer "B.Cu")
		(net 187)
	)
	(segment
		(start 180.99 146.2)
		(end 181.65 146.2)
		(width 0.09)
		(layer "In6.Cu")
		(net 187)
	)
	(segment
		(start 181.65 146.2)
		(end 182.858904 147.408904)
		(width 0.09)
		(layer "In6.Cu")
		(net 187)
	)
	(segment
		(start 179.28 144.49)
		(end 180.99 146.2)
		(width 0.09)
		(layer "In6.Cu")
		(net 187)
	)
	(segment
		(start 177.57 144.32)
		(end 177.74 144.49)
		(width 0.09)
		(layer "In6.Cu")
		(net 187)
	)
	(segment
		(start 177.74 144.49)
		(end 179.28 144.49)
		(width 0.09)
		(layer "In6.Cu")
		(net 187)
	)
	(segment
		(start 182.858904 147.408904)
		(end 182.858904 147.831531)
		(width 0.09)
		(layer "In6.Cu")
		(net 187)
	)
	(segment
		(start 179.1 138.96)
		(end 178.818398 138.678398)
		(width 0.1)
		(layer "In9.Cu")
		(net 187)
	)
	(segment
		(start 177.15 141.19)
		(end 177.89 140.45)
		(width 0.09)
		(layer "In9.Cu")
		(net 187)
	)
	(segment
		(start 178.818398 138.678398)
		(end 178.818398 137.608398)
		(width 0.1)
		(layer "In9.Cu")
		(net 187)
	)
	(segment
		(start 177.57 144.32)
		(end 177.15 143.9)
		(width 0.09)
		(layer "In9.Cu")
		(net 187)
	)
	(segment
		(start 178.818398 137.608398)
		(end 179.066796 137.36)
		(width 0.1)
		(layer "In9.Cu")
		(net 187)
	)
	(segment
		(start 185.3 136.25)
		(end 185.3 123.45)
		(width 0.1)
		(layer "In9.Cu")
		(net 187)
	)
	(segment
		(start 179.1 140.45)
		(end 179.1 138.96)
		(width 0.1)
		(layer "In9.Cu")
		(net 187)
	)
	(segment
		(start 184.19 137.36)
		(end 185.3 136.25)
		(width 0.1)
		(layer "In9.Cu")
		(net 187)
	)
	(segment
		(start 182.38 120.53)
		(end 181.64 120.53)
		(width 0.1)
		(layer "In9.Cu")
		(net 187)
	)
	(segment
		(start 179.066796 137.36)
		(end 184.19 137.36)
		(width 0.1)
		(layer "In9.Cu")
		(net 187)
	)
	(segment
		(start 185.3 123.45)
		(end 182.38 120.53)
		(width 0.1)
		(layer "In9.Cu")
		(net 187)
	)
	(segment
		(start 177.89 140.45)
		(end 179.1 140.45)
		(width 0.09)
		(layer "In9.Cu")
		(net 187)
	)
	(segment
		(start 177.15 143.9)
		(end 177.15 141.19)
		(width 0.09)
		(layer "In9.Cu")
		(net 187)
	)
	(segment
		(start 219.0995 129.16)
		(end 219.0995 128.3805)
		(width 0.256)
		(layer "B.Cu")
		(net 188)
	)
	(segment
		(start 219.0995 130.639)
		(end 219.0995 129.16)
		(width 0.256)
		(layer "B.Cu")
		(net 188)
	)
	(segment
		(start 219.0995 128.3805)
		(end 219.43 128.05)
		(width 0.256)
		(layer "B.Cu")
		(net 188)
	)
	(segment
		(start 184.05 121.45)
		(end 184.57 121.45)
		(width 0.1)
		(layer "F.Cu")
		(net 189)
	)
	(segment
		(start 183.58 121.45)
		(end 184.05 121.45)
		(width 0.1)
		(layer "F.Cu")
		(net 189)
	)
	(segment
		(start 183.35 120.4)
		(end 184.05 121.1)
		(width 0.1)
		(layer "F.Cu")
		(net 189)
	)
	(segment
		(start 184.05 121.1)
		(end 184.05 121.45)
		(width 0.1)
		(layer "F.Cu")
		(net 189)
	)
	(via
		(at 202.9 129.901)
		(size 0.35)
		(drill 0.15)
		(layers "F.Cu" "B.Cu")
		(remove_unused_layers yes)
		(keep_end_layers yes)
		(zone_layer_connections)
		(net 189)
	)
	(via
		(at 183.35 120.4)
		(size 0.35)
		(drill 0.15)
		(layers "F.Cu" "B.Cu")
		(remove_unused_layers yes)
		(keep_end_layers yes)
		(zone_layer_connections)
		(net 189)
	)
	(segment
		(start 204.445 125.225)
		(end 203.225 126.445)
		(width 0.1)
		(layer "In11.Cu")
		(net 189)
	)
	(segment
		(start 204.98462 125.225)
		(end 204.445 125.225)
		(width 0.1)
		(layer "In11.Cu")
		(net 189)
	)
	(segment
		(start 199.224 124.476)
		(end 199 124.7)
		(width 0.1)
		(layer "In11.Cu")
		(net 189)
	)
	(segment
		(start 200.65862 127.95)
		(end 200.975 127.63362)
		(width 0.1)
		(layer "In11.Cu")
		(net 189)
	)
	(segment
		(start 199 124.7)
		(end 198.76063 124.7)
		(width 0.1)
		(layer "In11.Cu")
		(net 189)
	)
	(segment
		(start 205.7 124.50962)
		(end 204.98462 125.225)
		(width 0.1)
		(layer "In11.Cu")
		(net 189)
	)
	(segment
		(start 199.029478 125.586)
		(end 199.25 125.806522)
		(width 0.1)
		(layer "In11.Cu")
		(net 189)
	)
	(segment
		(start 199.425 127.95)
		(end 200.65862 127.95)
		(width 0.1)
		(layer "In11.Cu")
		(net 189)
	)
	(segment
		(start 184 121.05)
		(end 187.25 121.05)
		(width 0.1)
		(layer "In11.Cu")
		(net 189)
	)
	(segment
		(start 198.84663 125.586)
		(end 199.029478 125.586)
		(width 0.1)
		(layer "In11.Cu")
		(net 189)
	)
	(segment
		(start 205.3 123.4)
		(end 205.7 123.8)
		(width 0.1)
		(layer "In11.Cu")
		(net 189)
	)
	(segment
		(start 205.7 123.8)
		(end 205.7 124.50962)
		(width 0.1)
		(layer "In11.Cu")
		(net 189)
	)
	(segment
		(start 200.975 125.76638)
		(end 201.16538 125.576)
		(width 0.1)
		(layer "In11.Cu")
		(net 189)
	)
	(segment
		(start 199.224 124.124)
		(end 199.224 124.476)
		(width 0.1)
		(layer "In11.Cu")
		(net 189)
	)
	(segment
		(start 201.625 125.275)
		(end 201.625 124.31538)
		(width 0.1)
		(layer "In11.Cu")
		(net 189)
	)
	(segment
		(start 202.54038 123.4)
		(end 205.3 123.4)
		(width 0.1)
		(layer "In11.Cu")
		(net 189)
	)
	(segment
		(start 199.25 125.806522)
		(end 199.25 127.775)
		(width 0.1)
		(layer "In11.Cu")
		(net 189)
	)
	(segment
		(start 201.16538 125.576)
		(end 201.324 125.576)
		(width 0.1)
		(layer "In11.Cu")
		(net 189)
	)
	(segment
		(start 198.76063 124.7)
		(end 198.574 124.88663)
		(width 0.1)
		(layer "In11.Cu")
		(net 189)
	)
	(segment
		(start 201.324 125.576)
		(end 201.625 125.275)
		(width 0.1)
		(layer "In11.Cu")
		(net 189)
	)
	(segment
		(start 183.35 120.4)
		(end 184 121.05)
		(width 0.1)
		(layer "In11.Cu")
		(net 189)
	)
	(segment
		(start 200.975 127.63362)
		(end 200.975 125.76638)
		(width 0.1)
		(layer "In11.Cu")
		(net 189)
	)
	(segment
		(start 201.625 124.31538)
		(end 202.54038 123.4)
		(width 0.1)
		(layer "In11.Cu")
		(net 189)
	)
	(segment
		(start 203.225 126.445)
		(end 203.225 129.275)
		(width 0.1)
		(layer "In11.Cu")
		(net 189)
	)
	(segment
		(start 198.574 125.31337)
		(end 198.84663 125.586)
		(width 0.1)
		(layer "In11.Cu")
		(net 189)
	)
	(segment
		(start 187.25 121.05)
		(end 189.15 122.95)
		(width 0.1)
		(layer "In11.Cu")
		(net 189)
	)
	(segment
		(start 189.15 122.95)
		(end 198.05 122.95)
		(width 0.1)
		(layer "In11.Cu")
		(net 189)
	)
	(segment
		(start 199.25 127.775)
		(end 199.425 127.95)
		(width 0.1)
		(layer "In11.Cu")
		(net 189)
	)
	(segment
		(start 202.9 129.6)
		(end 202.9 129.901)
		(width 0.1)
		(layer "In11.Cu")
		(net 189)
	)
	(segment
		(start 203.225 129.275)
		(end 202.9 129.6)
		(width 0.1)
		(layer "In11.Cu")
		(net 189)
	)
	(segment
		(start 198.574 124.88663)
		(end 198.574 125.31337)
		(width 0.1)
		(layer "In11.Cu")
		(net 189)
	)
	(segment
		(start 198.05 122.95)
		(end 199.224 124.124)
		(width 0.1)
		(layer "In11.Cu")
		(net 189)
	)
	(segment
		(start 212.342748 147.622751)
		(end 212.5 147.622751)
		(width 0.09)
		(layer "F.Cu")
		(net 190)
	)
	(segment
		(start 212.927 147.8)
		(end 212.677249 147.8)
		(width 0.09)
		(layer "F.Cu")
		(net 190)
	)
	(segment
		(start 212.677249 147.8)
		(end 212.5 147.622751)
		(width 0.09)
		(layer "F.Cu")
		(net 190)
	)
	(segment
		(start 212.205499 147.76)
		(end 212.342748 147.622751)
		(width 0.09)
		(layer "F.Cu")
		(net 190)
	)
	(via
		(at 212.205499 147.76)
		(size 0.35)
		(drill 0.15)
		(layers "F.Cu" "B.Cu")
		(remove_unused_layers yes)
		(keep_end_layers yes)
		(zone_layer_connections)
		(net 190)
	)
	(via
		(at 221.767499 146.245)
		(size 0.35)
		(drill 0.15)
		(layers "F.Cu" "B.Cu")
		(remove_unused_layers yes)
		(keep_end_layers yes)
		(zone_layer_connections)
		(net 190)
	)
	(segment
		(start 221.6125 146.399999)
		(end 221.6125 146.776852)
		(width 0.09)
		(layer "In4.Cu")
		(net 190)
	)
	(segment
		(start 215.760648 149.995)
		(end 214.215 148.449352)
		(width 0.09)
		(layer "In4.Cu")
		(net 190)
	)
	(segment
		(start 214.215 147.899352)
		(end 213.943399 147.627751)
		(width 0.09)
		(layer "In4.Cu")
		(net 190)
	)
	(segment
		(start 221.6125 146.776852)
		(end 220.425 147.964352)
		(width 0.09)
		(layer "In4.Cu")
		(net 190)
	)
	(segment
		(start 219.524352 149.995)
		(end 215.760648 149.995)
		(width 0.09)
		(layer "In4.Cu")
		(net 190)
	)
	(segment
		(start 220.425 149.094352)
		(end 219.524352 149.995)
		(width 0.09)
		(layer "In4.Cu")
		(net 190)
	)
	(segment
		(start 213.943399 147.627751)
		(end 212.337748 147.627751)
		(width 0.09)
		(layer "In4.Cu")
		(net 190)
	)
	(segment
		(start 214.215 148.449352)
		(end 214.215 147.899352)
		(width 0.09)
		(layer "In4.Cu")
		(net 190)
	)
	(segment
		(start 221.767499 146.245)
		(end 221.6125 146.399999)
		(width 0.09)
		(layer "In4.Cu")
		(net 190)
	)
	(segment
		(start 220.425 147.964352)
		(end 220.425 149.094352)
		(width 0.09)
		(layer "In4.Cu")
		(net 190)
	)
	(segment
		(start 212.337748 147.627751)
		(end 212.205499 147.76)
		(width 0.09)
		(layer "In4.Cu")
		(net 190)
	)
	(segment
		(start 203.049 146.751)
		(end 202.399 146.751)
		(width 0.201)
		(layer "F.Cu")
		(net 191)
	)
	(segment
		(start 207.6 143.85)
		(end 207.575 143.825)
		(width 0.1)
		(layer "F.Cu")
		(net 191)
	)
	(via
		(at 207.55 143.85)
		(size 0.35)
		(drill 0.15)
		(layers "F.Cu" "B.Cu")
		(remove_unused_layers yes)
		(keep_end_layers yes)
		(zone_layer_connections)
		(net 191)
	)
	(via
		(at 202.399 146.751)
		(size 0.35)
		(drill 0.15)
		(layers "F.Cu" "B.Cu")
		(remove_unused_layers yes)
		(keep_end_layers yes)
		(zone_layer_connections)
		(net 191)
	)
	(segment
		(start 201.425 143.96)
		(end 201.425 144.4)
		(width 0.1)
		(layer "B.Cu")
		(net 191)
	)
	(segment
		(start 201.35 144.475)
		(end 200.96538 144.475)
		(width 0.1)
		(layer "B.Cu")
		(net 191)
	)
	(segment
		(start 200.96438 145.776)
		(end 201.23362 145.776)
		(width 0.1)
		(layer "B.Cu")
		(net 191)
	)
	(segment
		(start 201.425 143.685)
		(end 201.425 143.873962)
		(width 0.201)
		(layer "B.Cu")
		(net 191)
	)
	(segment
		(start 200.96538 144.475)
		(end 200.774 144.66638)
		(width 0.1)
		(layer "B.Cu")
		(net 191)
	)
	(segment
		(start 201.425 144.4)
		(end 201.35 144.475)
		(width 0.1)
		(layer "B.Cu")
		(net 191)
	)
	(segment
		(start 202.399 146.751)
		(end 202.117 146.751)
		(width 0.256)
		(layer "B.Cu")
		(net 191)
	)
	(segment
		(start 201.23362 145.776)
		(end 201.75 146.29238)
		(width 0.1)
		(layer "B.Cu")
		(net 191)
	)
	(segment
		(start 200.774 145.58562)
		(end 200.96438 145.776)
		(width 0.1)
		(layer "B.Cu")
		(net 191)
	)
	(segment
		(start 207.626 143.58)
		(end 201.53 143.58)
		(width 0.201)
		(layer "B.Cu")
		(net 191)
	)
	(segment
		(start 201.75 146.29238)
		(end 201.75 146.384)
		(width 0.1)
		(layer "B.Cu")
		(net 191)
	)
	(segment
		(start 201.53 143.58)
		(end 201.425 143.685)
		(width 0.201)
		(layer "B.Cu")
		(net 191)
	)
	(segment
		(start 202.117 146.751)
		(end 201.75 146.384)
		(width 0.256)
		(layer "B.Cu")
		(net 191)
	)
	(segment
		(start 200.774 144.66638)
		(end 200.774 145.58562)
		(width 0.1)
		(layer "B.Cu")
		(net 191)
	)
	(segment
		(start 184.05 120.4)
		(end 184.48 120.4)
		(width 0.1)
		(layer "F.Cu")
		(net 192)
	)
	(segment
		(start 219.78 143.5885)
		(end 219.8265 143.542)
		(width 0.1)
		(layer "F.Cu")
		(net 192)
	)
	(segment
		(start 184.48 120.4)
		(end 185.53 121.45)
		(width 0.1)
		(layer "F.Cu")
		(net 192)
	)
	(segment
		(start 219.78 143.71)
		(end 219.78 143.5885)
		(width 0.1)
		(layer "F.Cu")
		(net 192)
	)
	(via
		(at 219.78 143.71)
		(size 0.35)
		(drill 0.15)
		(layers "F.Cu" "B.Cu")
		(remove_unused_layers yes)
		(keep_end_layers yes)
		(zone_layer_connections)
		(net 192)
	)
	(via
		(at 184.05 120.4)
		(size 0.35)
		(drill 0.15)
		(layers "F.Cu" "B.Cu")
		(remove_unused_layers yes)
		(keep_end_layers yes)
		(zone_layer_connections)
		(net 192)
	)
	(segment
		(start 219.34 143.27)
		(end 219.78 143.71)
		(width 0.1)
		(layer "In11.Cu")
		(net 192)
	)
	(segment
		(start 219.18 137.9)
		(end 217.99 139.09)
		(width 0.1)
		(layer "In11.Cu")
		(net 192)
	)
	(segment
		(start 210.968594 117.618594)
		(end 211.5 118.15)
		(width 0.1)
		(layer "In11.Cu")
		(net 192)
	)
	(segment
		(start 206.631406 117.618594)
		(end 210.968594 117.618594)
		(width 0.1)
		(layer "In11.Cu")
		(net 192)
	)
	(segment
		(start 196.815794 117.776)
		(end 197.084206 117.776)
		(width 0.1)
		(layer "In11.Cu")
		(net 192)
	)
	(segment
		(start 196.791794 117.8)
		(end 196.815794 117.776)
		(width 0.1)
		(layer "In11.Cu")
		(net 192)
	)
	(segment
		(start 190.06 117.8)
		(end 196.791794 117.8)
		(width 0.1)
		(layer "In11.Cu")
		(net 192)
	)
	(segment
		(start 218.61 143.27)
		(end 219.34 143.27)
		(width 0.1)
		(layer "In11.Cu")
		(net 192)
	)
	(segment
		(start 217.99 139.09)
		(end 217.99 142.65)
		(width 0.1)
		(layer "In11.Cu")
		(net 192)
	)
	(segment
		(start 213.5 118.15)
		(end 214.221 117.429)
		(width 0.1)
		(layer "In11.Cu")
		(net 192)
	)
	(segment
		(start 217.99 142.65)
		(end 218.61 143.27)
		(width 0.1)
		(layer "In11.Cu")
		(net 192)
	)
	(segment
		(start 184.05 120.4)
		(end 187.46 120.4)
		(width 0.1)
		(layer "In11.Cu")
		(net 192)
	)
	(segment
		(start 219.6 127.6)
		(end 219.18 128.02)
		(width 0.1)
		(layer "In11.Cu")
		(net 192)
	)
	(segment
		(start 197.084206 117.776)
		(end 197.108206 117.8)
		(width 0.1)
		(layer "In11.Cu")
		(net 192)
	)
	(segment
		(start 219.18 128.02)
		(end 219.18 137.9)
		(width 0.1)
		(layer "In11.Cu")
		(net 192)
	)
	(segment
		(start 211.5 118.15)
		(end 213.5 118.15)
		(width 0.1)
		(layer "In11.Cu")
		(net 192)
	)
	(segment
		(start 187.46 120.4)
		(end 190.06 117.8)
		(width 0.1)
		(layer "In11.Cu")
		(net 192)
	)
	(segment
		(start 219.6 117.6)
		(end 219.6 127.6)
		(width 0.1)
		(layer "In11.Cu")
		(net 192)
	)
	(segment
		(start 218.101 117.429)
		(end 218.151 117.379)
		(width 0.1)
		(layer "In11.Cu")
		(net 192)
	)
	(segment
		(start 218.151 117.379)
		(end 219.379 117.379)
		(width 0.1)
		(layer "In11.Cu")
		(net 192)
	)
	(segment
		(start 206.45 117.8)
		(end 206.631406 117.618594)
		(width 0.1)
		(layer "In11.Cu")
		(net 192)
	)
	(segment
		(start 219.379 117.379)
		(end 219.6 117.6)
		(width 0.1)
		(layer "In11.Cu")
		(net 192)
	)
	(segment
		(start 214.221 117.429)
		(end 218.101 117.429)
		(width 0.1)
		(layer "In11.Cu")
		(net 192)
	)
	(segment
		(start 197.108206 117.8)
		(end 206.45 117.8)
		(width 0.1)
		(layer "In11.Cu")
		(net 192)
	)
	(via
		(at 224.44 147.31)
		(size 0.35)
		(drill 0.15)
		(layers "F.Cu" "B.Cu")
		(remove_unused_layers yes)
		(keep_end_layers yes)
		(zone_layer_connections)
		(net 193)
	)
	(via
		(at 222.94 145.94)
		(size 0.35)
		(drill 0.15)
		(layers "F.Cu" "B.Cu")
		(remove_unused_layers yes)
		(keep_end_layers yes)
		(zone_layer_connections)
		(net 193)
	)
	(segment
		(start 224.44 147.31)
		(end 225.04 147.31)
		(width 0.09)
		(layer "B.Cu")
		(net 193)
	)
	(segment
		(start 223.06 145.82)
		(end 222.94 145.94)
		(width 0.09)
		(layer "B.Cu")
		(net 193)
	)
	(segment
		(start 225.04 147.31)
		(end 225.075 147.345)
		(width 0.09)
		(layer "B.Cu")
		(net 193)
	)
	(segment
		(start 223.06 145.46)
		(end 223.06 145.82)
		(width 0.09)
		(layer "B.Cu")
		(net 193)
	)
	(segment
		(start 222.94 145.94)
		(end 223.07 145.94)
		(width 0.09)
		(layer "In11.Cu")
		(net 193)
	)
	(segment
		(start 223.07 145.94)
		(end 224.44 147.31)
		(width 0.09)
		(layer "In11.Cu")
		(net 193)
	)
	(segment
		(start 223.96 145.46)
		(end 223.660001 145.46)
		(width 0.09)
		(layer "B.Cu")
		(net 194)
	)
	(segment
		(start 224.275 146.385)
		(end 224.72 146.83)
		(width 0.09)
		(layer "B.Cu")
		(net 194)
	)
	(segment
		(start 223.31 146.081135)
		(end 223.613865 146.385)
		(width 0.09)
		(layer "B.Cu")
		(net 194)
	)
	(segment
		(start 224.72 146.83)
		(end 225.565 146.83)
		(width 0.09)
		(layer "B.Cu")
		(net 194)
	)
	(segment
		(start 223.660001 145.46)
		(end 223.31 145.810001)
		(width 0.09)
		(layer "B.Cu")
		(net 194)
	)
	(segment
		(start 225.565 146.83)
		(end 226.075 147.34)
		(width 0.09)
		(layer "B.Cu")
		(net 194)
	)
	(segment
		(start 223.613865 146.385)
		(end 224.275 146.385)
		(width 0.09)
		(layer "B.Cu")
		(net 194)
	)
	(segment
		(start 223.31 145.810001)
		(end 223.31 146.081135)
		(width 0.09)
		(layer "B.Cu")
		(net 194)
	)
	(via
		(at 204.999 149.351)
		(size 0.35)
		(drill 0.15)
		(layers "F.Cu" "B.Cu")
		(remove_unused_layers yes)
		(keep_end_layers yes)
		(zone_layer_connections)
		(net 195)
	)
	(via
		(at 191.544436 150.705564)
		(size 0.35)
		(drill 0.15)
		(layers "F.Cu" "B.Cu")
		(remove_unused_layers yes)
		(keep_end_layers yes)
		(zone_layer_connections)
		(net 195)
	)
	(segment
		(start 191.722 151.461)
		(end 191.722 151.246)
		(width 0.11)
		(layer "B.Cu")
		(net 195)
	)
	(segment
		(start 191.822 150.80317)
		(end 191.724394 150.705564)
		(width 0.11)
		(layer "B.Cu")
		(net 195)
	)
	(segment
		(start 191.722 151.246)
		(end 191.822 151.146)
		(width 0.11)
		(layer "B.Cu")
		(net 195)
	)
	(segment
		(start 191.724394 150.705564)
		(end 191.544436 150.705564)
		(width 0.11)
		(layer "B.Cu")
		(net 195)
	)
	(segment
		(start 191.822 151.146)
		(end 191.822 150.80317)
		(width 0.11)
		(layer "B.Cu")
		(net 195)
	)
	(segment
		(start 205.416004 150.565)
		(end 201.619352 150.565)
		(width 0.09)
		(layer "In9.Cu")
		(net 195)
	)
	(segment
		(start 192.210649 151.195)
		(end 198.659652 151.195)
		(width 0.09)
		(layer "In9.Cu")
		(net 195)
	)
	(segment
		(start 205.524355 149.581)
		(end 205.740844 149.797489)
		(width 0.09)
		(layer "In9.Cu")
		(net 195)
	)
	(segment
		(start 205.740844 150.24016)
		(end 205.416004 150.565)
		(width 0.09)
		(layer "In9.Cu")
		(net 195)
	)
	(segment
		(start 199.509652 152.100349)
		(end 199.47 152.100349)
		(width 0.09)
		(layer "In9.Cu")
		(net 195)
	)
	(segment
		(start 205.229 149.581)
		(end 205.524355 149.581)
		(width 0.09)
		(layer "In9.Cu")
		(net 195)
	)
	(segment
		(start 205.740844 149.797489)
		(end 205.740844 150.24016)
		(width 0.09)
		(layer "In9.Cu")
		(net 195)
	)
	(segment
		(start 200.989352 151.195)
		(end 200.32 151.195)
		(width 0.09)
		(layer "In9.Cu")
		(net 195)
	)
	(segment
		(start 192.210649 151.195)
		(end 191.721213 150.705564)
		(width 0.09)
		(layer "In9.Cu")
		(net 195)
	)
	(segment
		(start 201.619352 150.565)
		(end 200.989352 151.195)
		(width 0.09)
		(layer "In9.Cu")
		(net 195)
	)
	(segment
		(start 191.721213 150.705564)
		(end 191.544436 150.705564)
		(width 0.09)
		(layer "In9.Cu")
		(net 195)
	)
	(segment
		(start 204.999 149.351)
		(end 205.229 149.581)
		(width 0.09)
		(layer "In9.Cu")
		(net 195)
	)
	(segment
		(start 198.969826 151.600175)
		(end 198.969826 151.505174)
		(width 0.09)
		(layer "In9.Cu")
		(net 195)
	)
	(segment
		(start 200.009826 151.505174)
		(end 200.009826 151.600175)
		(width 0.09)
		(layer "In9.Cu")
		(net 195)
	)
	(arc
		(start 198.969826 151.505174)
		(mid 198.878978 151.285848)
		(end 198.659652 151.195)
		(width 0.09)
		(layer "In9.Cu")
		(net 195)
	)
	(arc
		(start 200.32 151.195)
		(mid 200.100674 151.285848)
		(end 200.009826 151.505174)
		(width 0.09)
		(layer "In9.Cu")
		(net 195)
	)
	(arc
		(start 200.009826 151.600175)
		(mid 199.863328 151.953851)
		(end 199.509652 152.100349)
		(width 0.09)
		(layer "In9.Cu")
		(net 195)
	)
	(arc
		(start 199.47 152.100349)
		(mid 199.116324 151.953851)
		(end 198.969826 151.600175)
		(width 0.09)
		(layer "In9.Cu")
		(net 195)
	)
	(segment
		(start 192.827782 148.827782)
		(end 191.950541 149.705023)
		(width 0.1)
		(layer "F.Cu")
		(net 196)
	)
	(segment
		(start 192.99 148.4)
		(end 192.99 148.626778)
		(width 0.12)
		(layer "F.Cu")
		(net 196)
	)
	(segment
		(start 192.827782 148.772218)
		(end 192.827782 148.827782)
		(width 0.1)
		(layer "F.Cu")
		(net 196)
	)
	(segment
		(start 191.950541 149.705023)
		(end 191.426784 149.705023)
		(width 0.1)
		(layer "F.Cu")
		(net 196)
	)
	(segment
		(start 191.426784 149.705023)
		(end 191.309534 149.822273)
		(width 0.1)
		(layer "F.Cu")
		(net 196)
	)
	(segment
		(start 192.99 148.4)
		(end 192.99 148.61)
		(width 0.1)
		(layer "F.Cu")
		(net 196)
	)
	(segment
		(start 192.99 148.61)
		(end 192.827782 148.772218)
		(width 0.1)
		(layer "F.Cu")
		(net 196)
	)
	(via
		(at 191.672 154.9)
		(size 0.35)
		(drill 0.15)
		(layers "F.Cu" "B.Cu")
		(remove_unused_layers yes)
		(keep_end_layers yes)
		(zone_layer_connections)
		(net 196)
	)
	(via
		(at 191.309534 149.822273)
		(size 0.35)
		(drill 0.15)
		(layers "F.Cu" "B.Cu")
		(remove_unused_layers yes)
		(keep_end_layers yes)
		(zone_layer_connections)
		(net 196)
	)
	(segment
		(start 191.812 154.76)
		(end 191.672 154.9)
		(width 0.1)
		(layer "B.Cu")
		(net 196)
	)
	(segment
		(start 191.722 154.386)
		(end 191.812 154.476)
		(width 0.1)
		(layer "B.Cu")
		(net 196)
	)
	(segment
		(start 191.812 154.476)
		(end 191.812 154.76)
		(width 0.1)
		(layer "B.Cu")
		(net 196)
	)
	(segment
		(start 191.722 154.171)
		(end 191.722 154.386)
		(width 0.1)
		(layer "B.Cu")
		(net 196)
	)
	(segment
		(start 192.02 149.409706)
		(end 191.714683 149.715023)
		(width 0.09)
		(layer "In2.Cu")
		(net 196)
	)
	(segment
		(start 190.703828 151.42)
		(end 190.32 151.036172)
		(width 0.09)
		(layer "In2.Cu")
		(net 196)
	)
	(segment
		(start 191.672 154.9)
		(end 191.802 154.77)
		(width 0.09)
		(layer "In2.Cu")
		(net 196)
	)
	(segment
		(start 190.32 148.750294)
		(end 190.859446 148.210848)
		(width 0.09)
		(layer "In2.Cu")
		(net 196)
	)
	(segment
		(start 191.802 152.131706)
		(end 191.090294 151.42)
		(width 0.09)
		(layer "In2.Cu")
		(net 196)
	)
	(segment
		(start 191.090294 151.42)
		(end 190.703828 151.42)
		(width 0.09)
		(layer "In2.Cu")
		(net 196)
	)
	(segment
		(start 191.714683 149.715023)
		(end 191.416784 149.715023)
		(width 0.09)
		(layer "In2.Cu")
		(net 196)
	)
	(segment
		(start 190.859446 148.210848)
		(end 191.630554 148.210848)
		(width 0.09)
		(layer "In2.Cu")
		(net 196)
	)
	(segment
		(start 191.802 154.77)
		(end 191.802 152.131706)
		(width 0.09)
		(layer "In2.Cu")
		(net 196)
	)
	(segment
		(start 191.630554 148.210848)
		(end 192.02 148.600294)
		(width 0.09)
		(layer "In2.Cu")
		(net 196)
	)
	(segment
		(start 192.02 148.600294)
		(end 192.02 149.409706)
		(width 0.09)
		(layer "In2.Cu")
		(net 196)
	)
	(segment
		(start 191.416784 149.715023)
		(end 191.309534 149.822273)
		(width 0.09)
		(layer "In2.Cu")
		(net 196)
	)
	(segment
		(start 190.32 151.036172)
		(end 190.32 148.750294)
		(width 0.09)
		(layer "In2.Cu")
		(net 196)
	)
	(segment
		(start 205.025 152.058578)
		(end 205.025 153.933578)
		(width 0.11)
		(layer "F.Cu")
		(net 197)
	)
	(segment
		(start 192.341422 154.175)
		(end 203.56 154.175)
		(width 0.11)
		(layer "F.Cu")
		(net 197)
	)
	(segment
		(start 206.299 150.001)
		(end 206.299 150.784578)
		(width 0.11)
		(layer "F.Cu")
		(net 197)
	)
	(segment
		(start 192.341422 154.175)
		(end 192.075 153.908578)
		(width 0.11)
		(layer "F.Cu")
		(net 197)
	)
	(segment
		(start 205.025 153.933578)
		(end 204.783578 154.175)
		(width 0.11)
		(layer "F.Cu")
		(net 197)
	)
	(segment
		(start 192.075 153.908578)
		(end 192.075 153.333578)
		(width 0.11)
		(layer "F.Cu")
		(net 197)
	)
	(segment
		(start 204.085 154)
		(end 204.085 153.45227)
		(width 0.11)
		(layer "F.Cu")
		(net 197)
	)
	(segment
		(start 191.669672 152.92825)
		(end 191.44475 152.92825)
		(width 0.11)
		(layer "F.Cu")
		(net 197)
	)
	(segment
		(start 204.783578 154.175)
		(end 204.26 154.175)
		(width 0.11)
		(layer "F.Cu")
		(net 197)
	)
	(segment
		(start 191.44475 152.92825)
		(end 191.3175 152.801)
		(width 0.11)
		(layer "F.Cu")
		(net 197)
	)
	(segment
		(start 203.735 153.45227)
		(end 203.735 154)
		(width 0.11)
		(layer "F.Cu")
		(net 197)
	)
	(segment
		(start 192.075 153.333578)
		(end 191.669672 152.92825)
		(width 0.11)
		(layer "F.Cu")
		(net 197)
	)
	(segment
		(start 206.299 150.784578)
		(end 205.025 152.058578)
		(width 0.11)
		(layer "F.Cu")
		(net 197)
	)
	(via
		(at 191.3175 152.801)
		(size 0.35)
		(drill 0.15)
		(layers "F.Cu" "B.Cu")
		(remove_unused_layers yes)
		(keep_end_layers yes)
		(zone_layer_connections)
		(net 197)
	)
	(arc
		(start 204.085 153.45227)
		(mid 204.033744 153.328526)
		(end 203.91 153.27727)
		(width 0.11)
		(layer "F.Cu")
		(net 197)
	)
	(arc
		(start 203.91 153.27727)
		(mid 203.786256 153.328526)
		(end 203.735 153.45227)
		(width 0.11)
		(layer "F.Cu")
		(net 197)
	)
	(arc
		(start 203.735 154)
		(mid 203.683744 154.123744)
		(end 203.56 154.175)
		(width 0.11)
		(layer "F.Cu")
		(net 197)
	)
	(arc
		(start 204.26 154.175)
		(mid 204.136256 154.123744)
		(end 204.085 154)
		(width 0.11)
		(layer "F.Cu")
		(net 197)
	)
	(segment
		(start 190.922 151.676)
		(end 190.822 151.776)
		(width 0.11)
		(layer "B.Cu")
		(net 197)
	)
	(segment
		(start 190.922 151.461)
		(end 190.922 151.676)
		(width 0.11)
		(layer "B.Cu")
		(net 197)
	)
	(segment
		(start 191.19025 152.92825)
		(end 191.3175 152.801)
		(width 0.11)
		(layer "B.Cu")
		(net 197)
	)
	(segment
		(start 191.157201 152.92825)
		(end 191.19025 152.92825)
		(width 0.11)
		(layer "B.Cu")
		(net 197)
	)
	(segment
		(start 190.822 151.776)
		(end 190.822 152.593049)
		(width 0.11)
		(layer "B.Cu")
		(net 197)
	)
	(segment
		(start 190.822 152.593049)
		(end 191.157201 152.92825)
		(width 0.11)
		(layer "B.Cu")
		(net 197)
	)
	(segment
		(start 197.25 148.616422)
		(end 197.25 149.916422)
		(width 0.11)
		(layer "F.Cu")
		(net 198)
	)
	(segment
		(start 198.116422 147.75)
		(end 197.25 148.616422)
		(width 0.11)
		(layer "F.Cu")
		(net 198)
	)
	(segment
		(start 203.486763 150.600366)
		(end 203.625306 150.738909)
		(width 0.11)
		(layer "F.Cu")
		(net 198)
	)
	(segment
		(start 203.0625 150.8125)
		(end 203.025 150.85)
		(width 0.11)
		(layer "F.Cu")
		(net 198)
	)
	(segment
		(start 203.413174 150.951042)
		(end 203.274632 150.8125)
		(width 0.11)
		(layer "F.Cu")
		(net 198)
	)
	(segment
		(start 203.579 150.175)
		(end 203.579 150.3)
		(width 0.11)
		(layer "F.Cu")
		(net 198)
	)
	(segment
		(start 192.541422 151.65)
		(end 191.039853 151.65)
		(width 0.11)
		(layer "F.Cu")
		(net 198)
	)
	(segment
		(start 199.275 150.25)
		(end 199.275 148.15)
		(width 0.11)
		(layer "F.Cu")
		(net 198)
	)
	(segment
		(start 203.699 150.001)
		(end 203.699 150.055)
		(width 0.11)
		(layer "F.Cu")
		(net 198)
	)
	(segment
		(start 196.316422 150.85)
		(end 193.341422 150.85)
		(width 0.11)
		(layer "F.Cu")
		(net 198)
	)
	(segment
		(start 190.85 154.584738)
		(end 190.822 154.612738)
		(width 0.11)
		(layer "F.Cu")
		(net 198)
	)
	(segment
		(start 203.575 150.3)
		(end 203.486763 150.388234)
		(width 0.11)
		(layer "F.Cu")
		(net 198)
	)
	(segment
		(start 193.341422 150.85)
		(end 192.541422 151.65)
		(width 0.11)
		(layer "F.Cu")
		(net 198)
	)
	(segment
		(start 190.822 154.75)
		(end 190.972 154.9)
		(width 0.11)
		(layer "F.Cu")
		(net 198)
	)
	(segment
		(start 191.039853 151.65)
		(end 190.85 151.839853)
		(width 0.11)
		(layer "F.Cu")
		(net 198)
	)
	(segment
		(start 203.579 150.3)
		(end 203.575 150.3)
		(width 0.11)
		(layer "F.Cu")
		(net 198)
	)
	(segment
		(start 203.625306 150.738909)
		(end 203.625306 150.738908)
		(width 0.11)
		(layer "F.Cu")
		(net 198)
	)
	(segment
		(start 190.822 154.612738)
		(end 190.822 154.75)
		(width 0.11)
		(layer "F.Cu")
		(net 198)
	)
	(segment
		(start 203.699 150.055)
		(end 203.579 150.175)
		(width 0.11)
		(layer "F.Cu")
		(net 198)
	)
	(segment
		(start 190.85 151.839853)
		(end 190.85 154.584738)
		(width 0.11)
		(layer "F.Cu")
		(net 198)
	)
	(segment
		(start 198.875 147.75)
		(end 198.116422 147.75)
		(width 0.11)
		(layer "F.Cu")
		(net 198)
	)
	(segment
		(start 197.25 149.916422)
		(end 196.316422 150.85)
		(width 0.11)
		(layer "F.Cu")
		(net 198)
	)
	(segment
		(start 203.025 150.85)
		(end 199.875 150.85)
		(width 0.11)
		(layer "F.Cu")
		(net 198)
	)
	(via
		(at 190.972 154.9)
		(size 0.35)
		(drill 0.15)
		(layers "F.Cu" "B.Cu")
		(remove_unused_layers yes)
		(keep_end_layers yes)
		(zone_layer_connections)
		(net 198)
	)
	(arc
		(start 203.625306 150.738908)
		(mid 203.66924 150.844975)
		(end 203.625306 150.951042)
		(width 0.11)
		(layer "F.Cu")
		(net 198)
	)
	(arc
		(start 203.274632 150.8125)
		(mid 203.168566 150.768566)
		(end 203.0625 150.8125)
		(width 0.11)
		(layer "F.Cu")
		(net 198)
	)
	(arc
		(start 203.486763 150.388234)
		(mid 203.442829 150.4943)
		(end 203.486763 150.600366)
		(width 0.11)
		(layer "F.Cu")
		(net 198)
	)
	(arc
		(start 203.625306 150.951042)
		(mid 203.51924 150.994976)
		(end 203.413174 150.951042)
		(width 0.11)
		(layer "F.Cu")
		(net 198)
	)
	(arc
		(start 199.875 150.85)
		(mid 199.450736 150.674264)
		(end 199.275 150.25)
		(width 0.11)
		(layer "F.Cu")
		(net 198)
	)
	(arc
		(start 199.275 148.15)
		(mid 199.157843 147.867157)
		(end 198.875 147.75)
		(width 0.11)
		(layer "F.Cu")
		(net 198)
	)
	(segment
		(start 190.922 154.386)
		(end 190.832 154.476)
		(width 0.1)
		(layer "B.Cu")
		(net 198)
	)
	(segment
		(start 190.922 154.171)
		(end 190.922 154.386)
		(width 0.1)
		(layer "B.Cu")
		(net 198)
	)
	(segment
		(start 190.832 154.476)
		(end 190.832 154.76)
		(width 0.1)
		(layer "B.Cu")
		(net 198)
	)
	(segment
		(start 190.832 154.76)
		(end 190.972 154.9)
		(width 0.1)
		(layer "B.Cu")
		(net 198)
	)
	(segment
		(start 192.258578 154.375)
		(end 204.866422 154.375)
		(width 0.11)
		(layer "F.Cu")
		(net 199)
	)
	(segment
		(start 206.499 149.551)
		(end 206.299 149.351)
		(width 0.11)
		(layer "F.Cu")
		(net 199)
	)
	(segment
		(start 191.3175 153.2555)
		(end 191.44475 153.12825)
		(width 0.11)
		(layer "F.Cu")
		(net 199)
	)
	(segment
		(start 191.586828 153.12825)
		(end 191.875 153.416422)
		(width 0.11)
		(layer "F.Cu")
		(net 199)
	)
	(segment
		(start 206.619 149.868451)
		(end 206.499 149.748451)
		(width 0.11)
		(layer "F.Cu")
		(net 199)
	)
	(segment
		(start 191.875 153.991422)
		(end 192.258578 154.375)
		(width 0.11)
		(layer "F.Cu")
		(net 199)
	)
	(segment
		(start 205.225 154.016422)
		(end 205.225 152.141422)
		(width 0.11)
		(layer "F.Cu")
		(net 199)
	)
	(segment
		(start 191.875 153.416422)
		(end 191.875 153.991422)
		(width 0.11)
		(layer "F.Cu")
		(net 199)
	)
	(segment
		(start 191.44475 153.12825)
		(end 191.586828 153.12825)
		(width 0.11)
		(layer "F.Cu")
		(net 199)
	)
	(segment
		(start 206.499 150.867422)
		(end 206.499 150.253549)
		(width 0.11)
		(layer "F.Cu")
		(net 199)
	)
	(segment
		(start 206.499 150.253549)
		(end 206.619 150.133549)
		(width 0.11)
		(layer "F.Cu")
		(net 199)
	)
	(segment
		(start 206.499 149.748451)
		(end 206.499 149.551)
		(width 0.11)
		(layer "F.Cu")
		(net 199)
	)
	(segment
		(start 204.866422 154.375)
		(end 205.225 154.016422)
		(width 0.11)
		(layer "F.Cu")
		(net 199)
	)
	(segment
		(start 205.225 152.141422)
		(end 206.499 150.867422)
		(width 0.11)
		(layer "F.Cu")
		(net 199)
	)
	(segment
		(start 206.619 150.133549)
		(end 206.619 149.868451)
		(width 0.11)
		(layer "F.Cu")
		(net 199)
	)
	(via
		(at 191.3175 153.2555)
		(size 0.35)
		(drill 0.15)
		(layers "F.Cu" "B.Cu")
		(remove_unused_layers yes)
		(keep_end_layers yes)
		(zone_layer_connections)
		(net 199)
	)
	(segment
		(start 190.622 152.675893)
		(end 191.074357 153.12825)
		(width 0.11)
		(layer "B.Cu")
		(net 199)
	)
	(segment
		(start 190.522 151.676)
		(end 190.622 151.776)
		(width 0.11)
		(layer "B.Cu")
		(net 199)
	)
	(segment
		(start 190.522 151.461)
		(end 190.522 151.676)
		(width 0.11)
		(layer "B.Cu")
		(net 199)
	)
	(segment
		(start 191.074357 153.12825)
		(end 191.19025 153.12825)
		(width 0.11)
		(layer "B.Cu")
		(net 199)
	)
	(segment
		(start 191.19025 153.12825)
		(end 191.3175 153.2555)
		(width 0.11)
		(layer "B.Cu")
		(net 199)
	)
	(segment
		(start 190.622 151.776)
		(end 190.622 152.675893)
		(width 0.11)
		(layer "B.Cu")
		(net 199)
	)
	(via
		(at 208.91 153.47)
		(size 0.35)
		(drill 0.15)
		(layers "F.Cu" "B.Cu")
		(remove_unused_layers yes)
		(keep_end_layers yes)
		(zone_layer_connections)
		(net 200)
	)
	(via
		(at 210.210003 137.84)
		(size 0.35)
		(drill 0.15)
		(layers "F.Cu" "B.Cu")
		(remove_unused_layers yes)
		(keep_end_layers yes)
		(zone_layer_connections)
		(net 200)
	)
	(segment
		(start 209.91 137.3)
		(end 209.2 137.3)
		(width 0.1)
		(layer "B.Cu")
		(net 200)
	)
	(segment
		(start 210.210003 137.84)
		(end 210.210003 137.600003)
		(width 0.1)
		(layer "B.Cu")
		(net 200)
	)
	(segment
		(start 210.210003 137.600003)
		(end 209.91 137.3)
		(width 0.1)
		(layer "B.Cu")
		(net 200)
	)
	(segment
		(start 208.91 153.47)
		(end 209.322 153.882)
		(width 0.11)
		(layer "B.Cu")
		(net 200)
	)
	(segment
		(start 209.322 153.882)
		(end 209.322 154.171)
		(width 0.11)
		(layer "B.Cu")
		(net 200)
	)
	(segment
		(start 210.63 138.54)
		(end 210.2 138.11)
		(width 0.09)
		(layer "In9.Cu")
		(net 200)
	)
	(segment
		(start 208.91 153.47)
		(end 208.91 152.11)
		(width 0.09)
		(layer "In9.Cu")
		(net 200)
	)
	(segment
		(start 211.825 149.51332)
		(end 211.825 146.38038)
		(width 0.09)
		(layer "In9.Cu")
		(net 200)
	)
	(segment
		(start 210.93 138.54)
		(end 210.63 138.54)
		(width 0.09)
		(layer "In9.Cu")
		(net 200)
	)
	(segment
		(start 211.605 142.785)
		(end 211.605 139.215)
		(width 0.09)
		(layer "In9.Cu")
		(net 200)
	)
	(segment
		(start 208.91 152.11)
		(end 209.29 151.73)
		(width 0.09)
		(layer "In9.Cu")
		(net 200)
	)
	(segment
		(start 211.39 144.71)
		(end 211.39 143)
		(width 0.09)
		(layer "In9.Cu")
		(net 200)
	)
	(segment
		(start 211.825 146.38038)
		(end 211.5 146.05538)
		(width 0.09)
		(layer "In9.Cu")
		(net 200)
	)
	(segment
		(start 209.60832 151.73)
		(end 211.825 149.51332)
		(width 0.09)
		(layer "In9.Cu")
		(net 200)
	)
	(segment
		(start 211.605 139.215)
		(end 210.93 138.54)
		(width 0.09)
		(layer "In9.Cu")
		(net 200)
	)
	(segment
		(start 210.2 138.11)
		(end 210.2 137.850003)
		(width 0.09)
		(layer "In9.Cu")
		(net 200)
	)
	(segment
		(start 210.2 137.850003)
		(end 210.210003 137.84)
		(width 0.09)
		(layer "In9.Cu")
		(net 200)
	)
	(segment
		(start 211.5 144.82)
		(end 211.39 144.71)
		(width 0.09)
		(layer "In9.Cu")
		(net 200)
	)
	(segment
		(start 211.5 146.05538)
		(end 211.5 144.82)
		(width 0.09)
		(layer "In9.Cu")
		(net 200)
	)
	(segment
		(start 211.39 143)
		(end 211.605 142.785)
		(width 0.09)
		(layer "In9.Cu")
		(net 200)
	)
	(segment
		(start 209.29 151.73)
		(end 209.60832 151.73)
		(width 0.09)
		(layer "In9.Cu")
		(net 200)
	)
	(segment
		(start 196.233578 150.65)
		(end 193.258578 150.65)
		(width 0.11)
		(layer "F.Cu")
		(net 201)
	)
	(segment
		(start 203.699 149.351)
		(end 203.379 149.671)
		(width 0.11)
		(layer "F.Cu")
		(net 201)
	)
	(segment
		(start 197.05 148.533578)
		(end 197.05 149.833578)
		(width 0.11)
		(layer "F.Cu")
		(net 201)
	)
	(segment
		(start 193.258578 150.65)
		(end 192.458578 151.45)
		(width 0.11)
		(layer "F.Cu")
		(net 201)
	)
	(segment
		(start 190.65 154.508202)
		(end 190.622 154.536202)
		(width 0.11)
		(layer "F.Cu")
		(net 201)
	)
	(segment
		(start 190.65 151.757009)
		(end 190.65 154.508202)
		(width 0.11)
		(layer "F.Cu")
		(net 201)
	)
	(segment
		(start 190.622 154.75)
		(end 190.472 154.9)
		(width 0.11)
		(layer "F.Cu")
		(net 201)
	)
	(segment
		(start 197.05 149.833578)
		(end 196.233578 150.65)
		(width 0.11)
		(layer "F.Cu")
		(net 201)
	)
	(segment
		(start 192.458578 151.45)
		(end 190.957009 151.45)
		(width 0.11)
		(layer "F.Cu")
		(net 201)
	)
	(segment
		(start 198.875 147.55)
		(end 198.033578 147.55)
		(width 0.11)
		(layer "F.Cu")
		(net 201)
	)
	(segment
		(start 202.929 150.65)
		(end 199.875 150.65)
		(width 0.11)
		(layer "F.Cu")
		(net 201)
	)
	(segment
		(start 190.957009 151.45)
		(end 190.65 151.757009)
		(width 0.11)
		(layer "F.Cu")
		(net 201)
	)
	(segment
		(start 199.475 150.25)
		(end 199.475 148.15)
		(width 0.11)
		(layer "F.Cu")
		(net 201)
	)
	(segment
		(start 198.033578 147.55)
		(end 197.05 148.533578)
		(width 0.11)
		(layer "F.Cu")
		(net 201)
	)
	(segment
		(start 190.622 154.536202)
		(end 190.622 154.75)
		(width 0.11)
		(layer "F.Cu")
		(net 201)
	)
	(segment
		(start 203.379 150.2)
		(end 202.929 150.65)
		(width 0.11)
		(layer "F.Cu")
		(net 201)
	)
	(segment
		(start 203.379 149.671)
		(end 203.379 150.2)
		(width 0.11)
		(layer "F.Cu")
		(net 201)
	)
	(via
		(at 190.472 154.9)
		(size 0.35)
		(drill 0.15)
		(layers "F.Cu" "B.Cu")
		(remove_unused_layers yes)
		(keep_end_layers yes)
		(zone_layer_connections)
		(net 201)
	)
	(arc
		(start 199.475 148.15)
		(mid 199.299264 147.725736)
		(end 198.875 147.55)
		(width 0.11)
		(layer "F.Cu")
		(net 201)
	)
	(arc
		(start 199.875 150.65)
		(mid 199.592157 150.532843)
		(end 199.475 150.25)
		(width 0.11)
		(layer "F.Cu")
		(net 201)
	)
	(segment
		(start 190.522 154.171)
		(end 190.522 154.386)
		(width 0.1)
		(layer "B.Cu")
		(net 201)
	)
	(segment
		(start 190.612 154.76)
		(end 190.472 154.9)
		(width 0.1)
		(layer "B.Cu")
		(net 201)
	)
	(segment
		(start 190.612 154.476)
		(end 190.612 154.76)
		(width 0.1)
		(layer "B.Cu")
		(net 201)
	)
	(segment
		(start 190.522 154.386)
		(end 190.612 154.476)
		(width 0.1)
		(layer "B.Cu")
		(net 201)
	)
	(via
		(at 209.76 137.84)
		(size 0.35)
		(drill 0.15)
		(layers "F.Cu" "B.Cu")
		(remove_unused_layers yes)
		(keep_end_layers yes)
		(zone_layer_connections)
		(net 202)
	)
	(via
		(at 206.94 152.48)
		(size 0.35)
		(drill 0.15)
		(layers "F.Cu" "B.Cu")
		(remove_unused_layers yes)
		(keep_end_layers yes)
		(zone_layer_connections)
		(net 202)
	)
	(segment
		(start 207.22 152.48)
		(end 206.94 152.48)
		(width 0.1)
		(layer "B.Cu")
		(net 202)
	)
	(segment
		(start 209.76 137.84)
		(end 209.76 138.08)
		(width 0.1)
		(layer "B.Cu")
		(net 202)
	)
	(segment
		(start 209.64 138.2)
		(end 209.2 138.2)
		(width 0.1)
		(layer "B.Cu")
		(net 202)
	)
	(segment
		(start 209.76 138.08)
		(end 209.64 138.2)
		(width 0.1)
		(layer "B.Cu")
		(net 202)
	)
	(segment
		(start 207.717 151.983)
		(end 207.22 152.48)
		(width 0.1)
		(layer "B.Cu")
		(net 202)
	)
	(segment
		(start 207.717 151.461)
		(end 207.717 151.983)
		(width 0.1)
		(layer "B.Cu")
		(net 202)
	)
	(segment
		(start 210.805 146.335)
		(end 211.33 146.86)
		(width 0.09)
		(layer "In9.Cu")
		(net 202)
	)
	(segment
		(start 209.76 138.22)
		(end 210.37 138.83)
		(width 0.09)
		(layer "In9.Cu")
		(net 202)
	)
	(segment
		(start 210.52962 150.54)
		(end 210.15038 150.54)
		(width 0.09)
		(layer "In9.Cu")
		(net 202)
	)
	(segment
		(start 208.21038 152.48)
		(end 206.94 152.48)
		(width 0.09)
		(layer "In9.Cu")
		(net 202)
	)
	(segment
		(start 211.38 149.68962)
		(end 210.52962 150.54)
		(width 0.09)
		(layer "In9.Cu")
		(net 202)
	)
	(segment
		(start 211.33 146.86)
		(end 211.33 147.4)
		(width 0.09)
		(layer "In9.Cu")
		(net 202)
	)
	(segment
		(start 209.76 137.84)
		(end 209.76 138.22)
		(width 0.09)
		(layer "In9.Cu")
		(net 202)
	)
	(segment
		(start 211.0325 143.0425)
		(end 211.0325 144.6925)
		(width 0.09)
		(layer "In9.Cu")
		(net 202)
	)
	(segment
		(start 210.805 144.92)
		(end 210.805 146.335)
		(width 0.09)
		(layer "In9.Cu")
		(net 202)
	)
	(segment
		(start 210.37 138.83)
		(end 210.85 138.83)
		(width 0.09)
		(layer "In9.Cu")
		(net 202)
	)
	(segment
		(start 211.173 148.443)
		(end 211.38 148.65)
		(width 0.09)
		(layer "In9.Cu")
		(net 202)
	)
	(segment
		(start 211.38 148.65)
		(end 211.38 149.68962)
		(width 0.09)
		(layer "In9.Cu")
		(net 202)
	)
	(segment
		(start 211.425 142.65)
		(end 211.0325 143.0425)
		(width 0.09)
		(layer "In9.Cu")
		(net 202)
	)
	(segment
		(start 211.173 147.557)
		(end 211.173 148.443)
		(width 0.09)
		(layer "In9.Cu")
		(net 202)
	)
	(segment
		(start 210.15038 150.54)
		(end 208.21038 152.48)
		(width 0.09)
		(layer "In9.Cu")
		(net 202)
	)
	(segment
		(start 211.425 139.405)
		(end 211.425 142.65)
		(width 0.09)
		(layer "In9.Cu")
		(net 202)
	)
	(segment
		(start 211.33 147.4)
		(end 211.173 147.557)
		(width 0.09)
		(layer "In9.Cu")
		(net 202)
	)
	(segment
		(start 210.85 138.83)
		(end 211.425 139.405)
		(width 0.09)
		(layer "In9.Cu")
		(net 202)
	)
	(segment
		(start 211.0325 144.6925)
		(end 210.805 144.92)
		(width 0.09)
		(layer "In9.Cu")
		(net 202)
	)
	(segment
		(start 206.98 149.6574)
		(end 206.98 151.075)
		(width 0.1)
		(layer "F.Cu")
		(net 203)
	)
	(segment
		(start 202.475 148.875)
		(end 205.199 148.875)
		(width 0.174)
		(layer "F.Cu")
		(net 203)
	)
	(segment
		(start 207.575 152.67)
		(end 207.575 151.691)
		(width 0.201)
		(layer "F.Cu")
		(net 203)
	)
	(segment
		(start 202.025 148.425)
		(end 202.025 147.775)
		(width 0.174)
		(layer "F.Cu")
		(net 203)
	)
	(segment
		(start 205.199 148.875)
		(end 205.35 149.026)
		(width 0.174)
		(layer "F.Cu")
		(net 203)
	)
	(segment
		(start 206.72 149.196)
		(end 206.72 149.3974)
		(width 0.1)
		(layer "F.Cu")
		(net 203)
	)
	(segment
		(start 206.98 151.075)
		(end 207.6 151.695)
		(width 0.1)
		(layer "F.Cu")
		(net 203)
	)
	(segment
		(start 202.475 148.875)
		(end 202.025 148.425)
		(width 0.174)
		(layer "F.Cu")
		(net 203)
	)
	(segment
		(start 206.72 149.3974)
		(end 206.98 149.6574)
		(width 0.1)
		(layer "F.Cu")
		(net 203)
	)
	(segment
		(start 207.575 151.691)
		(end 207.586 151.68)
		(width 0.1)
		(layer "F.Cu")
		(net 203)
	)
	(segment
		(start 202.025 147.775)
		(end 202.399 147.401)
		(width 0.174)
		(layer "F.Cu")
		(net 203)
	)
	(segment
		(start 205.35 149.026)
		(end 206.55 149.026)
		(width 0.1)
		(layer "F.Cu")
		(net 203)
	)
	(segment
		(start 206.55 149.026)
		(end 206.72 149.196)
		(width 0.1)
		(layer "F.Cu")
		(net 203)
	)
	(via
		(at 202.399 147.401)
		(size 0.35)
		(drill 0.15)
		(layers "F.Cu" "B.Cu")
		(remove_unused_layers yes)
		(keep_end_layers yes)
		(zone_layer_connections)
		(net 203)
	)
	(segment
		(start 202.399 147.401)
		(end 201.929 147.401)
		(width 0.201)
		(layer "B.Cu")
		(net 203)
	)
	(segment
		(start 201.929 147.401)
		(end 201.88 147.45)
		(width 0.201)
		(layer "B.Cu")
		(net 203)
	)
	(segment
		(start 206.91 148.697102)
		(end 206.91 149.3187)
		(width 0.1)
		(layer "F.Cu")
		(net 204)
	)
	(segment
		(start 207.17 149.5787)
		(end 207.17 150.29)
		(width 0.1)
		(layer "F.Cu")
		(net 204)
	)
	(segment
		(start 205.425 148.375)
		(end 206.587898 148.375)
		(width 0.1)
		(layer "F.Cu")
		(net 204)
	)
	(segment
		(start 205.275 148.525)
		(end 202.873 148.525)
		(width 0.174)
		(layer "F.Cu")
		(net 204)
	)
	(segment
		(start 202.873 148.525)
		(end 202.399 148.051)
		(width 0.174)
		(layer "F.Cu")
		(net 204)
	)
	(segment
		(start 205.4 148.4)
		(end 205.275 148.525)
		(width 0.174)
		(layer "F.Cu")
		(net 204)
	)
	(segment
		(start 206.91 149.3187)
		(end 207.17 149.5787)
		(width 0.1)
		(layer "F.Cu")
		(net 204)
	)
	(segment
		(start 206.587898 148.375)
		(end 206.91 148.697102)
		(width 0.1)
		(layer "F.Cu")
		(net 204)
	)
	(segment
		(start 205.4 148.4)
		(end 205.425 148.375)
		(width 0.1)
		(layer "F.Cu")
		(net 204)
	)
	(segment
		(start 207.17 150.29)
		(end 207.6 150.72)
		(width 0.1)
		(layer "F.Cu")
		(net 204)
	)
	(via
		(at 202.399 148.051)
		(size 0.35)
		(drill 0.15)
		(layers "F.Cu" "B.Cu")
		(remove_unused_layers yes)
		(keep_end_layers yes)
		(zone_layer_connections)
		(net 204)
	)
	(via
		(at 207.6 150.72)
		(size 0.35)
		(drill 0.15)
		(layers "F.Cu" "B.Cu")
		(remove_unused_layers yes)
		(keep_end_layers yes)
		(zone_layer_connections)
		(net 204)
	)
	(segment
		(start 202.34 148.051)
		(end 201.716 148.675)
		(width 0.201)
		(layer "B.Cu")
		(net 204)
	)
	(segment
		(start 202.399 148.051)
		(end 202.34 148.051)
		(width 0.201)
		(layer "B.Cu")
		(net 204)
	)
	(segment
		(start 207.03 147.555)
		(end 206.551 147.076)
		(width 0.201)
		(layer "F.Cu")
		(net 205)
	)
	(segment
		(start 205.324 147.076)
		(end 204.349 148.051)
		(width 0.201)
		(layer "F.Cu")
		(net 205)
	)
	(segment
		(start 207.6 148.75)
		(end 207.03 148.18)
		(width 0.201)
		(layer "F.Cu")
		(net 205)
	)
	(segment
		(start 207.03 148.18)
		(end 207.03 147.555)
		(width 0.201)
		(layer "F.Cu")
		(net 205)
	)
	(segment
		(start 205.442962 147.076)
		(end 205.324 147.076)
		(width 0.201)
		(layer "F.Cu")
		(net 205)
	)
	(segment
		(start 205.442962 147.076)
		(end 206.551 147.076)
		(width 0.1)
		(layer "F.Cu")
		(net 205)
	)
	(via
		(at 207.6 148.75)
		(size 0.35)
		(drill 0.15)
		(layers "F.Cu" "B.Cu")
		(remove_unused_layers yes)
		(keep_end_layers yes)
		(zone_layer_connections)
		(net 205)
	)
	(via
		(at 204.349 148.051)
		(size 0.35)
		(drill 0.15)
		(layers "F.Cu" "B.Cu")
		(remove_unused_layers yes)
		(keep_end_layers yes)
		(zone_layer_connections)
		(net 205)
	)
	(segment
		(start 205.716 149.536962)
		(end 204.902019 148.722981)
		(width 0.201)
		(layer "B.Cu")
		(net 205)
	)
	(segment
		(start 204.349 148.051)
		(end 204.902019 148.604019)
		(width 0.201)
		(layer "B.Cu")
		(net 205)
	)
	(segment
		(start 204.902019 148.604019)
		(end 204.902019 148.722981)
		(width 0.201)
		(layer "B.Cu")
		(net 205)
	)
	(segment
		(start 205.716 149.625)
		(end 205.716 149.536962)
		(width 0.201)
		(layer "B.Cu")
		(net 205)
	)
	(segment
		(start 197.632297 147.25)
		(end 197.632297 147.447703)
		(width 0.1)
		(layer "F.Cu")
		(net 206)
	)
	(segment
		(start 197.13 147.95)
		(end 196.64 147.95)
		(width 0.1)
		(layer "F.Cu")
		(net 206)
	)
	(segment
		(start 197.632297 147.447703)
		(end 197.13 147.95)
		(width 0.1)
		(layer "F.Cu")
		(net 206)
	)
	(via
		(at 197.632297 147.25)
		(size 0.35)
		(drill 0.15)
		(layers "F.Cu" "B.Cu")
		(remove_unused_layers yes)
		(keep_end_layers yes)
		(zone_layer_connections)
		(net 206)
	)
	(via
		(at 189.717 151.131)
		(size 0.35)
		(drill 0.15)
		(layers "F.Cu" "B.Cu")
		(remove_unused_layers yes)
		(keep_end_layers yes)
		(zone_layer_connections)
		(net 206)
	)
	(segment
		(start 189 152.95)
		(end 189.717 152.233)
		(width 0.1)
		(layer "B.Cu")
		(net 206)
	)
	(segment
		(start 189.717 152.233)
		(end 189.717 151.461)
		(width 0.1)
		(layer "B.Cu")
		(net 206)
	)
	(segment
		(start 187.875 152.95)
		(end 189 152.95)
		(width 0.1)
		(layer "B.Cu")
		(net 206)
	)
	(segment
		(start 197.632297 147.697703)
		(end 196.5 148.83)
		(width 0.1)
		(layer "In7.Cu")
		(net 206)
	)
	(segment
		(start 195.419 151.131)
		(end 189.717 151.131)
		(width 0.1)
		(layer "In7.Cu")
		(net 206)
	)
	(segment
		(start 196.5 150.05)
		(end 195.419 151.131)
		(width 0.1)
		(layer "In7.Cu")
		(net 206)
	)
	(segment
		(start 197.632297 147.25)
		(end 197.632297 147.697703)
		(width 0.1)
		(layer "In7.Cu")
		(net 206)
	)
	(segment
		(start 196.5 148.83)
		(end 196.5 150.05)
		(width 0.1)
		(layer "In7.Cu")
		(net 206)
	)
	(via
		(at 212.6425 126.327)
		(size 0.35)
		(drill 0.15)
		(layers "F.Cu" "B.Cu")
		(remove_unused_layers yes)
		(keep_end_layers yes)
		(zone_layer_connections)
		(net 207)
	)
	(via
		(at 211.9435 128.95)
		(size 0.35)
		(drill 0.15)
		(layers "F.Cu" "B.Cu")
		(remove_unused_layers yes)
		(keep_end_layers yes)
		(zone_layer_connections)
		(net 207)
	)
	(segment
		(start 207.291002 121.05)
		(end 207.636439 121.05)
		(width 0.15)
		(layer "B.Cu")
		(net 207)
	)
	(segment
		(start 209.38 123.49)
		(end 209.38 124.54)
		(width 0.15)
		(layer "B.Cu")
		(net 207)
	)
	(segment
		(start 213.82 125.79)
		(end 214.15 126.12)
		(width 0.15)
		(layer "B.Cu")
		(net 207)
	)
	(segment
		(start 212.009 125.099)
		(end 212.29 125.38)
		(width 0.15)
		(layer "B.Cu")
		(net 207)
	)
	(segment
		(start 213.12 125.79)
		(end 213.82 125.79)
		(width 0.15)
		(layer "B.Cu")
		(net 207)
	)
	(segment
		(start 214.15 126.12)
		(end 214.15 126.65)
		(width 0.15)
		(layer "B.Cu")
		(net 207)
	)
	(segment
		(start 214.15 126.65)
		(end 213.85 126.95)
		(width 0.15)
		(layer "B.Cu")
		(net 207)
	)
	(segment
		(start 209.074 123.184)
		(end 209.38 123.49)
		(width 0.15)
		(layer "B.Cu")
		(net 207)
	)
	(segment
		(start 213.85 126.95)
		(end 213.2605 126.95)
		(width 0.15)
		(layer "B.Cu")
		(net 207)
	)
	(segment
		(start 212.29 125.38)
		(end 212.71 125.38)
		(width 0.15)
		(layer "B.Cu")
		(net 207)
	)
	(segment
		(start 208.48 123)
		(end 208.664 123.184)
		(width 0.15)
		(layer "B.Cu")
		(net 207)
	)
	(segment
		(start 213.2605 126.95)
		(end 212.6425 126.332)
		(width 0.15)
		(layer "B.Cu")
		(net 207)
	)
	(segment
		(start 210.089 125.249)
		(end 210.694561 125.249)
		(width 0.15)
		(layer "B.Cu")
		(net 207)
	)
	(segment
		(start 207.636439 121.05)
		(end 208.48 121.893561)
		(width 0.15)
		(layer "B.Cu")
		(net 207)
	)
	(segment
		(start 210.694561 125.249)
		(end 210.844561 125.099)
		(width 0.15)
		(layer "B.Cu")
		(net 207)
	)
	(segment
		(start 212.71 125.38)
		(end 213.12 125.79)
		(width 0.15)
		(layer "B.Cu")
		(net 207)
	)
	(segment
		(start 208.48 121.893561)
		(end 208.48 123)
		(width 0.15)
		(layer "B.Cu")
		(net 207)
	)
	(segment
		(start 210.844561 125.099)
		(end 212.009 125.099)
		(width 0.15)
		(layer "B.Cu")
		(net 207)
	)
	(segment
		(start 208.664 123.184)
		(end 209.074 123.184)
		(width 0.15)
		(layer "B.Cu")
		(net 207)
	)
	(segment
		(start 209.38 124.54)
		(end 210.089 125.249)
		(width 0.15)
		(layer "B.Cu")
		(net 207)
	)
	(segment
		(start 212.025 126.275)
		(end 211.93 126.18)
		(width 0.09)
		(layer "In2.Cu")
		(net 207)
	)
	(segment
		(start 213.065 126.61)
		(end 212.82 126.61)
		(width 0.09)
		(layer "In2.Cu")
		(net 207)
	)
	(segment
		(start 211.02 130.82)
		(end 211.175 130.975)
		(width 0.09)
		(layer "In2.Cu")
		(net 207)
	)
	(segment
		(start 213.18 126.725)
		(end 213.065 126.61)
		(width 0.09)
		(layer "In2.Cu")
		(net 207)
	)
	(segment
		(start 212.82 126.61)
		(end 212.57 126.86)
		(width 0.09)
		(layer "In2.Cu")
		(net 207)
	)
	(segment
		(start 211.75 130.975)
		(end 211.92 130.805)
		(width 0.09)
		(layer "In2.Cu")
		(net 207)
	)
	(segment
		(start 212.4 126.86)
		(end 212.025 126.485)
		(width 0.09)
		(layer "In2.Cu")
		(net 207)
	)
	(segment
		(start 212.6425 126.0775)
		(end 212.6425 126.327)
		(width 0.09)
		(layer "In2.Cu")
		(net 207)
	)
	(segment
		(start 211.92 130.805)
		(end 211.92 129.43)
		(width 0.09)
		(layer "In2.Cu")
		(net 207)
	)
	(segment
		(start 212.025 126.485)
		(end 212.025 126.275)
		(width 0.09)
		(layer "In2.Cu")
		(net 207)
	)
	(segment
		(start 212.0025 125.87)
		(end 212.435 125.87)
		(width 0.09)
		(layer "In2.Cu")
		(net 207)
	)
	(segment
		(start 211.19 128.95)
		(end 211.02 129.12)
		(width 0.09)
		(layer "In2.Cu")
		(net 207)
	)
	(segment
		(start 212.836181 128.818317)
		(end 212.836182 128.818317)
		(width 0.09)
		(layer "In2.Cu")
		(net 207)
	)
	(segment
		(start 212.57 126.86)
		(end 212.4 126.86)
		(width 0.09)
		(layer "In2.Cu")
		(net 207)
	)
	(segment
		(start 212.836182 129.030449)
		(end 212.836182 129.03045)
		(width 0.09)
		(layer "In2.Cu")
		(net 207)
	)
	(segment
		(start 211.92 129.43)
		(end 212.21 129.14)
		(width 0.09)
		(layer "In2.Cu")
		(net 207)
	)
	(segment
		(start 212.836182 128.606183)
		(end 213.18 128.262365)
		(width 0.09)
		(layer "In2.Cu")
		(net 207)
	)
	(segment
		(start 211.175 130.975)
		(end 211.75 130.975)
		(width 0.09)
		(layer "In2.Cu")
		(net 207)
	)
	(segment
		(start 211.02 129.12)
		(end 211.02 130.82)
		(width 0.09)
		(layer "In2.Cu")
		(net 207)
	)
	(segment
		(start 213.18 128.262365)
		(end 213.18 126.725)
		(width 0.09)
		(layer "In2.Cu")
		(net 207)
	)
	(segment
		(start 211.93 125.9425)
		(end 212.0025 125.87)
		(width 0.09)
		(layer "In2.Cu")
		(net 207)
	)
	(segment
		(start 212.435 125.87)
		(end 212.6425 126.0775)
		(width 0.09)
		(layer "In2.Cu")
		(net 207)
	)
	(segment
		(start 212.21 129.14)
		(end 212.305294 129.14)
		(width 0.09)
		(layer "In2.Cu")
		(net 207)
	)
	(segment
		(start 212.305294 129.14)
		(end 212.441411 129.003883)
		(width 0.09)
		(layer "In2.Cu")
		(net 207)
	)
	(segment
		(start 211.9435 128.95)
		(end 211.19 128.95)
		(width 0.09)
		(layer "In2.Cu")
		(net 207)
	)
	(segment
		(start 211.93 126.18)
		(end 211.93 125.9425)
		(width 0.09)
		(layer "In2.Cu")
		(net 207)
	)
	(arc
		(start 212.441411 129.003883)
		(mid 212.537566 128.987804)
		(end 212.62405 129.030449)
		(width 0.09)
		(layer "In2.Cu")
		(net 207)
	)
	(arc
		(start 212.62405 129.030449)
		(mid 212.730116 129.074383)
		(end 212.836182 129.030449)
		(width 0.09)
		(layer "In2.Cu")
		(net 207)
	)
	(arc
		(start 212.836182 129.03045)
		(mid 212.880117 128.924382)
		(end 212.836181 128.818317)
		(width 0.09)
		(layer "In2.Cu")
		(net 207)
	)
	(arc
		(start 212.836182 128.818317)
		(mid 212.792247 128.712251)
		(end 212.836182 128.606183)
		(width 0.09)
		(layer "In2.Cu")
		(net 207)
	)
	(via
		(at 212.4435 128.45)
		(size 0.35)
		(drill 0.15)
		(layers "F.Cu" "B.Cu")
		(remove_unused_layers yes)
		(keep_end_layers yes)
		(zone_layer_connections)
		(net 208)
	)
	(via
		(at 211.6425 126.327)
		(size 0.35)
		(drill 0.15)
		(layers "F.Cu" "B.Cu")
		(remove_unused_layers yes)
		(keep_end_layers yes)
		(zone_layer_connections)
		(net 208)
	)
	(segment
		(start 210.86 125.59)
		(end 211.03 125.42)
		(width 0.15)
		(layer "B.Cu")
		(net 208)
	)
	(segment
		(start 211.476366 125.769087)
		(end 211.51 125.77)
		(width 0.15)
		(layer "B.Cu")
		(net 208)
	)
	(segment
		(start 211.339087 125.556366)
		(end 211.34 125.59)
		(width 0.15)
		(layer "B.Cu")
		(net 208)
	)
	(segment
		(start 211.24 126.61)
		(end 211.518 126.332)
		(width 0.15)
		(layer "B.Cu")
		(net 208)
	)
	(segment
		(start 211.75422 125.446655)
		(end 211.816366 125.420913)
		(width 0.15)
		(layer "B.Cu")
		(net 208)
	)
	(segment
		(start 211.34 125.59)
		(end 211.34 125.6)
		(width 0.15)
		(layer "B.Cu")
		(net 208)
	)
	(segment
		(start 211.68 125.59)
		(end 211.680913 125.556366)
		(width 0.15)
		(layer "B.Cu")
		(net 208)
	)
	(segment
		(start 209.03 123.77)
		(end 209.03 124.69)
		(width 0.15)
		(layer "B.Cu")
		(net 208)
	)
	(segment
		(start 210.77 126.43)
		(end 210.94 126.43)
		(width 0.15)
		(layer "B.Cu")
		(net 208)
	)
	(segment
		(start 211.366655 125.69578)
		(end 211.41422 125.743345)
		(width 0.15)
		(layer "B.Cu")
		(net 208)
	)
	(segment
		(start 210.439331 125.679999)
		(end 210.470081 125.710749)
		(width 0.15)
		(layer "B.Cu")
		(net 208)
	)
	(segment
		(start 211.26578 125.446655)
		(end 211.313345 125.49422)
		(width 0.15)
		(layer "B.Cu")
		(net 208)
	)
	(segment
		(start 212.01 126.82)
		(end 211.33 126.82)
		(width 0.15)
		(layer "B.Cu")
		(net 208)
	)
	(segment
		(start 211.41422 125.743345)
		(end 211.476366 125.769087)
		(width 0.15)
		(layer "B.Cu")
		(net 208)
	)
	(segment
		(start 211.340913 125.633634)
		(end 211.366655 125.69578)
		(width 0.15)
		(layer "B.Cu")
		(net 208)
	)
	(segment
		(start 211.543634 125.769087)
		(end 211.60578 125.743345)
		(width 0.15)
		(layer "B.Cu")
		(net 208)
	)
	(segment
		(start 211.51 125.77)
		(end 211.543634 125.769087)
		(width 0.15)
		(layer "B.Cu")
		(net 208)
	)
	(segment
		(start 211.17 125.42)
		(end 211.203634 125.420913)
		(width 0.15)
		(layer "B.Cu")
		(net 208)
	)
	(segment
		(start 211.92 125.42)
		(end 212.15 125.65)
		(width 0.15)
		(layer "B.Cu")
		(net 208)
	)
	(segment
		(start 212.15 126.68)
		(end 212.01 126.82)
		(width 0.15)
		(layer "B.Cu")
		(net 208)
	)
	(segment
		(start 211.679087 125.633634)
		(end 211.68 125.6)
		(width 0.15)
		(layer "B.Cu")
		(net 208)
	)
	(segment
		(start 208.44 123.5)
		(end 208.76 123.5)
		(width 0.15)
		(layer "B.Cu")
		(net 208)
	)
	(segment
		(start 208.14 122)
		(end 208.14 123.2)
		(width 0.15)
		(layer "B.Cu")
		(net 208)
	)
	(segment
		(start 211.34 125.6)
		(end 211.340913 125.633634)
		(width 0.15)
		(layer "B.Cu")
		(net 208)
	)
	(segment
		(start 211.85 125.42)
		(end 211.92 125.42)
		(width 0.15)
		(layer "B.Cu")
		(net 208)
	)
	(segment
		(start 210.470081 126.130082)
		(end 210.77 126.43)
		(width 0.15)
		(layer "B.Cu")
		(net 208)
	)
	(segment
		(start 211.518 126.332)
		(end 211.6425 126.332)
		(width 0.15)
		(layer "B.Cu")
		(net 208)
	)
	(segment
		(start 211.680913 125.556366)
		(end 211.706655 125.49422)
		(width 0.15)
		(layer "B.Cu")
		(net 208)
	)
	(segment
		(start 211.03 126.06)
		(end 210.86 125.89)
		(width 0.15)
		(layer "B.Cu")
		(net 208)
	)
	(segment
		(start 211.33 126.82)
		(end 211.24 126.73)
		(width 0.15)
		(layer "B.Cu")
		(net 208)
	)
	(segment
		(start 207.588 121.448)
		(end 208.14 122)
		(width 0.15)
		(layer "B.Cu")
		(net 208)
	)
	(segment
		(start 211.816366 125.420913)
		(end 211.85 125.42)
		(width 0.15)
		(layer "B.Cu")
		(net 208)
	)
	(segment
		(start 211.653345 125.69578)
		(end 211.679087 125.633634)
		(width 0.15)
		(layer "B.Cu")
		(net 208)
	)
	(segment
		(start 209.03 124.69)
		(end 210.02 125.68)
		(width 0.15)
		(layer "B.Cu")
		(net 208)
	)
	(segment
		(start 211.03 126.34)
		(end 211.03 126.06)
		(width 0.15)
		(layer "B.Cu")
		(net 208)
	)
	(segment
		(start 210.86 125.89)
		(end 210.86 125.59)
		(width 0.15)
		(layer "B.Cu")
		(net 208)
	)
	(segment
		(start 208.14 123.2)
		(end 208.44 123.5)
		(width 0.15)
		(layer "B.Cu")
		(net 208)
	)
	(segment
		(start 208.76 123.5)
		(end 209.03 123.77)
		(width 0.15)
		(layer "B.Cu")
		(net 208)
	)
	(segment
		(start 211.03 125.42)
		(end 211.17 125.42)
		(width 0.15)
		(layer "B.Cu")
		(net 208)
	)
	(segment
		(start 212.15 125.65)
		(end 212.15 126.68)
		(width 0.15)
		(layer "B.Cu")
		(net 208)
	)
	(segment
		(start 211.68 125.6)
		(end 211.68 125.59)
		(width 0.15)
		(layer "B.Cu")
		(net 208)
	)
	(segment
		(start 211.706655 125.49422)
		(end 211.75422 125.446655)
		(width 0.15)
		(layer "B.Cu")
		(net 208)
	)
	(segment
		(start 210.470081 125.920415)
		(end 210.470081 125.920416)
		(width 0.15)
		(layer "B.Cu")
		(net 208)
	)
	(segment
		(start 210.94 126.43)
		(end 211.03 126.34)
		(width 0.15)
		(layer "B.Cu")
		(net 208)
	)
	(segment
		(start 211.313345 125.49422)
		(end 211.339087 125.556366)
		(width 0.15)
		(layer "B.Cu")
		(net 208)
	)
	(segment
		(start 211.24 126.73)
		(end 211.24 126.61)
		(width 0.15)
		(layer "B.Cu")
		(net 208)
	)
	(segment
		(start 211.203634 125.420913)
		(end 211.26578 125.446655)
		(width 0.15)
		(layer "B.Cu")
		(net 208)
	)
	(segment
		(start 211.60578 125.743345)
		(end 211.653345 125.69578)
		(width 0.15)
		(layer "B.Cu")
		(net 208)
	)
	(segment
		(start 207.291002 121.448)
		(end 207.588 121.448)
		(width 0.15)
		(layer "B.Cu")
		(net 208)
	)
	(arc
		(start 210.470081 125.920416)
		(mid 210.426658 126.025249)
		(end 210.470081 126.130082)
		(width 0.15)
		(layer "B.Cu")
		(net 208)
	)
	(arc
		(start 210.229665 125.679999)
		(mid 210.334498 125.636576)
		(end 210.439331 125.679999)
		(width 0.15)
		(layer "B.Cu")
		(net 208)
	)
	(arc
		(start 210.02 125.68)
		(mid 210.124833 125.723423)
		(end 210.229665 125.679999)
		(width 0.15)
		(layer "B.Cu")
		(net 208)
	)
	(arc
		(start 210.470081 125.710749)
		(mid 210.513504 125.815582)
		(end 210.470081 125.920415)
		(width 0.15)
		(layer "B.Cu")
		(net 208)
	)
	(segment
		(start 212.94 128.18)
		(end 212.67 128.45)
		(width 0.09)
		(layer "In2.Cu")
		(net 208)
	)
	(segment
		(start 211.326 127.284)
		(end 211.326 126.776)
		(width 0.09)
		(layer "In2.Cu")
		(net 208)
	)
	(segment
		(start 210.424973 127.452511)
		(end 210.460329 127.487867)
		(width 0.09)
		(layer "In2.Cu")
		(net 208)
	)
	(segment
		(start 211.6425 126.0125)
		(end 211.5 125.87)
		(width 0.09)
		(layer "In2.Cu")
		(net 208)
	)
	(segment
		(start 210.62 126.86)
		(end 210.62 127.01)
		(width 0.09)
		(layer "In2.Cu")
		(net 208)
	)
	(segment
		(start 210.17 128.26)
		(end 210.35 128.26)
		(width 0.09)
		(layer "In2.Cu")
		(net 208)
	)
	(segment
		(start 212.37 127.4)
		(end 212.604135 127.4)
		(width 0.09)
		(layer "In2.Cu")
		(net 208)
	)
	(segment
		(start 209.85 127.78)
		(end 209.85 127.94)
		(width 0.09)
		(layer "In2.Cu")
		(net 208)
	)
	(segment
		(start 210.62 126.02)
		(end 210.62 126.16)
		(width 0.09)
		(layer "In2.Cu")
		(net 208)
	)
	(segment
		(start 210.460329 127.735355)
		(end 210.46033 127.735355)
		(width 0.09)
		(layer "In2.Cu")
		(net 208)
	)
	(segment
		(start 212.97 127.765865)
		(end 212.97 128.15)
		(width 0.09)
		(layer "In2.Cu")
		(net 208)
	)
	(segment
		(start 211.040416 127.569583)
		(end 211.21 127.4)
		(width 0.09)
		(layer "In2.Cu")
		(net 208)
	)
	(segment
		(start 212.022 126.86)
		(end 212.08 126.86)
		(width 0.09)
		(layer "In2.Cu")
		(net 208)
	)
	(segment
		(start 212.67 128.45)
		(end 212.4435 128.45)
		(width 0.09)
		(layer "In2.Cu")
		(net 208)
	)
	(segment
		(start 211.442 126.66)
		(end 211.5 126.66)
		(width 0.09)
		(layer "In2.Cu")
		(net 208)
	)
	(segment
		(start 210.77 125.87)
		(end 210.62 126.02)
		(width 0.09)
		(layer "In2.Cu")
		(net 208)
	)
	(segment
		(start 210.8 127.81)
		(end 211.040416 127.569583)
		(width 0.09)
		(layer "In2.Cu")
		(net 208)
	)
	(segment
		(start 209.85 127.94)
		(end 210.17 128.26)
		(width 0.09)
		(layer "In2.Cu")
		(net 208)
	)
	(segment
		(start 211.5 125.87)
		(end 211.38 125.87)
		(width 0.09)
		(layer "In2.Cu")
		(net 208)
	)
	(segment
		(start 210.795 126.335)
		(end 210.945 126.335)
		(width 0.09)
		(layer "In2.Cu")
		(net 208)
	)
	(segment
		(start 212.312 127.4)
		(end 212.37 127.4)
		(width 0.09)
		(layer "In2.Cu")
		(net 208)
	)
	(segment
		(start 210.62 127.01)
		(end 210.424973 127.205023)
		(width 0.09)
		(layer "In2.Cu")
		(net 208)
	)
	(segment
		(start 211.732 127.4)
		(end 211.79 127.4)
		(width 0.09)
		(layer "In2.Cu")
		(net 208)
	)
	(segment
		(start 211.38 125.87)
		(end 211.29 125.96)
		(width 0.09)
		(layer "In2.Cu")
		(net 208)
	)
	(segment
		(start 211.07 125.96)
		(end 210.98 125.87)
		(width 0.09)
		(layer "In2.Cu")
		(net 208)
	)
	(segment
		(start 211.616 126.776)
		(end 211.616 127.284)
		(width 0.09)
		(layer "In2.Cu")
		(net 208)
	)
	(segment
		(start 211.29 125.96)
		(end 211.07 125.96)
		(width 0.09)
		(layer "In2.Cu")
		(net 208)
	)
	(segment
		(start 210.945 126.685)
		(end 210.795 126.685)
		(width 0.09)
		(layer "In2.Cu")
		(net 208)
	)
	(segment
		(start 211.6425 126.327)
		(end 211.6425 126.0125)
		(width 0.09)
		(layer "In2.Cu")
		(net 208)
	)
	(segment
		(start 212.196 126.976)
		(end 212.196 127.284)
		(width 0.09)
		(layer "In2.Cu")
		(net 208)
	)
	(segment
		(start 211.906 127.284)
		(end 211.906 126.976)
		(width 0.09)
		(layer "In2.Cu")
		(net 208)
	)
	(segment
		(start 212.97 128.15)
		(end 212.94 128.18)
		(width 0.09)
		(layer "In2.Cu")
		(net 208)
	)
	(segment
		(start 209.93 127.7)
		(end 209.85 127.78)
		(width 0.09)
		(layer "In2.Cu")
		(net 208)
	)
	(segment
		(start 210.212842 127.735355)
		(end 210.177486 127.7)
		(width 0.09)
		(layer "In2.Cu")
		(net 208)
	)
	(segment
		(start 210.35 128.26)
		(end 210.8 127.81)
		(width 0.09)
		(layer "In2.Cu")
		(net 208)
	)
	(segment
		(start 210.98 125.87)
		(end 210.77 125.87)
		(width 0.09)
		(layer "In2.Cu")
		(net 208)
	)
	(segment
		(start 212.604135 127.4)
		(end 212.97 127.765865)
		(width 0.09)
		(layer "In2.Cu")
		(net 208)
	)
	(arc
		(start 211.21 127.4)
		(mid 211.292024 127.366024)
		(end 211.326 127.284)
		(width 0.09)
		(layer "In2.Cu")
		(net 208)
	)
	(arc
		(start 211.326 126.776)
		(mid 211.359976 126.693976)
		(end 211.442 126.66)
		(width 0.09)
		(layer "In2.Cu")
		(net 208)
	)
	(arc
		(start 211.616 127.284)
		(mid 211.649976 127.366024)
		(end 211.732 127.4)
		(width 0.09)
		(layer "In2.Cu")
		(net 208)
	)
	(arc
		(start 211.5 126.66)
		(mid 211.582024 126.693976)
		(end 211.616 126.776)
		(width 0.09)
		(layer "In2.Cu")
		(net 208)
	)
	(arc
		(start 211.12 126.51)
		(mid 211.068744 126.633744)
		(end 210.945 126.685)
		(width 0.09)
		(layer "In2.Cu")
		(net 208)
	)
	(arc
		(start 210.46033 127.735355)
		(mid 210.336586 127.786611)
		(end 210.212842 127.735355)
		(width 0.09)
		(layer "In2.Cu")
		(net 208)
	)
	(arc
		(start 212.08 126.86)
		(mid 212.162024 126.893976)
		(end 212.196 126.976)
		(width 0.09)
		(layer "In2.Cu")
		(net 208)
	)
	(arc
		(start 210.945 126.335)
		(mid 211.068744 126.386256)
		(end 211.12 126.51)
		(width 0.09)
		(layer "In2.Cu")
		(net 208)
	)
	(arc
		(start 210.62 126.16)
		(mid 210.671256 126.283744)
		(end 210.795 126.335)
		(width 0.09)
		(layer "In2.Cu")
		(net 208)
	)
	(arc
		(start 210.424973 127.205023)
		(mid 210.373717 127.328767)
		(end 210.424973 127.452511)
		(width 0.09)
		(layer "In2.Cu")
		(net 208)
	)
	(arc
		(start 210.460329 127.487867)
		(mid 210.511585 127.611611)
		(end 210.460329 127.735355)
		(width 0.09)
		(layer "In2.Cu")
		(net 208)
	)
	(arc
		(start 210.795 126.685)
		(mid 210.671256 126.736256)
		(end 210.62 126.86)
		(width 0.09)
		(layer "In2.Cu")
		(net 208)
	)
	(arc
		(start 211.79 127.4)
		(mid 211.872024 127.366024)
		(end 211.906 127.284)
		(width 0.09)
		(layer "In2.Cu")
		(net 208)
	)
	(arc
		(start 211.906 126.976)
		(mid 211.939976 126.893976)
		(end 212.022 126.86)
		(width 0.09)
		(layer "In2.Cu")
		(net 208)
	)
	(arc
		(start 212.196 127.284)
		(mid 212.229976 127.366024)
		(end 212.312 127.4)
		(width 0.09)
		(layer "In2.Cu")
		(net 208)
	)
	(arc
		(start 210.177486 127.7)
		(mid 210.053743 127.648744)
		(end 209.93 127.7)
		(width 0.09)
		(layer "In2.Cu")
		(net 208)
	)
	(segment
		(start 177.880247 140.107759)
		(end 177.900506 140.0875)
		(width 0.174)
		(layer "F.Cu")
		(net 209)
	)
	(segment
		(start 177.900506 140.0875)
		(end 178.515 140.0875)
		(width 0.174)
		(layer "F.Cu")
		(net 209)
	)
	(via
		(at 177.880247 140.107759)
		(size 0.35)
		(drill 0.15)
		(layers "F.Cu" "B.Cu")
		(remove_unused_layers yes)
		(keep_end_layers yes)
		(zone_layer_connections)
		(net 209)
	)
	(via
		(at 175.25 140.075)
		(size 0.35)
		(drill 0.15)
		(layers "F.Cu" "B.Cu")
		(remove_unused_layers yes)
		(keep_end_layers yes)
		(zone_layer_connections)
		(net 209)
	)
	(via
		(at 175.475 140.4835)
		(size 0.35)
		(drill 0.15)
		(layers "F.Cu" "B.Cu")
		(remove_unused_layers yes)
		(keep_end_layers yes)
		(zone_layer_connections)
		(net 209)
	)
	(via
		(at 175.75 140.1)
		(size 0.35)
		(drill 0.15)
		(layers "F.Cu" "B.Cu")
		(remove_unused_layers yes)
		(keep_end_layers yes)
		(zone_layer_connections)
		(net 209)
	)
	(via
		(at 175.525 139.7)
		(size 0.35)
		(drill 0.15)
		(layers "F.Cu" "B.Cu")
		(remove_unused_layers yes)
		(keep_end_layers yes)
		(zone_layer_connections)
		(net 209)
	)
	(segment
		(start 178 139.25)
		(end 178.5 139.75)
		(width 0.1)
		(layer "B.Cu")
		(net 209)
	)
	(segment
		(start 177.880247 140.107759)
		(end 177.220259 140.107759)
		(width 0.174)
		(layer "B.Cu")
		(net 209)
	)
	(segment
		(start 178.5 139.75)
		(end 178.51 139.75)
		(width 0.1)
		(layer "B.Cu")
		(net 209)
	)
	(segment
		(start 177.1 139.25)
		(end 178 139.25)
		(width 0.1)
		(layer "B.Cu")
		(net 209)
	)
	(segment
		(start 176.95 139.4)
		(end 177.1 139.25)
		(width 0.1)
		(layer "B.Cu")
		(net 209)
	)
	(segment
		(start 177.220259 140.107759)
		(end 176.95 139.8375)
		(width 0.174)
		(layer "B.Cu")
		(net 209)
	)
	(segment
		(start 176.95 139.8375)
		(end 176.95 139.4)
		(width 0.1)
		(layer "B.Cu")
		(net 209)
	)
	(via
		(at 189.299 139.5)
		(size 0.35)
		(drill 0.15)
		(layers "F.Cu" "B.Cu")
		(remove_unused_layers yes)
		(keep_end_layers yes)
		(zone_layer_connections)
		(net 210)
	)
	(via
		(at 201.749 144.801)
		(size 0.35)
		(drill 0.15)
		(layers "F.Cu" "B.Cu")
		(remove_unused_layers yes)
		(keep_end_layers yes)
		(zone_layer_connections)
		(net 210)
	)
	(segment
		(start 189.7 139.099)
		(end 189.7 138.647451)
		(width 0.09)
		(layer "In9.Cu")
		(net 210)
	)
	(segment
		(start 194.77 139.9)
		(end 195.02 139.9)
		(width 0.09)
		(layer "In9.Cu")
		(net 210)
	)
	(segment
		(start 198.75 144)
		(end 199.871 145.121)
		(width 0.09)
		(layer "In9.Cu")
		(net 210)
	)
	(segment
		(start 195.02 139.9)
		(end 195.28 140.16)
		(width 0.09)
		(layer "In9.Cu")
		(net 210)
	)
	(segment
		(start 197.967451 141.421)
		(end 198.331 141.421)
		(width 0.09)
		(layer "In9.Cu")
		(net 210)
	)
	(segment
		(start 194 139.06)
		(end 194.18 139.06)
		(width 0.09)
		(layer "In9.Cu")
		(net 210)
	)
	(segment
		(start 200.639 145.121)
		(end 200.769 144.991)
		(width 0.09)
		(layer "In9.Cu")
		(net 210)
	)
	(segment
		(start 193.67 138.73)
		(end 194 139.06)
		(width 0.09)
		(layer "In9.Cu")
		(net 210)
	)
	(segment
		(start 201.63 144.48)
		(end 201.749 144.599)
		(width 0.09)
		(layer "In9.Cu")
		(net 210)
	)
	(segment
		(start 200.92 144.48)
		(end 201.63 144.48)
		(width 0.09)
		(layer "In9.Cu")
		(net 210)
	)
	(segment
		(start 189.299 139.5)
		(end 189.7 139.099)
		(width 0.09)
		(layer "In9.Cu")
		(net 210)
	)
	(segment
		(start 197.69 140.97)
		(end 197.69 141.143549)
		(width 0.09)
		(layer "In9.Cu")
		(net 210)
	)
	(segment
		(start 195.28 140.332549)
		(end 195.722451 140.775)
		(width 0.09)
		(layer "In9.Cu")
		(net 210)
	)
	(segment
		(start 199.871 145.121)
		(end 200.639 145.121)
		(width 0.09)
		(layer "In9.Cu")
		(net 210)
	)
	(segment
		(start 190.047451 138.3)
		(end 193.51 138.3)
		(width 0.09)
		(layer "In9.Cu")
		(net 210)
	)
	(segment
		(start 189.7 138.647451)
		(end 190.047451 138.3)
		(width 0.09)
		(layer "In9.Cu")
		(net 210)
	)
	(segment
		(start 194.18 139.06)
		(end 194.49 139.37)
		(width 0.09)
		(layer "In9.Cu")
		(net 210)
	)
	(segment
		(start 193.67 138.46)
		(end 193.67 138.73)
		(width 0.09)
		(layer "In9.Cu")
		(net 210)
	)
	(segment
		(start 195.722451 140.775)
		(end 197.495 140.775)
		(width 0.09)
		(layer "In9.Cu")
		(net 210)
	)
	(segment
		(start 197.69 141.143549)
		(end 197.967451 141.421)
		(width 0.09)
		(layer "In9.Cu")
		(net 210)
	)
	(segment
		(start 201.749 144.599)
		(end 201.749 144.801)
		(width 0.09)
		(layer "In9.Cu")
		(net 210)
	)
	(segment
		(start 200.769 144.631)
		(end 200.92 144.48)
		(width 0.09)
		(layer "In9.Cu")
		(net 210)
	)
	(segment
		(start 193.51 138.3)
		(end 193.67 138.46)
		(width 0.09)
		(layer "In9.Cu")
		(net 210)
	)
	(segment
		(start 195.28 140.16)
		(end 195.28 140.332549)
		(width 0.09)
		(layer "In9.Cu")
		(net 210)
	)
	(segment
		(start 198.75 141.84)
		(end 198.75 144)
		(width 0.09)
		(layer "In9.Cu")
		(net 210)
	)
	(segment
		(start 197.495 140.775)
		(end 197.69 140.97)
		(width 0.09)
		(layer "In9.Cu")
		(net 210)
	)
	(segment
		(start 194.49 139.62)
		(end 194.77 139.9)
		(width 0.09)
		(layer "In9.Cu")
		(net 210)
	)
	(segment
		(start 194.49 139.37)
		(end 194.49 139.62)
		(width 0.09)
		(layer "In9.Cu")
		(net 210)
	)
	(segment
		(start 198.331 141.421)
		(end 198.75 141.84)
		(width 0.09)
		(layer "In9.Cu")
		(net 210)
	)
	(segment
		(start 200.769 144.991)
		(end 200.769 144.631)
		(width 0.09)
		(layer "In9.Cu")
		(net 210)
	)
	(segment
		(start 206.7795 148.07188)
		(end 206.7795 148.28376)
		(width 0.1)
		(layer "F.Cu")
		(net 211)
	)
	(segment
		(start 205.649 148.051)
		(end 205.974 147.726)
		(width 0.1)
		(layer "F.Cu")
		(net 211)
	)
	(segment
		(start 206.43362 147.726)
		(end 206.7795 148.07188)
		(width 0.1)
		(layer "F.Cu")
		(net 211)
	)
	(segment
		(start 205.974 147.726)
		(end 206.43362 147.726)
		(width 0.1)
		(layer "F.Cu")
		(net 211)
	)
	(segment
		(start 207.1 148.604259)
		(end 207.1 149.24)
		(width 0.1)
		(layer "F.Cu")
		(net 211)
	)
	(segment
		(start 207.1 149.24)
		(end 207.6 149.74)
		(width 0.1)
		(layer "F.Cu")
		(net 211)
	)
	(segment
		(start 206.7795 148.28376)
		(end 207.1 148.604259)
		(width 0.1)
		(layer "F.Cu")
		(net 211)
	)
	(via
		(at 205.649 148.051)
		(size 0.35)
		(drill 0.15)
		(layers "F.Cu" "B.Cu")
		(remove_unused_layers yes)
		(keep_end_layers yes)
		(zone_layer_connections)
		(net 211)
	)
	(via
		(at 207.616 149.7365)
		(size 0.35)
		(drill 0.15)
		(layers "F.Cu" "B.Cu")
		(remove_unused_layers yes)
		(keep_end_layers yes)
		(zone_layer_connections)
		(net 211)
	)
	(segment
		(start 205.662 148.064)
		(end 205.649 148.051)
		(width 0.256)
		(layer "B.Cu")
		(net 211)
	)
	(segment
		(start 205.662 148.65)
		(end 205.662 148.064)
		(width 0.256)
		(layer "B.Cu")
		(net 211)
	)
	(segment
		(start 189.717 118.133)
		(end 189.717 117.461)
		(width 0.1)
		(layer "B.Cu")
		(net 212)
	)
	(segment
		(start 188.18 119.67)
		(end 189.717 118.133)
		(width 0.1)
		(layer "B.Cu")
		(net 212)
	)
	(segment
		(start 185.75 119.43)
		(end 184.75 119.43)
		(width 0.1)
		(layer "B.Cu")
		(net 212)
	)
	(segment
		(start 186.45 119.67)
		(end 188.18 119.67)
		(width 0.1)
		(layer "B.Cu")
		(net 212)
	)
	(segment
		(start 186.21 119.43)
		(end 186.45 119.67)
		(width 0.1)
		(layer "B.Cu")
		(net 212)
	)
	(segment
		(start 184.75 119.43)
		(end 184.75 120.37)
		(width 0.1)
		(layer "B.Cu")
		(net 212)
	)
	(segment
		(start 185.75 119.43)
		(end 186.21 119.43)
		(width 0.1)
		(layer "B.Cu")
		(net 212)
	)
	(segment
		(start 212.9435 128.95)
		(end 212.4435 129.45)
		(width 0.15)
		(layer "F.Cu")
		(net 213)
	)
	(via
		(at 212.4435 129.45)
		(size 0.35)
		(drill 0.15)
		(layers "F.Cu" "B.Cu")
		(net 213)
	)
	(via
		(at 209.77 127.34)
		(size 0.35)
		(drill 0.15)
		(layers "F.Cu" "B.Cu")
		(net 213)
	)
	(segment
		(start 210.1895 126.87)
		(end 209.7125 127.347)
		(width 0.15)
		(layer "B.Cu")
		(net 213)
	)
	(segment
		(start 208.15 124.525)
		(end 208.15 124.665)
		(width 0.15)
		(layer "B.Cu")
		(net 213)
	)
	(segment
		(start 208.35 125.275)
		(end 208.35 125.67)
		(width 0.15)
		(layer "B.Cu")
		(net 213)
	)
	(segment
		(start 208.52 124.085)
		(end 208.53 124.085)
		(width 0.15)
		(layer "B.Cu")
		(net 213)
	)
	(segment
		(start 208.708749 125.788333)
		(end 209.069374 125.427708)
		(width 0.15)
		(layer "B.Cu")
		(net 213)
	)
	(segment
		(start 208.25 124.765)
		(end 208.63 124.765)
		(width 0.15)
		(layer "B.Cu")
		(net 213)
	)
	(segment
		(start 209.7125 127.347)
		(end 209.763 127.347)
		(width 0.15)
		(layer "B.Cu")
		(net 213)
	)
	(segment
		(start 208.949167 126.269167)
		(end 208.949166 126.269166)
		(width 0.15)
		(layer "B.Cu")
		(net 213)
	)
	(segment
		(start 210.39 126.46)
		(end 210.53 126.6)
		(width 0.15)
		(layer "B.Cu")
		(net 213)
	)
	(segment
		(start 209.763 127.347)
		(end 209.77 127.34)
		(width 0.15)
		(layer "B.Cu")
		(net 213)
	)
	(segment
		(start 207.81 122.06)
		(end 207.81 123.375)
		(width 0.15)
		(layer "B.Cu")
		(net 213)
	)
	(segment
		(start 209.43 126.75)
		(end 209.58 126.75)
		(width 0.15)
		(layer "B.Cu")
		(net 213)
	)
	(segment
		(start 208.35 125.67)
		(end 208.468333 125.788333)
		(width 0.15)
		(layer "B.Cu")
		(net 213)
	)
	(segment
		(start 209.58 126.75)
		(end 209.87 126.46)
		(width 0.15)
		(layer "B.Cu")
		(net 213)
	)
	(segment
		(start 209.189582 126.269166)
		(end 209.550207 125.908541)
		(width 0.15)
		(layer "B.Cu")
		(net 213)
	)
	(segment
		(start 209.429999 126.509583)
		(end 209.790624 126.148958)
		(width 0.15)
		(layer "B.Cu")
		(net 213)
	)
	(segment
		(start 210.53 126.77)
		(end 210.43 126.87)
		(width 0.15)
		(layer "B.Cu")
		(net 213)
	)
	(segment
		(start 210.53 126.6)
		(end 210.53 126.77)
		(width 0.15)
		(layer "B.Cu")
		(net 213)
	)
	(segment
		(start 208.63 125.105)
		(end 208.52 125.105)
		(width 0.15)
		(layer "B.Cu")
		(net 213)
	)
	(segment
		(start 207.291002 121.85)
		(end 207.6 121.85)
		(width 0.15)
		(layer "B.Cu")
		(net 213)
	)
	(segment
		(start 207.81 123.375)
		(end 208.35 123.915)
		(width 0.15)
		(layer "B.Cu")
		(net 213)
	)
	(segment
		(start 210.43 126.87)
		(end 210.1895 126.87)
		(width 0.15)
		(layer "B.Cu")
		(net 213)
	)
	(segment
		(start 208.949166 126.02875)
		(end 209.309791 125.668125)
		(width 0.15)
		(layer "B.Cu")
		(net 213)
	)
	(segment
		(start 209.87 126.46)
		(end 210.39 126.46)
		(width 0.15)
		(layer "B.Cu")
		(net 213)
	)
	(segment
		(start 207.6 121.85)
		(end 207.81 122.06)
		(width 0.15)
		(layer "B.Cu")
		(net 213)
	)
	(segment
		(start 208.53 124.425)
		(end 208.25 124.425)
		(width 0.15)
		(layer "B.Cu")
		(net 213)
	)
	(arc
		(start 209.069374 125.427708)
		(mid 209.189583 125.377917)
		(end 209.309791 125.427709)
		(width 0.15)
		(layer "B.Cu")
		(net 213)
	)
	(arc
		(start 208.25 124.425)
		(mid 208.179289 124.454289)
		(end 208.15 124.525)
		(width 0.15)
		(layer "B.Cu")
		(net 213)
	)
	(arc
		(start 209.429999 126.509583)
		(mid 209.380208 126.629792)
		(end 209.43 126.75)
		(width 0.15)
		(layer "B.Cu")
		(net 213)
	)
	(arc
		(start 208.52 125.105)
		(mid 208.399792 125.154792)
		(end 208.35 125.275)
		(width 0.15)
		(layer "B.Cu")
		(net 213)
	)
	(arc
		(start 209.309791 125.427709)
		(mid 209.359583 125.547917)
		(end 209.309791 125.668125)
		(width 0.15)
		(layer "B.Cu")
		(net 213)
	)
	(arc
		(start 209.550207 125.908541)
		(mid 209.670416 125.85875)
		(end 209.790624 125.908542)
		(width 0.15)
		(layer "B.Cu")
		(net 213)
	)
	(arc
		(start 208.35 123.915)
		(mid 208.399792 124.035208)
		(end 208.52 124.085)
		(width 0.15)
		(layer "B.Cu")
		(net 213)
	)
	(arc
		(start 208.7 124.255)
		(mid 208.650208 124.375208)
		(end 208.53 124.425)
		(width 0.15)
		(layer "B.Cu")
		(net 213)
	)
	(arc
		(start 208.15 124.665)
		(mid 208.179289 124.735711)
		(end 208.25 124.765)
		(width 0.15)
		(layer "B.Cu")
		(net 213)
	)
	(arc
		(start 208.949166 126.269166)
		(mid 209.069374 126.318958)
		(end 209.189582 126.269166)
		(width 0.15)
		(layer "B.Cu")
		(net 213)
	)
	(arc
		(start 208.63 124.765)
		(mid 208.750208 124.814792)
		(end 208.8 124.935)
		(width 0.15)
		(layer "B.Cu")
		(net 213)
	)
	(arc
		(start 208.949166 126.02875)
		(mid 208.899375 126.148959)
		(end 208.949167 126.269167)
		(width 0.15)
		(layer "B.Cu")
		(net 213)
	)
	(arc
		(start 208.53 124.085)
		(mid 208.650208 124.134792)
		(end 208.7 124.255)
		(width 0.15)
		(layer "B.Cu")
		(net 213)
	)
	(arc
		(start 208.468333 125.788333)
		(mid 208.588541 125.838125)
		(end 208.708749 125.788333)
		(width 0.15)
		(layer "B.Cu")
		(net 213)
	)
	(arc
		(start 209.790624 125.908542)
		(mid 209.840416 126.02875)
		(end 209.790624 126.148958)
		(width 0.15)
		(layer "B.Cu")
		(net 213)
	)
	(arc
		(start 208.8 124.935)
		(mid 208.750208 125.055208)
		(end 208.63 125.105)
		(width 0.15)
		(layer "B.Cu")
		(net 213)
	)
	(segment
		(start 210.225003 125.804996)
		(end 210.42 125.61)
		(width 0.09)
		(layer "In2.Cu")
		(net 213)
	)
	(segment
		(start 213.48 127.478201)
		(end 213.48 127.530201)
		(width 0.09)
		(layer "In2.Cu")
		(net 213)
	)
	(segment
		(start 213.21 125.8)
		(end 213.21 126.27)
		(width 0.09)
		(layer "In2.Cu")
		(net 213)
	)
	(segment
		(start 213.886 127.374201)
		(end 213.584 127.374201)
		(width 0.09)
		(layer "In2.Cu")
		(net 213)
	)
	(segment
		(start 209.970444 126.229261)
		(end 210.225002 126.483819)
		(width 0.09)
		(layer "In2.Cu")
		(net 213)
	)
	(segment
		(start 213.48 128.32)
		(end 213.13 128.67)
		(width 0.09)
		(layer "In2.Cu")
		(net 213)
	)
	(segment
		(start 213.21 126.27)
		(end 213.48 126.54)
		(width 0.09)
		(layer "In2.Cu")
		(net 213)
	)
	(segment
		(start 210.437134 126.271686)
		(end 210.182575 126.017127)
		(width 0.09)
		(layer "In2.Cu")
		(net 213)
	)
	(segment
		(start 210.182575 125.847421)
		(end 210.225003 125.804996)
		(width 0.09)
		(layer "In2.Cu")
		(net 213)
	)
	(segment
		(start 213.48 126.54)
		(end 213.48 127.010201)
		(width 0.09)
		(layer "In2.Cu")
		(net 213)
	)
	(segment
		(start 211.06141 125.61)
		(end 213.02 125.61)
		(width 0.09)
		(layer "In2.Cu")
		(net 213)
	)
	(segment
		(start 213.02 125.61)
		(end 213.21 125.8)
		(width 0.09)
		(layer "In2.Cu")
		(net 213)
	)
	(segment
		(start 213.48 127.530201)
		(end 213.48 127.66)
		(width 0.09)
		(layer "In2.Cu")
		(net 213)
	)
	(segment
		(start 212.79 129.45)
		(end 212.4435 129.45)
		(width 0.09)
		(layer "In2.Cu")
		(net 213)
	)
	(segment
		(start 213.99 127.218201)
		(end 213.99 127.270201)
		(width 0.09)
		(layer "In2.Cu")
		(net 213)
	)
	(segment
		(start 210.394708 126.483819)
		(end 210.437134 126.441392)
		(width 0.09)
		(layer "In2.Cu")
		(net 213)
	)
	(segment
		(start 209.77 126.26)
		(end 209.800739 126.229261)
		(width 0.09)
		(layer "In2.Cu")
		(net 213)
	)
	(segment
		(start 213.13 129.11)
		(end 212.79 129.45)
		(width 0.09)
		(layer "In2.Cu")
		(net 213)
	)
	(segment
		(start 213.13 128.67)
		(end 213.13 129.11)
		(width 0.09)
		(layer "In2.Cu")
		(net 213)
	)
	(segment
		(start 210.42 125.61)
		(end 211.06141 125.61)
		(width 0.09)
		(layer "In2.Cu")
		(net 213)
	)
	(segment
		(start 213.48 127.66)
		(end 213.48 128.32)
		(width 0.09)
		(layer "In2.Cu")
		(net 213)
	)
	(segment
		(start 209.77 127.34)
		(end 209.77 126.26)
		(width 0.09)
		(layer "In2.Cu")
		(net 213)
	)
	(segment
		(start 213.584 127.114201)
		(end 213.886 127.114201)
		(width 0.09)
		(layer "In2.Cu")
		(net 213)
	)
	(arc
		(start 210.437134 126.441392)
		(mid 210.472281 126.356539)
		(end 210.437134 126.271686)
		(width 0.09)
		(layer "In2.Cu")
		(net 213)
	)
	(arc
		(start 213.99 127.270201)
		(mid 213.959539 127.34374)
		(end 213.886 127.374201)
		(width 0.09)
		(layer "In2.Cu")
		(net 213)
	)
	(arc
		(start 213.48 127.010201)
		(mid 213.510461 127.08374)
		(end 213.584 127.114201)
		(width 0.09)
		(layer "In2.Cu")
		(net 213)
	)
	(arc
		(start 213.886 127.114201)
		(mid 213.959539 127.144662)
		(end 213.99 127.218201)
		(width 0.09)
		(layer "In2.Cu")
		(net 213)
	)
	(arc
		(start 209.800739 126.229261)
		(mid 209.885591 126.194114)
		(end 209.970444 126.229261)
		(width 0.09)
		(layer "In2.Cu")
		(net 213)
	)
	(arc
		(start 210.225002 126.483819)
		(mid 210.309855 126.518966)
		(end 210.394708 126.483819)
		(width 0.09)
		(layer "In2.Cu")
		(net 213)
	)
	(arc
		(start 213.584 127.374201)
		(mid 213.510461 127.404662)
		(end 213.48 127.478201)
		(width 0.09)
		(layer "In2.Cu")
		(net 213)
	)
	(arc
		(start 210.182575 126.017127)
		(mid 210.147428 125.932274)
		(end 210.182575 125.847421)
		(width 0.09)
		(layer "In2.Cu")
		(net 213)
	)
	(segment
		(start 214.9405 128.45)
		(end 214.9405 128.0895)
		(width 0.15)
		(layer "F.Cu")
		(net 214)
	)
	(segment
		(start 214.4405 128.95)
		(end 214.9405 128.45)
		(width 0.15)
		(layer "F.Cu")
		(net 214)
	)
	(segment
		(start 213.9435 128.95)
		(end 214.4405 128.95)
		(width 0.15)
		(layer "F.Cu")
		(net 214)
	)
	(segment
		(start 214.9405 128.0895)
		(end 215.01 128.02)
		(width 0.15)
		(layer "F.Cu")
		(net 214)
	)
	(segment
		(start 215.31 128.02)
		(end 215.36 127.97)
		(width 0.15)
		(layer "F.Cu")
		(net 214)
	)
	(segment
		(start 215.01 128.02)
		(end 215.31 128.02)
		(width 0.15)
		(layer "F.Cu")
		(net 214)
	)
	(via
		(at 215.36 127.97)
		(size 0.35)
		(drill 0.15)
		(layers "F.Cu" "B.Cu")
		(net 214)
	)
	(via
		(at 209.715 128.35)
		(size 0.35)
		(drill 0.15)
		(layers "F.Cu" "B.Cu")
		(net 214)
	)
	(segment
		(start 207.287503 122.641002)
		(end 206.914009 122.641002)
		(width 0.15)
		(layer "B.Cu")
		(net 214)
	)
	(segment
		(start 207.291002 123.351002)
		(end 207.88 123.94)
		(width 0.15)
		(layer "B.Cu")
		(net 214)
	)
	(segment
		(start 208.768125 127.888125)
		(end 208.671958 127.984291)
		(width 0.15)
		(layer "B.Cu")
		(net 214)
	)
	(segment
		(start 209.23 128.35)
		(end 209.715 128.35)
		(width 0.15)
		(layer "B.Cu")
		(net 214)
	)
	(segment
		(start 208.016 126.056)
		(end 208.404 126.056)
		(width 0.15)
		(layer "B.Cu")
		(net 214)
	)
	(segment
		(start 209.161277 127.206474)
		(end 209.20936 127.254557)
		(width 0.15)
		(layer "B.Cu")
		(net 214)
	)
	(segment
		(start 206.874392 122.641832)
		(end 206.801188 122.672153)
		(width 0.15)
		(layer "B.Cu")
		(net 214)
	)
	(segment
		(start 208.708727 128.428354)
		(end 208.912373 128.224707)
		(width 0.15)
		(layer "B.Cu")
		(net 214)
	)
	(segment
		(start 208.404 126.396)
		(end 208.016 126.396)
		(width 0.15)
		(layer "B.Cu")
		(net 214)
	)
	(segment
		(start 206.914009 123.041002)
		(end 207.091002 123.041002)
		(width 0.15)
		(layer "B.Cu")
		(net 214)
	)
	(segment
		(start 207.491002 122.444501)
		(end 207.4898 122.484044)
		(width 0.15)
		(layer "B.Cu")
		(net 214)
	)
	(segment
		(start 209.72 128.35)
		(end 209.715 128.35)
		(width 0.15)
		(layer "B.Cu")
		(net 214)
	)
	(segment
		(start 207.459535 122.557111)
		(end 207.403612 122.613034)
		(width 0.15)
		(layer "B.Cu")
		(net 214)
	)
	(segment
		(start 207.88 126.971)
		(end 207.88 127)
		(width 0.15)
		(layer "B.Cu")
		(net 214)
	)
	(segment
		(start 208.155771 127.275771)
		(end 208.431542 127.551542)
		(width 0.15)
		(layer "B.Cu")
		(net 214)
	)
	(segment
		(start 207.67 126.501)
		(end 207.67 126.631)
		(width 0.15)
		(layer "B.Cu")
		(net 214)
	)
	(segment
		(start 207.203614 123.072466)
		(end 207.259537 123.12839)
		(width 0.15)
		(layer "B.Cu")
		(net 214)
	)
	(segment
		(start 207.330545 122.6433)
		(end 207.291002 122.644501)
		(width 0.15)
		(layer "B.Cu")
		(net 214)
	)
	(segment
		(start 208.864291 127.791958)
		(end 208.768125 127.888125)
		(width 0.15)
		(layer "B.Cu")
		(net 214)
	)
	(segment
		(start 208.623876 127.551543)
		(end 208.968943 127.206473)
		(width 0.15)
		(layer "B.Cu")
		(net 214)
	)
	(segment
		(start 206.801188 122.672153)
		(end 206.74516 122.728181)
		(width 0.15)
		(layer "B.Cu")
		(net 214)
	)
	(segment
		(start 206.745473 122.953614)
		(end 206.801397 123.009537)
		(width 0.15)
		(layer "B.Cu")
		(net 214)
	)
	(segment
		(start 208.468311 128.380271)
		(end 208.516394 128.428354)
		(width 0.15)
		(layer "B.Cu")
		(net 214)
	)
	(segment
		(start 207.289802 123.201458)
		(end 207.291002 123.241002)
		(width 0.15)
		(layer "B.Cu")
		(net 214)
	)
	(segment
		(start 207.88 126.841)
		(end 207.88 126.971)
		(width 0.15)
		(layer "B.Cu")
		(net 214)
	)
	(segment
		(start 209.209359 127.446889)
		(end 208.864291 127.791958)
		(width 0.15)
		(layer "B.Cu")
		(net 214)
	)
	(segment
		(start 208.54 126.192)
		(end 208.54 126.26)
		(width 0.15)
		(layer "B.Cu")
		(net 214)
	)
	(segment
		(start 207.291002 122.248)
		(end 207.388 122.248)
		(width 0.15)
		(layer "B.Cu")
		(net 214)
	)
	(segment
		(start 209.152791 128.272791)
		(end 209.215 128.335)
		(width 0.15)
		(layer "B.Cu")
		(net 214)
	)
	(segment
		(start 207.388 122.248)
		(end 207.491002 122.351002)
		(width 0.15)
		(layer "B.Cu")
		(net 214)
	)
	(segment
		(start 207.88 123.94)
		(end 207.88 125.92)
		(width 0.15)
		(layer "B.Cu")
		(net 214)
	)
	(segment
		(start 207.403612 122.613034)
		(end 207.330545 122.6433)
		(width 0.15)
		(layer "B.Cu")
		(net 214)
	)
	(segment
		(start 207.491002 122.351002)
		(end 207.491002 122.444501)
		(width 0.15)
		(layer "B.Cu")
		(net 214)
	)
	(segment
		(start 207.259537 123.12839)
		(end 207.289802 123.201458)
		(width 0.15)
		(layer "B.Cu")
		(net 214)
	)
	(segment
		(start 207.130546 123.042199)
		(end 207.203614 123.072466)
		(width 0.15)
		(layer "B.Cu")
		(net 214)
	)
	(segment
		(start 207.091002 123.041002)
		(end 207.130546 123.042199)
		(width 0.15)
		(layer "B.Cu")
		(net 214)
	)
	(segment
		(start 209.215 128.335)
		(end 209.23 128.35)
		(width 0.15)
		(layer "B.Cu")
		(net 214)
	)
	(segment
		(start 206.801397 123.009537)
		(end 206.874465 123.039802)
		(width 0.15)
		(layer "B.Cu")
		(net 214)
	)
	(segment
		(start 207.291002 123.241002)
		(end 207.291002 123.351002)
		(width 0.15)
		(layer "B.Cu")
		(net 214)
	)
	(segment
		(start 207.88 126.396)
		(end 207.775 126.396)
		(width 0.15)
		(layer "B.Cu")
		(net 214)
	)
	(segment
		(start 209.104706 128.224707)
		(end 209.152791 128.272791)
		(width 0.15)
		(layer "B.Cu")
		(net 214)
	)
	(segment
		(start 206.714839 122.801385)
		(end 206.714009 122.841002)
		(width 0.15)
		(layer "B.Cu")
		(net 214)
	)
	(segment
		(start 207.4898 122.484044)
		(end 207.459535 122.557111)
		(width 0.15)
		(layer "B.Cu")
		(net 214)
	)
	(segment
		(start 207.291002 122.644501)
		(end 207.287503 122.641002)
		(width 0.15)
		(layer "B.Cu")
		(net 214)
	)
	(segment
		(start 207.88 127)
		(end 208.155771 127.275771)
		(width 0.15)
		(layer "B.Cu")
		(net 214)
	)
	(segment
		(start 206.714009 122.841002)
		(end 206.715206 122.880546)
		(width 0.15)
		(layer "B.Cu")
		(net 214)
	)
	(segment
		(start 208.671958 127.984291)
		(end 208.468311 128.187938)
		(width 0.15)
		(layer "B.Cu")
		(net 214)
	)
	(segment
		(start 206.74516 122.728181)
		(end 206.714839 122.801385)
		(width 0.15)
		(layer "B.Cu")
		(net 214)
	)
	(segment
		(start 206.874465 123.039802)
		(end 206.914009 123.041002)
		(width 0.15)
		(layer "B.Cu")
		(net 214)
	)
	(segment
		(start 206.914009 122.641002)
		(end 206.874392 122.641832)
		(width 0.15)
		(layer "B.Cu")
		(net 214)
	)
	(segment
		(start 206.715206 122.880546)
		(end 206.745473 122.953614)
		(width 0.15)
		(layer "B.Cu")
		(net 214)
	)
	(segment
		(start 208.016 126.396)
		(end 207.88 126.396)
		(width 0.15)
		(layer "B.Cu")
		(net 214)
	)
	(arc
		(start 208.516394 128.428354)
		(mid 208.612561 128.468187)
		(end 208.708727 128.428354)
		(width 0.15)
		(layer "B.Cu")
		(net 214)
	)
	(arc
		(start 208.431542 127.551542)
		(mid 208.527709 127.591375)
		(end 208.623876 127.551543)
		(width 0.15)
		(layer "B.Cu")
		(net 214)
	)
	(arc
		(start 207.67 126.631)
		(mid 207.700754 126.705246)
		(end 207.775 126.736)
		(width 0.15)
		(layer "B.Cu")
		(net 214)
	)
	(arc
		(start 207.88 125.92)
		(mid 207.919833 126.016167)
		(end 208.016 126.056)
		(width 0.15)
		(layer "B.Cu")
		(net 214)
	)
	(arc
		(start 208.912373 128.224707)
		(mid 209.008539 128.184874)
		(end 209.104706 128.224707)
		(width 0.15)
		(layer "B.Cu")
		(net 214)
	)
	(arc
		(start 208.404 126.056)
		(mid 208.500167 126.095833)
		(end 208.54 126.192)
		(width 0.15)
		(layer "B.Cu")
		(net 214)
	)
	(arc
		(start 208.54 126.26)
		(mid 208.500167 126.356167)
		(end 208.404 126.396)
		(width 0.15)
		(layer "B.Cu")
		(net 214)
	)
	(arc
		(start 208.968943 127.206473)
		(mid 209.06511 127.166641)
		(end 209.161277 127.206474)
		(width 0.15)
		(layer "B.Cu")
		(net 214)
	)
	(arc
		(start 207.775 126.396)
		(mid 207.700754 126.426754)
		(end 207.67 126.501)
		(width 0.15)
		(layer "B.Cu")
		(net 214)
	)
	(arc
		(start 209.20936 127.254557)
		(mid 209.249193 127.350724)
		(end 209.209359 127.446889)
		(width 0.15)
		(layer "B.Cu")
		(net 214)
	)
	(arc
		(start 207.775 126.736)
		(mid 207.849246 126.766754)
		(end 207.88 126.841)
		(width 0.15)
		(layer "B.Cu")
		(net 214)
	)
	(arc
		(start 208.468311 128.187938)
		(mid 208.428478 128.284104)
		(end 208.468311 128.380271)
		(width 0.15)
		(layer "B.Cu")
		(net 214)
	)
	(segment
		(start 214.65 127.26)
		(end 213.54 126.15)
		(width 0.09)
		(layer "In2.Cu")
		(net 214)
	)
	(segment
		(start 210.18 125.34)
		(end 209.41 126.11)
		(width 0.09)
		(layer "In2.Cu")
		(net 214)
	)
	(segment
		(start 213.54 126.15)
		(end 213.54 125.7)
		(width 0.09)
		(layer "In2.Cu")
		(net 214)
	)
	(segment
		(start 209.41 128.045)
		(end 209.715 128.35)
		(width 0.09)
		(layer "In2.Cu")
		(net 214)
	)
	(segment
		(start 213.54 125.7)
		(end 213.18 125.34)
		(width 0.09)
		(layer "In2.Cu")
		(net 214)
	)
	(segment
		(start 213.18 125.34)
		(end 210.18 125.34)
		(width 0.09)
		(layer "In2.Cu")
		(net 214)
	)
	(segment
		(start 209.41 126.11)
		(end 209.41 128.045)
		(width 0.09)
		(layer "In2.Cu")
		(net 214)
	)
	(segment
		(start 214.87 127.97)
		(end 214.65 127.75)
		(width 0.09)
		(layer "In2.Cu")
		(net 214)
	)
	(segment
		(start 214.65 127.75)
		(end 214.65 127.26)
		(width 0.09)
		(layer "In2.Cu")
		(net 214)
	)
	(segment
		(start 215.36 127.97)
		(end 214.87 127.97)
		(width 0.09)
		(layer "In2.Cu")
		(net 214)
	)
	(segment
		(start 206.174059 122.129057)
		(end 205.893002 121.848)
		(width 0.15)
		(layer "F.Cu")
		(net 215)
	)
	(segment
		(start 206.205 122.129057)
		(end 206.174059 122.129057)
		(width 0.15)
		(layer "F.Cu")
		(net 215)
	)
	(via
		(at 206.205 122.129057)
		(size 0.35)
		(drill 0.15)
		(layers "F.Cu" "B.Cu")
		(remove_unused_layers yes)
		(keep_end_layers yes)
		(zone_layer_connections)
		(net 215)
	)
	(via
		(at 200.499 125.101)
		(size 0.35)
		(drill 0.15)
		(layers "F.Cu" "B.Cu")
		(remove_unused_layers yes)
		(keep_end_layers yes)
		(zone_layer_connections)
		(net 215)
	)
	(segment
		(start 206.323943 122.248)
		(end 206.693002 122.248)
		(width 0.15)
		(layer "B.Cu")
		(net 215)
	)
	(segment
		(start 206.205 122.129057)
		(end 206.323943 122.248)
		(width 0.15)
		(layer "B.Cu")
		(net 215)
	)
	(segment
		(start 206.017028 122.317029)
		(end 206.205 122.129057)
		(width 0.09)
		(layer "In4.Cu")
		(net 215)
	)
	(segment
		(start 203.295 122.8)
		(end 203.295 123.07)
		(width 0.09)
		(layer "In4.Cu")
		(net 215)
	)
	(segment
		(start 200.499 125.101)
		(end 200.499 124.891)
		(width 0.09)
		(layer "In4.Cu")
		(net 215)
	)
	(segment
		(start 205.804895 122.317029)
		(end 205.804894 122.317029)
		(width 0.09)
		(layer "In4.Cu")
		(net 215)
	)
	(segment
		(start 205.168497 122.953425)
		(end 204.991721 122.776649)
		(width 0.09)
		(layer "In4.Cu")
		(net 215)
	)
	(segment
		(start 202.915 123.07)
		(end 202.915 122.8)
		(width 0.09)
		(layer "In4.Cu")
		(net 215)
	)
	(segment
		(start 200.85 123.875)
		(end 201.465 123.26)
		(width 0.09)
		(layer "In4.Cu")
		(net 215)
	)
	(segment
		(start 200.499 124.891)
		(end 200.85 124.54)
		(width 0.09)
		(layer "In4.Cu")
		(net 215)
	)
	(segment
		(start 205.38063 122.741294)
		(end 205.380629 122.741294)
		(width 0.09)
		(layer "In4.Cu")
		(net 215)
	)
	(segment
		(start 205.203853 122.564517)
		(end 205.38063 122.741294)
		(width 0.09)
		(layer "In4.Cu")
		(net 215)
	)
	(segment
		(start 203.485 123.26)
		(end 204.1 123.26)
		(width 0.09)
		(layer "In4.Cu")
		(net 215)
	)
	(segment
		(start 205.074057 123.26)
		(end 205.168497 123.165557)
		(width 0.09)
		(layer "In4.Cu")
		(net 215)
	)
	(segment
		(start 205.592762 122.52916)
		(end 205.415986 122.352384)
		(width 0.09)
		(layer "In4.Cu")
		(net 215)
	)
	(segment
		(start 205.592763 122.741294)
		(end 205.592762 122.741292)
		(width 0.09)
		(layer "In4.Cu")
		(net 215)
	)
	(segment
		(start 201.465 123.26)
		(end 202.725 123.26)
		(width 0.09)
		(layer "In4.Cu")
		(net 215)
	)
	(segment
		(start 204.7 123.26)
		(end 205.074057 123.26)
		(width 0.09)
		(layer "In4.Cu")
		(net 215)
	)
	(segment
		(start 205.628118 122.140252)
		(end 205.804895 122.317029)
		(width 0.09)
		(layer "In4.Cu")
		(net 215)
	)
	(segment
		(start 204.25 123.11)
		(end 204.25 120.41)
		(width 0.09)
		(layer "In4.Cu")
		(net 215)
	)
	(segment
		(start 200.85 124.54)
		(end 200.85 123.875)
		(width 0.09)
		(layer "In4.Cu")
		(net 215)
	)
	(segment
		(start 204.55 122.375)
		(end 204.55 123.11)
		(width 0.09)
		(layer "In4.Cu")
		(net 215)
	)
	(segment
		(start 204.55 120.41)
		(end 204.55 121.675)
		(width 0.09)
		(layer "In4.Cu")
		(net 215)
	)
	(arc
		(start 205.380629 122.741294)
		(mid 205.486696 122.785228)
		(end 205.592763 122.741294)
		(width 0.09)
		(layer "In4.Cu")
		(net 215)
	)
	(arc
		(start 204.9 122.025)
		(mid 204.848744 122.148744)
		(end 204.725 122.2)
		(width 0.09)
		(layer "In4.Cu")
		(net 215)
	)
	(arc
		(start 204.1 123.26)
		(mid 204.206066 123.216066)
		(end 204.25 123.11)
		(width 0.09)
		(layer "In4.Cu")
		(net 215)
	)
	(arc
		(start 203.295 123.07)
		(mid 203.35065 123.20435)
		(end 203.485 123.26)
		(width 0.09)
		(layer "In4.Cu")
		(net 215)
	)
	(arc
		(start 205.804894 122.317029)
		(mid 205.910961 122.360963)
		(end 206.017028 122.317029)
		(width 0.09)
		(layer "In4.Cu")
		(net 215)
	)
	(arc
		(start 205.592762 122.741292)
		(mid 205.636696 122.635226)
		(end 205.592762 122.52916)
		(width 0.09)
		(layer "In4.Cu")
		(net 215)
	)
	(arc
		(start 204.725 122.2)
		(mid 204.601256 122.251256)
		(end 204.55 122.375)
		(width 0.09)
		(layer "In4.Cu")
		(net 215)
	)
	(arc
		(start 204.991721 122.564517)
		(mid 205.097787 122.520583)
		(end 205.203853 122.564517)
		(width 0.09)
		(layer "In4.Cu")
		(net 215)
	)
	(arc
		(start 205.415986 122.140252)
		(mid 205.522052 122.096318)
		(end 205.628118 122.140252)
		(width 0.09)
		(layer "In4.Cu")
		(net 215)
	)
	(arc
		(start 202.915 122.8)
		(mid 202.97065 122.66565)
		(end 203.105 122.61)
		(width 0.09)
		(layer "In4.Cu")
		(net 215)
	)
	(arc
		(start 205.415986 122.352384)
		(mid 205.372052 122.246318)
		(end 205.415986 122.140252)
		(width 0.09)
		(layer "In4.Cu")
		(net 215)
	)
	(arc
		(start 204.25 120.41)
		(mid 204.293934 120.303934)
		(end 204.4 120.26)
		(width 0.09)
		(layer "In4.Cu")
		(net 215)
	)
	(arc
		(start 204.4 120.26)
		(mid 204.506066 120.303934)
		(end 204.55 120.41)
		(width 0.09)
		(layer "In4.Cu")
		(net 215)
	)
	(arc
		(start 204.991721 122.776649)
		(mid 204.947787 122.670583)
		(end 204.991721 122.564517)
		(width 0.09)
		(layer "In4.Cu")
		(net 215)
	)
	(arc
		(start 204.725 121.85)
		(mid 204.848744 121.901256)
		(end 204.9 122.025)
		(width 0.09)
		(layer "In4.Cu")
		(net 215)
	)
	(arc
		(start 202.725 123.26)
		(mid 202.85935 123.20435)
		(end 202.915 123.07)
		(width 0.09)
		(layer "In4.Cu")
		(net 215)
	)
	(arc
		(start 203.105 122.61)
		(mid 203.23935 122.66565)
		(end 203.295 122.8)
		(width 0.09)
		(layer "In4.Cu")
		(net 215)
	)
	(arc
		(start 204.55 123.11)
		(mid 204.593934 123.216066)
		(end 204.7 123.26)
		(width 0.09)
		(layer "In4.Cu")
		(net 215)
	)
	(arc
		(start 205.168497 123.165557)
		(mid 205.212431 123.059491)
		(end 205.168497 122.953425)
		(width 0.09)
		(layer "In4.Cu")
		(net 215)
	)
	(arc
		(start 204.55 121.675)
		(mid 204.601256 121.798744)
		(end 204.725 121.85)
		(width 0.09)
		(layer "In4.Cu")
		(net 215)
	)
	(segment
		(start 206.79 121.83)
		(end 206.41 121.45)
		(width 0.15)
		(layer "F.Cu")
		(net 216)
	)
	(segment
		(start 206.41 121.45)
		(end 205.893002 121.45)
		(width 0.15)
		(layer "F.Cu")
		(net 216)
	)
	(via
		(at 200.499 128.3)
		(size 0.35)
		(drill 0.15)
		(layers "F.Cu" "B.Cu")
		(remove_unused_layers yes)
		(keep_end_layers yes)
		(zone_layer_connections)
		(net 216)
	)
	(via
		(at 206.79 121.83)
		(size 0.35)
		(drill 0.15)
		(layers "F.Cu" "B.Cu")
		(remove_unused_layers yes)
		(keep_end_layers yes)
		(zone_layer_connections)
		(net 216)
	)
	(segment
		(start 202.74 123.85)
		(end 202.59 124)
		(width 0.09)
		(layer "In4.Cu")
		(net 216)
	)
	(segment
		(start 206.79 121.83)
		(end 206.79 121.235)
		(width 0.09)
		(layer "In4.Cu")
		(net 216)
	)
	(segment
		(start 202.59 124)
		(end 202.59 124.3)
		(width 0.09)
		(layer "In4.Cu")
		(net 216)
	)
	(segment
		(start 202.099 124.791)
		(end 201.694 124.791)
		(width 0.09)
		(layer "In4.Cu")
		(net 216)
	)
	(segment
		(start 207.175 121.15)
		(end 207.25 121.225)
		(width 0.09)
		(layer "In4.Cu")
		(net 216)
	)
	(segment
		(start 201.28462 127.975)
		(end 200.824 127.975)
		(width 0.09)
		(layer "In4.Cu")
		(net 216)
	)
	(segment
		(start 201.625 127.63462)
		(end 201.28462 127.975)
		(width 0.09)
		(layer "In4.Cu")
		(net 216)
	)
	(segment
		(start 207.25 121.225)
		(end 207.25 122.325)
		(width 0.09)
		(layer "In4.Cu")
		(net 216)
	)
	(segment
		(start 202.59 124.3)
		(end 202.099 124.791)
		(width 0.09)
		(layer "In4.Cu")
		(net 216)
	)
	(segment
		(start 200.824 127.975)
		(end 200.499 128.3)
		(width 0.09)
		(layer "In4.Cu")
		(net 216)
	)
	(segment
		(start 205.725 123.85)
		(end 202.74 123.85)
		(width 0.09)
		(layer "In4.Cu")
		(net 216)
	)
	(segment
		(start 201.625 124.86)
		(end 201.625 127.63462)
		(width 0.09)
		(layer "In4.Cu")
		(net 216)
	)
	(segment
		(start 201.694 124.791)
		(end 201.625 124.86)
		(width 0.09)
		(layer "In4.Cu")
		(net 216)
	)
	(segment
		(start 206.875 121.15)
		(end 207.175 121.15)
		(width 0.09)
		(layer "In4.Cu")
		(net 216)
	)
	(segment
		(start 206.79 121.235)
		(end 206.875 121.15)
		(width 0.09)
		(layer "In4.Cu")
		(net 216)
	)
	(segment
		(start 207.25 122.325)
		(end 205.725 123.85)
		(width 0.09)
		(layer "In4.Cu")
		(net 216)
	)
	(segment
		(start 217.55 124.474)
		(end 217.55 123.875)
		(width 0.174)
		(layer "F.Cu")
		(net 217)
	)
	(segment
		(start 217.569936 124.493936)
		(end 217.55 124.474)
		(width 0.174)
		(layer "F.Cu")
		(net 217)
	)
	(segment
		(start 217.569936 124.500661)
		(end 217.569936 124.493936)
		(width 0.174)
		(layer "F.Cu")
		(net 217)
	)
	(via
		(at 217.569936 124.500661)
		(size 0.35)
		(drill 0.15)
		(layers "F.Cu" "B.Cu")
		(remove_unused_layers yes)
		(keep_end_layers yes)
		(zone_layer_connections)
		(net 217)
	)
	(via
		(at 224.7 123)
		(size 0.35)
		(drill 0.15)
		(layers "F.Cu" "B.Cu")
		(remove_unused_layers yes)
		(keep_end_layers yes)
		(zone_layer_connections)
		(net 217)
	)
	(segment
		(start 217.569936 124.500661)
		(end 218.214339 124.500661)
		(width 0.174)
		(layer "B.Cu")
		(net 217)
	)
	(segment
		(start 218.361 124.354)
		(end 218.361 123.739)
		(width 0.174)
		(layer "B.Cu")
		(net 217)
	)
	(segment
		(start 218.214339 124.500661)
		(end 218.361 124.354)
		(width 0.174)
		(layer "B.Cu")
		(net 217)
	)
	(segment
		(start 224.7 123)
		(end 223.4 123)
		(width 0.09)
		(layer "In9.Cu")
		(net 217)
	)
	(segment
		(start 218.026597 124.044)
		(end 217.569936 124.500661)
		(width 0.09)
		(layer "In9.Cu")
		(net 217)
	)
	(segment
		(start 223.4 123)
		(end 222.356 124.044)
		(width 0.09)
		(layer "In9.Cu")
		(net 217)
	)
	(segment
		(start 222.356 124.044)
		(end 218.026597 124.044)
		(width 0.09)
		(layer "In9.Cu")
		(net 217)
	)
	(segment
		(start 189.717001 153.532999)
		(end 189.717001 154.9)
		(width 0.1)
		(layer "F.Cu")
		(net 218)
	)
	(segment
		(start 193.849246 150.44)
		(end 193.580006 150.44)
		(width 0.1)
		(layer "F.Cu")
		(net 218)
	)
	(segment
		(start 196.19 148.4)
		(end 196.19 148.5775)
		(width 0.1)
		(layer "F.Cu")
		(net 218)
	)
	(segment
		(start 190.1 151.85)
		(end 189.8 152.15)
		(width 0.1)
		(layer "F.Cu")
		(net 218)
	)
	(segment
		(start 193.15 150.3)
		(end 192.375 151.075)
		(width 0.1)
		(layer "F.Cu")
		(net 218)
	)
	(segment
		(start 195.975 150.275)
		(end 194.014246 150.275)
		(width 0.1)
		(layer "F.Cu")
		(net 218)
	)
	(segment
		(start 190.1 151.48238)
		(end 190.1 151.85)
		(width 0.1)
		(layer "F.Cu")
		(net 218)
	)
	(segment
		(start 189.8 153.45)
		(end 189.717001 153.532999)
		(width 0.1)
		(layer "F.Cu")
		(net 218)
	)
	(segment
		(start 196.6 149.65)
		(end 195.975 150.275)
		(width 0.1)
		(layer "F.Cu")
		(net 218)
	)
	(segment
		(start 189.8 152.15)
		(end 189.8 153.45)
		(width 0.1)
		(layer "F.Cu")
		(net 218)
	)
	(segment
		(start 194.014246 150.275)
		(end 193.849246 150.44)
		(width 0.1)
		(layer "F.Cu")
		(net 218)
	)
	(segment
		(start 196.19 148.5775)
		(end 196.6 148.9875)
		(width 0.1)
		(layer "F.Cu")
		(net 218)
	)
	(segment
		(start 193.580006 150.44)
		(end 193.440006 150.3)
		(width 0.1)
		(layer "F.Cu")
		(net 218)
	)
	(segment
		(start 196.6 148.9875)
		(end 196.6 149.65)
		(width 0.1)
		(layer "F.Cu")
		(net 218)
	)
	(segment
		(start 192.375 151.075)
		(end 190.50738 151.075)
		(width 0.1)
		(layer "F.Cu")
		(net 218)
	)
	(segment
		(start 193.440006 150.3)
		(end 193.15 150.3)
		(width 0.1)
		(layer "F.Cu")
		(net 218)
	)
	(segment
		(start 190.50738 151.075)
		(end 190.1 151.48238)
		(width 0.1)
		(layer "F.Cu")
		(net 218)
	)
	(via
		(at 189.717001 154.9)
		(size 0.35)
		(drill 0.15)
		(layers "F.Cu" "B.Cu")
		(remove_unused_layers yes)
		(keep_end_layers yes)
		(zone_layer_connections)
		(net 218)
	)
	(segment
		(start 189.301 153.325)
		(end 189.717 153.741)
		(width 0.1)
		(layer "B.Cu")
		(net 218)
	)
	(segment
		(start 188.95 153.325)
		(end 189.301 153.325)
		(width 0.1)
		(layer "B.Cu")
		(net 218)
	)
	(segment
		(start 189.717001 154.9)
		(end 189.717 154.171)
		(width 0.15)
		(layer "B.Cu")
		(net 218)
	)
	(segment
		(start 189.717 153.741)
		(end 189.717 154.171)
		(width 0.1)
		(layer "B.Cu")
		(net 218)
	)
	(segment
		(start 188.335 153.94)
		(end 188.95 153.325)
		(width 0.1)
		(layer "B.Cu")
		(net 218)
	)
	(segment
		(start 187.875 153.94)
		(end 188.335 153.94)
		(width 0.1)
		(layer "B.Cu")
		(net 218)
	)
	(segment
		(start 219.3765 147.401972)
		(end 219.3765 147.792)
		(width 0.174)
		(layer "F.Cu")
		(net 220)
	)
	(segment
		(start 219.3765 147.792)
		(end 219.4015 147.817)
		(width 0.174)
		(layer "F.Cu")
		(net 220)
	)
	(via
		(at 219.3765 147.401972)
		(size 0.35)
		(drill 0.15)
		(layers "F.Cu" "B.Cu")
		(remove_unused_layers yes)
		(keep_end_layers yes)
		(zone_layer_connections)
		(net 220)
	)
	(segment
		(start 219.833472 146.945)
		(end 219.3765 147.401972)
		(width 0.4)
		(layer "B.Cu")
		(net 220)
	)
	(segment
		(start 219.9 146.945)
		(end 219.833472 146.945)
		(width 0.4)
		(layer "B.Cu")
		(net 220)
	)
	(segment
		(start 213.125 140.125)
		(end 212.975 140.275)
		(width 0.1)
		(layer "F.Cu")
		(net 221)
	)
	(segment
		(start 212.4 140.275)
		(end 212.25 140.425)
		(width 0.1)
		(layer "F.Cu")
		(net 221)
	)
	(segment
		(start 197.322486 117.687335)
		(end 197.322486 117.727514)
		(width 0.1)
		(layer "F.Cu")
		(net 221)
	)
	(segment
		(start 213.695 139.2)
		(end 213.125 139.77)
		(width 0.1)
		(layer "F.Cu")
		(net 221)
	)
	(segment
		(start 197.322486 117.727514)
		(end 196.95 118.1)
		(width 0.1)
		(layer "F.Cu")
		(net 221)
	)
	(segment
		(start 212.975 140.275)
		(end 212.4 140.275)
		(width 0.1)
		(layer "F.Cu")
		(net 221)
	)
	(segment
		(start 213.125 139.77)
		(end 213.125 140.125)
		(width 0.1)
		(layer "F.Cu")
		(net 221)
	)
	(via
		(at 213.7 139.2)
		(size 0.35)
		(drill 0.15)
		(layers "F.Cu" "B.Cu")
		(remove_unused_layers yes)
		(keep_end_layers yes)
		(zone_layer_connections)
		(net 221)
	)
	(via
		(at 214.115 144.7505)
		(size 0.35)
		(drill 0.15)
		(layers "F.Cu" "B.Cu")
		(remove_unused_layers yes)
		(keep_end_layers yes)
		(zone_layer_connections)
		(net 221)
	)
	(via
		(at 196.95 118.1)
		(size 0.35)
		(drill 0.15)
		(layers "F.Cu" "B.Cu")
		(remove_unused_layers yes)
		(keep_end_layers yes)
		(zone_layer_connections)
		(net 221)
	)
	(segment
		(start 207.5 121.05)
		(end 206.1865 119.7365)
		(width 0.125)
		(layer "In4.Cu")
		(net 221)
	)
	(segment
		(start 214.115 144.635)
		(end 214.115 144.7505)
		(width 0.09)
		(layer "In4.Cu")
		(net 221)
	)
	(segment
		(start 212.75 125.8)
		(end 210.075 125.8)
		(width 0.125)
		(layer "In4.Cu")
		(net 221)
	)
	(segment
		(start 215.25 135.225)
		(end 215.25 134.5)
		(width 0.125)
		(layer "In4.Cu")
		(net 221)
	)
	(segment
		(start 217.25 143.5)
		(end 216.5 144.25)
		(width 0.09)
		(layer "In4.Cu")
		(net 221)
	)
	(segment
		(start 216 141.69038)
		(end 217.25 142.94038)
		(width 0.09)
		(layer "In4.Cu")
		(net 221)
	)
	(segment
		(start 214.525 132.008798)
		(end 214.281 131.764798)
		(width 0.125)
		(layer "In4.Cu")
		(net 221)
	)
	(segment
		(start 213.94 139.44)
		(end 213.94 140.24)
		(width 0.09)
		(layer "In4.Cu")
		(net 221)
	)
	(segment
		(start 197.4565 119.7365)
		(end 196.95 119.23)
		(width 0.125)
		(layer "In4.Cu")
		(net 221)
	)
	(segment
		(start 214.281 131.764798)
		(end 214.281 128.981)
		(width 0.125)
		(layer "In4.Cu")
		(net 221)
	)
	(segment
		(start 214.775 141.075)
		(end 215.546259 141.075)
		(width 0.09)
		(layer "In4.Cu")
		(net 221)
	)
	(segment
		(start 216.5 144.25)
		(end 214.5 144.25)
		(width 0.09)
		(layer "In4.Cu")
		(net 221)
	)
	(segment
		(start 216 141.528741)
		(end 216 141.69038)
		(width 0.09)
		(layer "In4.Cu")
		(net 221)
	)
	(segment
		(start 214.5 144.25)
		(end 214.115 144.635)
		(width 0.09)
		(layer "In4.Cu")
		(net 221)
	)
	(segment
		(start 210.075 125.8)
		(end 207.5 123.225)
		(width 0.125)
		(layer "In4.Cu")
		(net 221)
	)
	(segment
		(start 217.25 142.94038)
		(end 217.25 143.5)
		(width 0.09)
		(layer "In4.Cu")
		(net 221)
	)
	(segment
		(start 213.25 126.3)
		(end 212.75 125.8)
		(width 0.125)
		(layer "In4.Cu")
		(net 221)
	)
	(segment
		(start 214.525 133.775)
		(end 214.525 132.008798)
		(width 0.125)
		(layer "In4.Cu")
		(net 221)
	)
	(segment
		(start 196.95 119.23)
		(end 196.95 118.1)
		(width 0.125)
		(layer "In4.Cu")
		(net 221)
	)
	(segment
		(start 213.7 139.2)
		(end 213.94 139.44)
		(width 0.09)
		(layer "In4.Cu")
		(net 221)
	)
	(segment
		(start 217.8 137.775)
		(end 215.25 135.225)
		(width 0.125)
		(layer "In4.Cu")
		(net 221)
	)
	(segment
		(start 217.25 142.94038)
		(end 217.8 142.39038)
		(width 0.125)
		(layer "In4.Cu")
		(net 221)
	)
	(segment
		(start 213.94 140.24)
		(end 214.775 141.075)
		(width 0.09)
		(layer "In4.Cu")
		(net 221)
	)
	(segment
		(start 213.25 127.95)
		(end 213.25 126.3)
		(width 0.125)
		(layer "In4.Cu")
		(net 221)
	)
	(segment
		(start 217.8 142.39038)
		(end 217.8 137.775)
		(width 0.125)
		(layer "In4.Cu")
		(net 221)
	)
	(segment
		(start 207.5 123.225)
		(end 207.5 121.05)
		(width 0.125)
		(layer "In4.Cu")
		(net 221)
	)
	(segment
		(start 206.1865 119.7365)
		(end 197.4565 119.7365)
		(width 0.125)
		(layer "In4.Cu")
		(net 221)
	)
	(segment
		(start 215.25 134.5)
		(end 214.525 133.775)
		(width 0.125)
		(layer "In4.Cu")
		(net 221)
	)
	(segment
		(start 214.281 128.981)
		(end 213.25 127.95)
		(width 0.125)
		(layer "In4.Cu")
		(net 221)
	)
	(segment
		(start 215.546259 141.075)
		(end 216 141.528741)
		(width 0.09)
		(layer "In4.Cu")
		(net 221)
	)
	(segment
		(start 220.38 116.86)
		(end 220.38 117.545)
		(width 0.15)
		(layer "F.Cu")
		(net 222)
	)
	(segment
		(start 220.38 117.545)
		(end 220.275 117.65)
		(width 0.15)
		(layer "F.Cu")
		(net 222)
	)
	(via
		(at 220.38 116.86)
		(size 0.35)
		(drill 0.15)
		(layers "F.Cu" "B.Cu")
		(remove_unused_layers yes)
		(keep_end_layers yes)
		(zone_layer_connections)
		(net 222)
	)
	(via
		(at 189.299 140.3)
		(size 0.35)
		(drill 0.15)
		(layers "F.Cu" "B.Cu")
		(remove_unused_layers yes)
		(keep_end_layers yes)
		(zone_layer_connections)
		(net 223)
	)
	(via
		(at 200.449 146.101)
		(size 0.35)
		(drill 0.15)
		(layers "F.Cu" "B.Cu")
		(remove_unused_layers yes)
		(keep_end_layers yes)
		(zone_layer_connections)
		(net 223)
	)
	(segment
		(start 199.471 146.101)
		(end 197.82 144.45)
		(width 0.09)
		(layer "In9.Cu")
		(net 223)
	)
	(segment
		(start 193.41 141.639)
		(end 193.779 141.27)
		(width 0.09)
		(layer "In9.Cu")
		(net 223)
	)
	(segment
		(start 189.64 139.959)
		(end 189.64 140.66)
		(width 0.09)
		(layer "In9.Cu")
		(net 223)
	)
	(segment
		(start 193.8 142.97)
		(end 193.41 142.58)
		(width 0.09)
		(layer "In9.Cu")
		(net 223)
	)
	(segment
		(start 193.559 140.76)
		(end 193.306451 140.76)
		(width 0.09)
		(layer "In9.Cu")
		(net 223)
	)
	(segment
		(start 197.82 144.45)
		(end 197.82 143.36)
		(width 0.09)
		(layer "In9.Cu")
		(net 223)
	)
	(segment
		(start 193.779 141.27)
		(end 193.779 140.98)
		(width 0.09)
		(layer "In9.Cu")
		(net 223)
	)
	(segment
		(start 193.779 140.98)
		(end 193.559 140.76)
		(width 0.09)
		(layer "In9.Cu")
		(net 223)
	)
	(segment
		(start 197.16 142.7)
		(end 197.16 142.33)
		(width 0.09)
		(layer "In9.Cu")
		(net 223)
	)
	(segment
		(start 196.05 141.97)
		(end 195.78 142.24)
		(width 0.09)
		(layer "In9.Cu")
		(net 223)
	)
	(segment
		(start 195.78 142.81)
		(end 195.62 142.97)
		(width 0.09)
		(layer "In9.Cu")
		(net 223)
	)
	(segment
		(start 195.78 142.24)
		(end 195.78 142.81)
		(width 0.09)
		(layer "In9.Cu")
		(net 223)
	)
	(segment
		(start 189.699 139.9)
		(end 189.64 139.959)
		(width 0.09)
		(layer "In9.Cu")
		(net 223)
	)
	(segment
		(start 189.299 140.629)
		(end 189.299 140.3)
		(width 0.09)
		(layer "In9.Cu")
		(net 223)
	)
	(segment
		(start 200.449 146.101)
		(end 199.471 146.101)
		(width 0.09)
		(layer "In9.Cu")
		(net 223)
	)
	(segment
		(start 193.306451 140.76)
		(end 192.91 140.363549)
		(width 0.09)
		(layer "In9.Cu")
		(net 223)
	)
	(segment
		(start 197.82 143.36)
		(end 197.16 142.7)
		(width 0.09)
		(layer "In9.Cu")
		(net 223)
	)
	(segment
		(start 197.16 142.33)
		(end 196.8 141.97)
		(width 0.09)
		(layer "In9.Cu")
		(net 223)
	)
	(segment
		(start 193.41 142.58)
		(end 193.41 141.639)
		(width 0.09)
		(layer "In9.Cu")
		(net 223)
	)
	(segment
		(start 189.59 140.71)
		(end 189.38 140.71)
		(width 0.09)
		(layer "In9.Cu")
		(net 223)
	)
	(segment
		(start 192.76 139.9)
		(end 189.699 139.9)
		(width 0.09)
		(layer "In9.Cu")
		(net 223)
	)
	(segment
		(start 189.64 140.66)
		(end 189.59 140.71)
		(width 0.09)
		(layer "In9.Cu")
		(net 223)
	)
	(segment
		(start 189.38 140.71)
		(end 189.299 140.629)
		(width 0.09)
		(layer "In9.Cu")
		(net 223)
	)
	(segment
		(start 195.62 142.97)
		(end 193.8 142.97)
		(width 0.09)
		(layer "In9.Cu")
		(net 223)
	)
	(segment
		(start 192.91 140.05)
		(end 192.76 139.9)
		(width 0.09)
		(layer "In9.Cu")
		(net 223)
	)
	(segment
		(start 192.91 140.363549)
		(end 192.91 140.05)
		(width 0.09)
		(layer "In9.Cu")
		(net 223)
	)
	(segment
		(start 196.8 141.97)
		(end 196.05 141.97)
		(width 0.09)
		(layer "In9.Cu")
		(net 223)
	)
	(segment
		(start 206.75 136.85)
		(end 208.375 138.475)
		(width 0.1)
		(layer "F.Cu")
		(net 224)
	)
	(segment
		(start 203.3 133.5)
		(end 206.35 133.5)
		(width 0.1)
		(layer "F.Cu")
		(net 224)
	)
	(segment
		(start 220.525 139.225)
		(end 221.45 139.225)
		(width 0.1)
		(layer "F.Cu")
		(net 224)
	)
	(segment
		(start 216.375 139.775)
		(end 219.975 139.775)
		(width 0.1)
		(layer "F.Cu")
		(net 224)
	)
	(segment
		(start 219.975 139.775)
		(end 220.525 139.225)
		(width 0.1)
		(layer "F.Cu")
		(net 224)
	)
	(segment
		(start 221.675 138.525)
		(end 224.05 136.15)
		(width 0.1)
		(layer "F.Cu")
		(net 224)
	)
	(segment
		(start 202.9 133.9)
		(end 203.3 133.5)
		(width 0.1)
		(layer "F.Cu")
		(net 224)
	)
	(segment
		(start 215.075 138.475)
		(end 216.375 139.775)
		(width 0.1)
		(layer "F.Cu")
		(net 224)
	)
	(segment
		(start 221.675 139)
		(end 221.675 138.525)
		(width 0.1)
		(layer "F.Cu")
		(net 224)
	)
	(segment
		(start 221.45 139.225)
		(end 221.675 139)
		(width 0.1)
		(layer "F.Cu")
		(net 224)
	)
	(segment
		(start 206.75 133.9)
		(end 206.75 136.85)
		(width 0.1)
		(layer "F.Cu")
		(net 224)
	)
	(segment
		(start 206.35 133.5)
		(end 206.75 133.9)
		(width 0.1)
		(layer "F.Cu")
		(net 224)
	)
	(segment
		(start 208.375 138.475)
		(end 215.075 138.475)
		(width 0.1)
		(layer "F.Cu")
		(net 224)
	)
	(segment
		(start 224.05 135.35)
		(end 225.2 134.2)
		(width 0.1)
		(layer "F.Cu")
		(net 224)
	)
	(segment
		(start 224.05 136.15)
		(end 224.05 135.35)
		(width 0.1)
		(layer "F.Cu")
		(net 224)
	)
	(via
		(at 225.2 134.2)
		(size 0.35)
		(drill 0.15)
		(layers "F.Cu" "B.Cu")
		(remove_unused_layers yes)
		(keep_end_layers yes)
		(zone_layer_connections)
		(net 224)
	)
	(segment
		(start 223.05 132.09)
		(end 222.56 131.6)
		(width 0.1)
		(layer "B.Cu")
		(net 224)
	)
	(segment
		(start 222.58 130.55)
		(end 222.58 131.585)
		(width 0.15)
		(layer "B.Cu")
		(net 224)
	)
	(segment
		(start 223.05 134.15)
		(end 223.05 132.09)
		(width 0.1)
		(layer "B.Cu")
		(net 224)
	)
	(segment
		(start 222.58 131.585)
		(end 222.565 131.6)
		(width 0.15)
		(layer "B.Cu")
		(net 224)
	)
	(segment
		(start 224.875 134.525)
		(end 223.425 134.525)
		(width 0.1)
		(layer "B.Cu")
		(net 224)
	)
	(segment
		(start 225.2 134.2)
		(end 224.875 134.525)
		(width 0.1)
		(layer "B.Cu")
		(net 224)
	)
	(segment
		(start 223.425 134.525)
		(end 223.05 134.15)
		(width 0.1)
		(layer "B.Cu")
		(net 224)
	)
	(segment
		(start 220.013 142.657)
		(end 219.867 142.657)
		(width 0.09)
		(layer "F.Cu")
		(net 225)
	)
	(segment
		(start 219.681 141.619)
		(end 219.681 142.061)
		(width 0.09)
		(layer "F.Cu")
		(net 225)
	)
	(segment
		(start 220.1 142.23)
		(end 220.1 142.57)
		(width 0.09)
		(layer "F.Cu")
		(net 225)
	)
	(segment
		(start 219.867 142.657)
		(end 219.72 142.51)
		(width 0.09)
		(layer "F.Cu")
		(net 225)
	)
	(segment
		(start 220.029 142.159)
		(end 220.1 142.23)
		(width 0.09)
		(layer "F.Cu")
		(net 225)
	)
	(segment
		(start 220.0015 141.4685)
		(end 219.949 141.521)
		(width 0.09)
		(layer "F.Cu")
		(net 225)
	)
	(segment
		(start 220.0015 141.067)
		(end 220.0015 141.4685)
		(width 0.09)
		(layer "F.Cu")
		(net 225)
	)
	(segment
		(start 220.1 142.57)
		(end 220.013 142.657)
		(width 0.09)
		(layer "F.Cu")
		(net 225)
	)
	(segment
		(start 219.949 141.521)
		(end 219.779 141.521)
		(width 0.09)
		(layer "F.Cu")
		(net 225)
	)
	(segment
		(start 219.779 142.159)
		(end 220.029 142.159)
		(width 0.09)
		(layer "F.Cu")
		(net 225)
	)
	(segment
		(start 219.779 141.521)
		(end 219.681 141.619)
		(width 0.09)
		(layer "F.Cu")
		(net 225)
	)
	(segment
		(start 219.681 142.061)
		(end 219.779 142.159)
		(width 0.09)
		(layer "F.Cu")
		(net 225)
	)
	(via
		(at 219.72 142.51)
		(size 0.35)
		(drill 0.15)
		(layers "F.Cu" "B.Cu")
		(remove_unused_layers yes)
		(keep_end_layers yes)
		(zone_layer_connections)
		(net 225)
	)
	(segment
		(start 219.77 142.46)
		(end 219.77 142.37)
		(width 0.09)
		(layer "B.Cu")
		(net 225)
	)
	(segment
		(start 219.72 142.51)
		(end 219.77 142.46)
		(width 0.09)
		(layer "B.Cu")
		(net 225)
	)
	(segment
		(start 221.94 141.46)
		(end 221.8015 141.3215)
		(width 0.09)
		(layer "F.Cu")
		(net 226)
	)
	(segment
		(start 222.11 142.511284)
		(end 222.11 142)
		(width 0.09)
		(layer "F.Cu")
		(net 226)
	)
	(segment
		(start 222.27 141.59)
		(end 222.14 141.46)
		(width 0.09)
		(layer "F.Cu")
		(net 226)
	)
	(segment
		(start 222.378716 142.78)
		(end 222.11 142.511284)
		(width 0.09)
		(layer "F.Cu")
		(net 226)
	)
	(segment
		(start 222.14 141.46)
		(end 221.94 141.46)
		(width 0.09)
		(layer "F.Cu")
		(net 226)
	)
	(segment
		(start 222.11 142)
		(end 222.27 141.84)
		(width 0.09)
		(layer "F.Cu")
		(net 226)
	)
	(segment
		(start 222.41 142.78)
		(end 222.378716 142.78)
		(width 0.09)
		(layer "F.Cu")
		(net 226)
	)
	(segment
		(start 221.8015 141.3215)
		(end 221.8015 141.067)
		(width 0.09)
		(layer "F.Cu")
		(net 226)
	)
	(segment
		(start 222.27 141.84)
		(end 222.27 141.59)
		(width 0.09)
		(layer "F.Cu")
		(net 226)
	)
	(via
		(at 222.41 142.78)
		(size 0.35)
		(drill 0.15)
		(layers "F.Cu" "B.Cu")
		(remove_unused_layers yes)
		(keep_end_layers yes)
		(zone_layer_connections)
		(net 226)
	)
	(segment
		(start 222.41 142.78)
		(end 222.41 142.45)
		(width 0.09)
		(layer "B.Cu")
		(net 226)
	)
	(segment
		(start 222.41 142.45)
		(end 222.32 142.36)
		(width 0.09)
		(layer "B.Cu")
		(net 226)
	)
	(segment
		(start 212.65 118)
		(end 212.65 117.65)
		(width 0.15)
		(layer "F.Cu")
		(net 227)
	)
	(segment
		(start 214.05 123.5)
		(end 214.011 123.461)
		(width 0.15)
		(layer "F.Cu")
		(net 227)
	)
	(segment
		(start 212.288 116.882)
		(end 212.288 117.438)
		(width 0.15)
		(layer "F.Cu")
		(net 227)
	)
	(segment
		(start 213.325 119.65)
		(end 214.011 119.65)
		(width 0.15)
		(layer "F.Cu")
		(net 227)
	)
	(segment
		(start 212.31 116.86)
		(end 212.288 116.882)
		(width 0.15)
		(layer "F.Cu")
		(net 227)
	)
	(segment
		(start 213.325 117.65)
		(end 213.86 117.65)
		(width 0.15)
		(layer "F.Cu")
		(net 227)
	)
	(segment
		(start 212.65 117.65)
		(end 213.325 117.65)
		(width 0.15)
		(layer "F.Cu")
		(net 227)
	)
	(segment
		(start 214.011 119.65)
		(end 214.011 117.801)
		(width 0.15)
		(layer "F.Cu")
		(net 227)
	)
	(segment
		(start 212.288 117.438)
		(end 212.5 117.65)
		(width 0.15)
		(layer "F.Cu")
		(net 227)
	)
	(segment
		(start 214.011 118.15)
		(end 213.325 118.15)
		(width 0.15)
		(layer "F.Cu")
		(net 227)
	)
	(segment
		(start 212.5 117.65)
		(end 212.65 117.65)
		(width 0.15)
		(layer "F.Cu")
		(net 227)
	)
	(segment
		(start 214.011 123.461)
		(end 214.011 119.65)
		(width 0.15)
		(layer "F.Cu")
		(net 227)
	)
	(segment
		(start 212.8 118.15)
		(end 212.65 118)
		(width 0.15)
		(layer "F.Cu")
		(net 227)
	)
	(segment
		(start 213.86 117.65)
		(end 214.011 117.801)
		(width 0.15)
		(layer "F.Cu")
		(net 227)
	)
	(segment
		(start 214.05 123.875)
		(end 214.05 123.5)
		(width 0.15)
		(layer "F.Cu")
		(net 227)
	)
	(segment
		(start 213.325 118.15)
		(end 212.8 118.15)
		(width 0.15)
		(layer "F.Cu")
		(net 227)
	)
	(via
		(at 212.31 116.86)
		(size 0.35)
		(drill 0.15)
		(layers "F.Cu" "B.Cu")
		(remove_unused_layers yes)
		(keep_end_layers yes)
		(zone_layer_connections)
		(net 227)
	)
	(segment
		(start 212.31 116.86)
		(end 212.466 116.704)
		(width 0.15)
		(layer "B.Cu")
		(net 227)
	)
	(segment
		(start 212.466 116.704)
		(end 213.376 116.704)
		(width 0.15)
		(layer "B.Cu")
		(net 227)
	)
	(segment
		(start 182.734404 152.704531)
		(end 182.734404 152.713531)
		(width 0.174)
		(layer "F.Cu")
		(net 228)
	)
	(segment
		(start 182.858904 152.580031)
		(end 182.734404 152.704531)
		(width 0.174)
		(layer "F.Cu")
		(net 228)
	)
	(segment
		(start 182.858904 151.980531)
		(end 182.858904 152.580031)
		(width 0.174)
		(layer "F.Cu")
		(net 228)
	)
	(segment
		(start 182.734404 152.713531)
		(end 182.218404 153.229531)
		(width 0.174)
		(layer "F.Cu")
		(net 228)
	)
	(via
		(at 183.549 154.799)
		(size 0.35)
		(drill 0.15)
		(layers "F.Cu" "B.Cu")
		(remove_unused_layers yes)
		(keep_end_layers yes)
		(zone_layer_connections)
		(net 230)
	)
	(via
		(at 182.6 119.9)
		(size 0.35)
		(drill 0.15)
		(layers "F.Cu" "B.Cu")
		(net 230)
	)
	(segment
		(start 182.6 119.85)
		(end 183.15 119.3)
		(width 0.1)
		(layer "B.Cu")
		(net 230)
	)
	(segment
		(start 182.6 119.9)
		(end 182.6 119.85)
		(width 0.1)
		(layer "B.Cu")
		(net 230)
	)
	(segment
		(start 175.515 153.315)
		(end 175.515 147.485)
		(width 0.1)
		(layer "In9.Cu")
		(net 230)
	)
	(segment
		(start 177.7 137.7)
		(end 177.7 122.3)
		(width 0.1)
		(layer "In9.Cu")
		(net 230)
	)
	(segment
		(start 176.25 146.75)
		(end 176.95 146.75)
		(width 0.1)
		(layer "In9.Cu")
		(net 230)
	)
	(segment
		(start 182.948 155.4)
		(end 177.6 155.4)
		(width 0.1)
		(layer "In9.Cu")
		(net 230)
	)
	(segment
		(start 180.5 121.3)
		(end 181.165 120.635)
		(width 0.1)
		(layer "In9.Cu")
		(net 230)
	)
	(segment
		(start 176.21 144.658286)
		(end 176.21 139.19)
		(width 0.1)
		(layer "In9.Cu")
		(net 230)
	)
	(segment
		(start 182.335 120.165)
		(end 182.6 119.9)
		(width 0.1)
		(layer "In9.Cu")
		(net 230)
	)
	(segment
		(start 176.95 146.75)
		(end 177.265 146.435)
		(width 0.1)
		(layer "In9.Cu")
		(net 230)
	)
	(segment
		(start 177.6 155.4)
		(end 175.515 153.315)
		(width 0.1)
		(layer "In9.Cu")
		(net 230)
	)
	(segment
		(start 177.265 146.435)
		(end 177.265 145.713286)
		(width 0.1)
		(layer "In9.Cu")
		(net 230)
	)
	(segment
		(start 181.165 120.369522)
		(end 181.369522 120.165)
		(width 0.1)
		(layer "In9.Cu")
		(net 230)
	)
	(segment
		(start 177.7 122.3)
		(end 178.7 121.3)
		(width 0.1)
		(layer "In9.Cu")
		(net 230)
	)
	(segment
		(start 181.165 120.635)
		(end 181.165 120.369522)
		(width 0.1)
		(layer "In9.Cu")
		(net 230)
	)
	(segment
		(start 178.7 121.3)
		(end 180.5 121.3)
		(width 0.1)
		(layer "In9.Cu")
		(net 230)
	)
	(segment
		(start 177.265 145.713286)
		(end 176.21 144.658286)
		(width 0.1)
		(layer "In9.Cu")
		(net 230)
	)
	(segment
		(start 175.515 147.485)
		(end 176.25 146.75)
		(width 0.1)
		(layer "In9.Cu")
		(net 230)
	)
	(segment
		(start 181.369522 120.165)
		(end 182.335 120.165)
		(width 0.1)
		(layer "In9.Cu")
		(net 230)
	)
	(segment
		(start 176.21 139.19)
		(end 177.7 137.7)
		(width 0.1)
		(layer "In9.Cu")
		(net 230)
	)
	(segment
		(start 183.549 154.799)
		(end 182.948 155.4)
		(width 0.1)
		(layer "In9.Cu")
		(net 230)
	)
	(segment
		(start 222.4015 141.1515)
		(end 222.4015 141.067)
		(width 0.09)
		(layer "F.Cu")
		(net 231)
	)
	(segment
		(start 223.127 142.627)
		(end 222.825716 142.627)
		(width 0.09)
		(layer "F.Cu")
		(net 231)
	)
	(segment
		(start 222.7165 141.4665)
		(end 222.4015 141.1515)
		(width 0.09)
		(layer "F.Cu")
		(net 231)
	)
	(segment
		(start 222.7165 142.517784)
		(end 222.7165 141.4665)
		(width 0.09)
		(layer "F.Cu")
		(net 231)
	)
	(segment
		(start 222.825716 142.627)
		(end 222.7165 142.517784)
		(width 0.09)
		(layer "F.Cu")
		(net 231)
	)
	(segment
		(start 223.28 142.78)
		(end 223.127 142.627)
		(width 0.09)
		(layer "F.Cu")
		(net 231)
	)
	(via
		(at 223.28 142.78)
		(size 0.35)
		(drill 0.15)
		(layers "F.Cu" "B.Cu")
		(remove_unused_layers yes)
		(keep_end_layers yes)
		(zone_layer_connections)
		(net 231)
	)
	(segment
		(start 223.22 142.72)
		(end 223.22 142.36)
		(width 0.09)
		(layer "B.Cu")
		(net 231)
	)
	(segment
		(start 223.28 142.78)
		(end 223.22 142.72)
		(width 0.09)
		(layer "B.Cu")
		(net 231)
	)
	(segment
		(start 227.1525 141.742)
		(end 225.5765 141.742)
		(width 0.59)
		(layer "F.Cu")
		(net 232)
	)
	(via
		(at 205.893002 121.048)
		(size 0.35)
		(drill 0.15)
		(layers "F.Cu" "B.Cu")
		(remove_unused_layers yes)
		(keep_end_layers yes)
		(zone_layer_connections)
		(net 235)
	)
	(via
		(at 200.499 124.3)
		(size 0.35)
		(drill 0.15)
		(layers "F.Cu" "B.Cu")
		(remove_unused_layers yes)
		(keep_end_layers yes)
		(zone_layer_connections)
		(net 235)
	)
	(segment
		(start 206.293002 121.448)
		(end 206.693002 121.448)
		(width 0.15)
		(layer "B.Cu")
		(net 235)
	)
	(segment
		(start 205.893002 121.048)
		(end 206.293002 121.448)
		(width 0.15)
		(layer "B.Cu")
		(net 235)
	)
	(segment
		(start 203.15 120.1)
		(end 203.15 121.55)
		(width 0.09)
		(layer "In4.Cu")
		(net 235)
	)
	(segment
		(start 203.25884 121.65884)
		(end 203.25884 121.978407)
		(width 0.09)
		(layer "In4.Cu")
		(net 235)
	)
	(segment
		(start 203.25884 121.978407)
		(end 202.287247 122.95)
		(width 0.09)
		(layer "In4.Cu")
		(net 235)
	)
	(segment
		(start 206.125 120.2)
		(end 205.952982 120.027982)
		(width 0.09)
		(layer "In4.Cu")
		(net 235)
	)
	(segment
		(start 201.325 122.95)
		(end 200.499 123.776)
		(width 0.09)
		(layer "In4.Cu")
		(net 235)
	)
	(segment
		(start 203.925 120.2)
		(end 203.925 122.85)
		(width 0.09)
		(layer "In4.Cu")
		(net 235)
	)
	(segment
		(start 202.287247 122.95)
		(end 201.325 122.95)
		(width 0.09)
		(layer "In4.Cu")
		(net 235)
	)
	(segment
		(start 205.893002 121.048)
		(end 205.9 121.041002)
		(width 0.09)
		(layer "In4.Cu")
		(net 235)
	)
	(segment
		(start 203.446092 120.027982)
		(end 203.222018 120.027982)
		(width 0.09)
		(layer "In4.Cu")
		(net 235)
	)
	(segment
		(start 205.9 120.725)
		(end 206.125 120.5)
		(width 0.09)
		(layer "In4.Cu")
		(net 235)
	)
	(segment
		(start 203.15 121.55)
		(end 203.25884 121.65884)
		(width 0.09)
		(layer "In4.Cu")
		(net 235)
	)
	(segment
		(start 203.222018 120.027982)
		(end 203.15 120.1)
		(width 0.09)
		(layer "In4.Cu")
		(net 235)
	)
	(segment
		(start 200.499 123.776)
		(end 200.499 124.3)
		(width 0.09)
		(layer "In4.Cu")
		(net 235)
	)
	(segment
		(start 203.575 122.85)
		(end 203.575 120.2)
		(width 0.09)
		(layer "In4.Cu")
		(net 235)
	)
	(segment
		(start 206.125 120.5)
		(end 206.125 120.2)
		(width 0.09)
		(layer "In4.Cu")
		(net 235)
	)
	(segment
		(start 205.952982 120.027982)
		(end 204.053908 120.027982)
		(width 0.09)
		(layer "In4.Cu")
		(net 235)
	)
	(segment
		(start 205.9 121.041002)
		(end 205.9 120.725)
		(width 0.09)
		(layer "In4.Cu")
		(net 235)
	)
	(arc
		(start 203.575 120.2)
		(mid 203.538837 120.093467)
		(end 203.446092 120.027982)
		(width 0.09)
		(layer "In4.Cu")
		(net 235)
	)
	(arc
		(start 203.925 122.85)
		(mid 203.873744 122.973744)
		(end 203.75 123.025)
		(width 0.09)
		(layer "In4.Cu")
		(net 235)
	)
	(arc
		(start 203.75 123.025)
		(mid 203.626256 122.973744)
		(end 203.575 122.85)
		(width 0.09)
		(layer "In4.Cu")
		(net 235)
	)
	(arc
		(start 204.053908 120.027982)
		(mid 203.961163 120.093467)
		(end 203.925 120.2)
		(width 0.09)
		(layer "In4.Cu")
		(net 235)
	)
	(segment
		(start 206.235043 120.65)
		(end 205.893002 120.65)
		(width 0.15)
		(layer "F.Cu")
		(net 236)
	)
	(segment
		(start 206.361045 120.776002)
		(end 206.235043 120.65)
		(width 0.15)
		(layer "F.Cu")
		(net 236)
	)
	(via
		(at 206.361045 120.776002)
		(size 0.35)
		(drill 0.15)
		(layers "F.Cu" "B.Cu")
		(remove_unused_layers yes)
		(keep_end_layers yes)
		(zone_layer_connections)
		(net 236)
	)
	(via
		(at 199.699 129.1)
		(size 0.35)
		(drill 0.15)
		(layers "F.Cu" "B.Cu")
		(remove_unused_layers yes)
		(keep_end_layers yes)
		(zone_layer_connections)
		(net 236)
	)
	(segment
		(start 206.693002 121.05)
		(end 206.635043 121.05)
		(width 0.15)
		(layer "B.Cu")
		(net 236)
	)
	(segment
		(start 206.635043 121.05)
		(end 206.361045 120.776002)
		(width 0.15)
		(layer "B.Cu")
		(net 236)
	)
	(segment
		(start 201.79 124.26)
		(end 201.44 124.61)
		(width 0.09)
		(layer "In4.Cu")
		(net 236)
	)
	(segment
		(start 205.385 123.54)
		(end 202.3 123.54)
		(width 0.09)
		(layer "In4.Cu")
		(net 236)
	)
	(segment
		(start 201.44 124.61)
		(end 201.19 124.61)
		(width 0.09)
		(layer "In4.Cu")
		(net 236)
	)
	(segment
		(start 200.9 124.9)
		(end 200.9 127.4)
		(width 0.09)
		(layer "In4.Cu")
		(net 236)
	)
	(segment
		(start 202.3 123.54)
		(end 201.79 124.05)
		(width 0.09)
		(layer "In4.Cu")
		(net 236)
	)
	(segment
		(start 206.361045 120.776002)
		(end 206.361045 121.846695)
		(width 0.09)
		(layer "In4.Cu")
		(net 236)
	)
	(segment
		(start 201.19 124.61)
		(end 200.9 124.9)
		(width 0.09)
		(layer "In4.Cu")
		(net 236)
	)
	(segment
		(start 206.515 122.41)
		(end 205.385 123.54)
		(width 0.09)
		(layer "In4.Cu")
		(net 236)
	)
	(segment
		(start 200.018 128.282)
		(end 200.018 128.781)
		(width 0.09)
		(layer "In4.Cu")
		(net 236)
	)
	(segment
		(start 201.79 124.05)
		(end 201.79 124.26)
		(width 0.09)
		(layer "In4.Cu")
		(net 236)
	)
	(segment
		(start 206.361045 121.846695)
		(end 206.515 122.00065)
		(width 0.09)
		(layer "In4.Cu")
		(net 236)
	)
	(segment
		(start 206.515 122.00065)
		(end 206.515 122.41)
		(width 0.09)
		(layer "In4.Cu")
		(net 236)
	)
	(segment
		(start 200.9 127.4)
		(end 200.018 128.282)
		(width 0.09)
		(layer "In4.Cu")
		(net 236)
	)
	(segment
		(start 200.018 128.781)
		(end 199.699 129.1)
		(width 0.09)
		(layer "In4.Cu")
		(net 236)
	)
	(segment
		(start 208.57 143.85)
		(end 209.2 143.85)
		(width 0.35)
		(layer "F.Cu")
		(net 237)
	)
	(segment
		(start 208.8385 145.8)
		(end 209.3385 146.3)
		(width 0.35)
		(layer "F.Cu")
		(net 237)
	)
	(segment
		(start 208.57 145.8)
		(end 208.8385 145.8)
		(width 0.35)
		(layer "F.Cu")
		(net 237)
	)
	(via
		(at 209.2 143.85)
		(size 0.35)
		(drill 0.15)
		(layers "F.Cu" "B.Cu")
		(remove_unused_layers yes)
		(keep_end_layers yes)
		(zone_layer_connections)
		(net 237)
	)
	(via
		(at 184.7 146.85)
		(size 0.35)
		(drill 0.15)
		(layers "F.Cu" "B.Cu")
		(remove_unused_layers yes)
		(keep_end_layers yes)
		(zone_layer_connections)
		(net 237)
	)
	(via
		(at 209.3385 146.3)
		(size 0.35)
		(drill 0.15)
		(layers "F.Cu" "B.Cu")
		(remove_unused_layers yes)
		(keep_end_layers yes)
		(zone_layer_connections)
		(net 237)
	)
	(segment
		(start 209.85 144.1)
		(end 209.6 143.85)
		(width 0.35)
		(layer "In6.Cu")
		(net 237)
	)
	(segment
		(start 184.7 146.85)
		(end 184.525 147.025)
		(width 0.4)
		(layer "In6.Cu")
		(net 237)
	)
	(segment
		(start 209.85 144.1)
		(end 209.85 146.3135)
		(width 0.35)
		(layer "In6.Cu")
		(net 237)
	)
	(segment
		(start 209.85 146.3135)
		(end 209.8385 146.325)
		(width 0.4)
		(layer "In6.Cu")
		(net 237)
	)
	(segment
		(start 190.025 148.4)
		(end 192.2 148.4)
		(width 0.4)
		(layer "In6.Cu")
		(net 237)
	)
	(segment
		(start 199.4 151.3)
		(end 204.9 151.3)
		(width 0.4)
		(layer "In6.Cu")
		(net 237)
	)
	(segment
		(start 195.418248 146.6)
		(end 196.748248 147.93)
		(width 0.4)
		(layer "In6.Cu")
		(net 237)
	)
	(segment
		(start 192.2 148.4)
		(end 194 146.6)
		(width 0.4)
		(layer "In6.Cu")
		(net 237)
	)
	(segment
		(start 209.6 143.85)
		(end 209.2 143.85)
		(width 0.35)
		(layer "In6.Cu")
		(net 237)
	)
	(segment
		(start 194 146.6)
		(end 195.418248 146.6)
		(width 0.4)
		(layer "In6.Cu")
		(net 237)
	)
	(segment
		(start 184.9 149.475)
		(end 188.95 149.475)
		(width 0.4)
		(layer "In6.Cu")
		(net 237)
	)
	(segment
		(start 188.95 149.475)
		(end 190.025 148.4)
		(width 0.4)
		(layer "In6.Cu")
		(net 237)
	)
	(segment
		(start 197.93 147.93)
		(end 198.7 148.7)
		(width 0.4)
		(layer "In6.Cu")
		(net 237)
	)
	(segment
		(start 209.2685 150.245)
		(end 209.85 149.6635)
		(width 0.4)
		(layer "In6.Cu")
		(net 237)
	)
	(segment
		(start 204.9 151.3)
		(end 205.955 150.245)
		(width 0.4)
		(layer "In6.Cu")
		(net 237)
	)
	(segment
		(start 196.748248 147.93)
		(end 197.93 147.93)
		(width 0.4)
		(layer "In6.Cu")
		(net 237)
	)
	(segment
		(start 209.3385 146.3)
		(end 209.8135 146.3)
		(width 0.35)
		(layer "In6.Cu")
		(net 237)
	)
	(segment
		(start 198.7 148.7)
		(end 198.7 150.6)
		(width 0.4)
		(layer "In6.Cu")
		(net 237)
	)
	(segment
		(start 184.525 149.1)
		(end 184.9 149.475)
		(width 0.4)
		(layer "In6.Cu")
		(net 237)
	)
	(segment
		(start 198.7 150.6)
		(end 199.4 151.3)
		(width 0.4)
		(layer "In6.Cu")
		(net 237)
	)
	(segment
		(start 209.85 149.6635)
		(end 209.85 146.3365)
		(width 0.4)
		(layer "In6.Cu")
		(net 237)
	)
	(segment
		(start 205.955 150.245)
		(end 209.2685 150.245)
		(width 0.4)
		(layer "In6.Cu")
		(net 237)
	)
	(segment
		(start 209.8135 146.3)
		(end 209.8385 146.325)
		(width 0.4)
		(layer "In6.Cu")
		(net 237)
	)
	(segment
		(start 184.525 147.025)
		(end 184.525 149.1)
		(width 0.4)
		(layer "In6.Cu")
		(net 237)
	)
	(segment
		(start 209.85 146.3365)
		(end 209.8385 146.325)
		(width 0.4)
		(layer "In6.Cu")
		(net 237)
	)
	(segment
		(start 220.8865 141.6635)
		(end 221.2015 141.3485)
		(width 0.09)
		(layer "F.Cu")
		(net 240)
	)
	(segment
		(start 221.071135 142.79)
		(end 220.8865 142.605365)
		(width 0.09)
		(layer "F.Cu")
		(net 240)
	)
	(segment
		(start 221.2015 141.3485)
		(end 221.2015 141.067)
		(width 0.09)
		(layer "F.Cu")
		(net 240)
	)
	(segment
		(start 220.8865 142.605365)
		(end 220.8865 141.6635)
		(width 0.09)
		(layer "F.Cu")
		(net 240)
	)
	(segment
		(start 221.31 142.79)
		(end 221.071135 142.79)
		(width 0.09)
		(layer "F.Cu")
		(net 240)
	)
	(via
		(at 221.31 142.79)
		(size 0.35)
		(drill 0.15)
		(layers "F.Cu" "B.Cu")
		(remove_unused_layers yes)
		(keep_end_layers yes)
		(zone_layer_connections)
		(net 240)
	)
	(segment
		(start 221.31 142.79)
		(end 221.31 142.55)
		(width 0.09)
		(layer "B.Cu")
		(net 240)
	)
	(segment
		(start 221.31 142.55)
		(end 221.49 142.37)
		(width 0.09)
		(layer "B.Cu")
		(net 240)
	)
	(segment
		(start 212.9435 128.1905)
		(end 212.9435 128.45)
		(width 0.15)
		(layer "F.Cu")
		(net 243)
	)
	(segment
		(start 212.6515 127.8985)
		(end 212.9435 128.1905)
		(width 0.15)
		(layer "F.Cu")
		(net 243)
	)
	(via
		(at 209.7075 129.35)
		(size 0.35)
		(drill 0.15)
		(layers "F.Cu" "B.Cu")
		(remove_unused_layers yes)
		(keep_end_layers yes)
		(zone_layer_connections)
		(net 243)
	)
	(via
		(at 212.6515 127.8985)
		(size 0.35)
		(drill 0.15)
		(layers "F.Cu" "B.Cu")
		(remove_unused_layers yes)
		(keep_end_layers yes)
		(zone_layer_connections)
		(net 243)
	)
	(segment
		(start 204.6 121.77)
		(end 205.07 122.24)
		(width 0.15)
		(layer "B.Cu")
		(net 243)
	)
	(segment
		(start 207.42 125.1)
		(end 207.19 125.33)
		(width 0.15)
		(layer "B.Cu")
		(net 243)
	)
	(segment
		(start 208.05 127.97)
		(end 208.05 128.63)
		(width 0.15)
		(layer "B.Cu")
		(net 243)
	)
	(segment
		(start 208.05 128.63)
		(end 208.17 128.75)
		(width 0.15)
		(layer "B.Cu")
		(net 243)
	)
	(segment
		(start 203.54684 121.05)
		(end 204.33 121.05)
		(width 0.15)
		(layer "B.Cu")
		(net 243)
	)
	(segment
		(start 207.19 125.61)
		(end 207.42 125.84)
		(width 0.15)
		(layer "B.Cu")
		(net 243)
	)
	(segment
		(start 204.33 121.05)
		(end 204.6 121.32)
		(width 0.15)
		(layer "B.Cu")
		(net 243)
	)
	(segment
		(start 208.639515 129.219516)
		(end 208.77 129.35)
		(width 0.15)
		(layer "B.Cu")
		(net 243)
	)
	(segment
		(start 205.65 122.24)
		(end 207.42 124.01)
		(width 0.15)
		(layer "B.Cu")
		(net 243)
	)
	(segment
		(start 207.19 125.33)
		(end 207.19 125.61)
		(width 0.15)
		(layer "B.Cu")
		(net 243)
	)
	(segment
		(start 208.628199 128.749999)
		(end 208.639515 128.761315)
		(width 0.15)
		(layer "B.Cu")
		(net 243)
	)
	(segment
		(start 207.42 125.84)
		(end 207.42 127.34)
		(width 0.15)
		(layer "B.Cu")
		(net 243)
	)
	(segment
		(start 207.42 124.01)
		(end 207.42 125.1)
		(width 0.15)
		(layer "B.Cu")
		(net 243)
	)
	(segment
		(start 204.6 121.32)
		(end 204.6 121.77)
		(width 0.15)
		(layer "B.Cu")
		(net 243)
	)
	(segment
		(start 208.639515 128.990415)
		(end 208.639515 128.990416)
		(width 0.15)
		(layer "B.Cu")
		(net 243)
	)
	(segment
		(start 207.42 127.34)
		(end 208.05 127.97)
		(width 0.15)
		(layer "B.Cu")
		(net 243)
	)
	(segment
		(start 205.07 122.24)
		(end 205.65 122.24)
		(width 0.15)
		(layer "B.Cu")
		(net 243)
	)
	(segment
		(start 208.77 129.35)
		(end 209.7075 129.35)
		(width 0.15)
		(layer "B.Cu")
		(net 243)
	)
	(arc
		(start 208.639515 128.990416)
		(mid 208.592067 129.104966)
		(end 208.639515 129.219516)
		(width 0.15)
		(layer "B.Cu")
		(net 243)
	)
	(arc
		(start 208.639515 128.761315)
		(mid 208.686963 128.875865)
		(end 208.639515 128.990415)
		(width 0.15)
		(layer "B.Cu")
		(net 243)
	)
	(arc
		(start 208.399099 128.749999)
		(mid 208.513649 128.702551)
		(end 208.628199 128.749999)
		(width 0.15)
		(layer "B.Cu")
		(net 243)
	)
	(arc
		(start 208.17 128.75)
		(mid 208.284551 128.797448)
		(end 208.399099 128.749999)
		(width 0.15)
		(layer "B.Cu")
		(net 243)
	)
	(segment
		(start 212.28 127.98)
		(end 212.28 128.15)
		(width 0.09)
		(layer "In2.Cu")
		(net 243)
	)
	(segment
		(start 209.825 128.975)
		(end 209.725 129.075)
		(width 0.09)
		(layer "In2.Cu")
		(net 243)
	)
	(segment
		(start 210.55 129.18)
		(end 210.65 129.18)
		(width 0.09)
		(layer "In2.Cu")
		(net 243)
	)
	(segment
		(start 211.68 128.4)
		(end 211.65 128.4)
		(width 0.09)
		(layer "In2.Cu")
		(net 243)
	)
	(segment
		(start 210.65 129.48)
		(end 210.55 129.48)
		(width 0.09)
		(layer "In2.Cu")
		(net 243)
	)
	(segment
		(start 209.96 130.01)
		(end 209.66 130.01)
		(width 0.09)
		(layer "In2.Cu")
		(net 243)
	)
	(segment
		(start 209.78 130.955)
		(end 209.78 130.77)
		(width 0.09)
		(layer "In2.Cu")
		(net 243)
	)
	(segment
		(start 212.6515 127.8985)
		(end 212.3615 127.8985)
		(width 0.09)
		(layer "In2.Cu")
		(net 243)
	)
	(segment
		(start 212.28 128.15)
		(end 212.11 128.32)
		(width 0.09)
		(layer "In2.Cu")
		(net 243)
	)
	(segment
		(start 210.98 128.4)
		(end 210.8 128.58)
		(width 0.09)
		(layer "In2.Cu")
		(net 243)
	)
	(segment
		(start 212.11 128.32)
		(end 212.11 128.51)
		(width 0.09)
		(layer "In2.Cu")
		(net 243)
	)
	(segment
		(start 211.89 128.61)
		(end 211.68 128.4)
		(width 0.09)
		(layer "In2.Cu")
		(net 243)
	)
	(segment
		(start 210.675 131.02)
		(end 209.845 131.02)
		(width 0.09)
		(layer "In2.Cu")
		(net 243)
	)
	(segment
		(start 212.01 128.61)
		(end 211.89 128.61)
		(width 0.09)
		(layer "In2.Cu")
		(net 243)
	)
	(segment
		(start 209.725 129.075)
		(end 209.725 129.3325)
		(width 0.09)
		(layer "In2.Cu")
		(net 243)
	)
	(segment
		(start 210.55 129.78)
		(end 210.65 129.78)
		(width 0.09)
		(layer "In2.Cu")
		(net 243)
	)
	(segment
		(start 210.11 129.56)
		(end 210.11 129.06)
		(width 0.09)
		(layer "In2.Cu")
		(net 243)
	)
	(segment
		(start 211.2 128.6)
		(end 211.2 128.55)
		(width 0.09)
		(layer "In2.Cu")
		(net 243)
	)
	(segment
		(start 210.025 128.975)
		(end 209.825 128.975)
		(width 0.09)
		(layer "In2.Cu")
		(net 243)
	)
	(segment
		(start 212.11 128.51)
		(end 212.01 128.61)
		(width 0.09)
		(layer "In2.Cu")
		(net 243)
	)
	(segment
		(start 211.05 128.4)
		(end 210.98 128.4)
		(width 0.09)
		(layer "In2.Cu")
		(net 243)
	)
	(segment
		(start 210.11 130.44)
		(end 210.11 130.16)
		(width 0.09)
		(layer "In2.Cu")
		(net 243)
	)
	(segment
		(start 212.3615 127.8985)
		(end 212.28 127.98)
		(width 0.09)
		(layer "In2.Cu")
		(net 243)
	)
	(segment
		(start 209.66 129.71)
		(end 209.96 129.71)
		(width 0.09)
		(layer "In2.Cu")
		(net 243)
	)
	(segment
		(start 210.65 128.88)
		(end 210.55 128.88)
		(width 0.09)
		(layer "In2.Cu")
		(net 243)
	)
	(segment
		(start 210.11 129.06)
		(end 210.025 128.975)
		(width 0.09)
		(layer "In2.Cu")
		(net 243)
	)
	(segment
		(start 209.845 131.02)
		(end 209.78 130.955)
		(width 0.09)
		(layer "In2.Cu")
		(net 243)
	)
	(segment
		(start 211.5 128.55)
		(end 211.5 128.6)
		(width 0.09)
		(layer "In2.Cu")
		(net 243)
	)
	(segment
		(start 210.8 129.93)
		(end 210.8 130.895)
		(width 0.09)
		(layer "In2.Cu")
		(net 243)
	)
	(segment
		(start 210.8 130.895)
		(end 210.675 131.02)
		(width 0.09)
		(layer "In2.Cu")
		(net 243)
	)
	(segment
		(start 209.725 129.3325)
		(end 209.7075 129.35)
		(width 0.09)
		(layer "In2.Cu")
		(net 243)
	)
	(segment
		(start 209.78 130.77)
		(end 210.11 130.44)
		(width 0.09)
		(layer "In2.Cu")
		(net 243)
	)
	(segment
		(start 210.8 128.58)
		(end 210.8 128.73)
		(width 0.09)
		(layer "In2.Cu")
		(net 243)
	)
	(arc
		(start 210.55 128.88)
		(mid 210.443934 128.923934)
		(end 210.4 129.03)
		(width 0.09)
		(layer "In2.Cu")
		(net 243)
	)
	(arc
		(start 210.8 128.73)
		(mid 210.756066 128.836066)
		(end 210.65 128.88)
		(width 0.09)
		(layer "In2.Cu")
		(net 243)
	)
	(arc
		(start 211.35 128.75)
		(mid 211.243934 128.706066)
		(end 211.2 128.6)
		(width 0.09)
		(layer "In2.Cu")
		(net 243)
	)
	(arc
		(start 211.65 128.4)
		(mid 211.543934 128.443934)
		(end 211.5 128.55)
		(width 0.09)
		(layer "In2.Cu")
		(net 243)
	)
	(arc
		(start 209.51 129.86)
		(mid 209.553934 129.753934)
		(end 209.66 129.71)
		(width 0.09)
		(layer "In2.Cu")
		(net 243)
	)
	(arc
		(start 210.8 129.33)
		(mid 210.756066 129.436066)
		(end 210.65 129.48)
		(width 0.09)
		(layer "In2.Cu")
		(net 243)
	)
	(arc
		(start 210.65 129.78)
		(mid 210.756066 129.823934)
		(end 210.8 129.93)
		(width 0.09)
		(layer "In2.Cu")
		(net 243)
	)
	(arc
		(start 210.4 129.03)
		(mid 210.443934 129.136066)
		(end 210.55 129.18)
		(width 0.09)
		(layer "In2.Cu")
		(net 243)
	)
	(arc
		(start 210.55 129.48)
		(mid 210.443934 129.523934)
		(end 210.4 129.63)
		(width 0.09)
		(layer "In2.Cu")
		(net 243)
	)
	(arc
		(start 211.2 128.55)
		(mid 211.156066 128.443934)
		(end 211.05 128.4)
		(width 0.09)
		(layer "In2.Cu")
		(net 243)
	)
	(arc
		(start 209.66 130.01)
		(mid 209.553934 129.966066)
		(end 209.51 129.86)
		(width 0.09)
		(layer "In2.Cu")
		(net 243)
	)
	(arc
		(start 211.5 128.6)
		(mid 211.456066 128.706066)
		(end 211.35 128.75)
		(width 0.09)
		(layer "In2.Cu")
		(net 243)
	)
	(arc
		(start 210.4 129.63)
		(mid 210.443934 129.736066)
		(end 210.55 129.78)
		(width 0.09)
		(layer "In2.Cu")
		(net 243)
	)
	(arc
		(start 210.65 129.18)
		(mid 210.756066 129.223934)
		(end 210.8 129.33)
		(width 0.09)
		(layer "In2.Cu")
		(net 243)
	)
	(arc
		(start 209.96 129.71)
		(mid 210.066066 129.666066)
		(end 210.11 129.56)
		(width 0.09)
		(layer "In2.Cu")
		(net 243)
	)
	(arc
		(start 210.11 130.16)
		(mid 210.066066 130.053934)
		(end 209.96 130.01)
		(width 0.09)
		(layer "In2.Cu")
		(net 243)
	)
	(segment
		(start 198.282486 118.132486)
		(end 198.282486 117.687335)
		(width 0.1)
		(layer "F.Cu")
		(net 245)
	)
	(segment
		(start 199.550796 118.889204)
		(end 199.550796 118.600796)
		(width 0.1)
		(layer "F.Cu")
		(net 245)
	)
	(segment
		(start 199.550796 118.600796)
		(end 199.25 118.3)
		(width 0.1)
		(layer "F.Cu")
		(net 245)
	)
	(segment
		(start 199.25 118.3)
		(end 198.45 118.3)
		(width 0.1)
		(layer "F.Cu")
		(net 245)
	)
	(segment
		(start 198.45 118.3)
		(end 198.282486 118.132486)
		(width 0.1)
		(layer "F.Cu")
		(net 245)
	)
	(via
		(at 199.550796 118.889204)
		(size 0.35)
		(drill 0.15)
		(layers "F.Cu" "B.Cu")
		(remove_unused_layers yes)
		(keep_end_layers yes)
		(zone_layer_connections)
		(net 245)
	)
	(segment
		(start 199.729074 120.163926)
		(end 199.722 120.171)
		(width 0.15)
		(layer "B.Cu")
		(net 245)
	)
	(segment
		(start 199.729074 119.067482)
		(end 199.729074 120.163926)
		(width 0.15)
		(layer "B.Cu")
		(net 245)
	)
	(segment
		(start 199.550796 118.889204)
		(end 199.729074 119.067482)
		(width 0.15)
		(layer "B.Cu")
		(net 245)
	)
	(segment
		(start 196.45 119.7)
		(end 196.15 119.4)
		(width 0.1)
		(layer "F.Cu")
		(net 246)
	)
	(segment
		(start 204.1 124.45)
		(end 204.1 123.6)
		(width 0.1)
		(layer "F.Cu")
		(net 246)
	)
	(segment
		(start 200.95 122.75)
		(end 200.37384 122.17384)
		(width 0.1)
		(layer "F.Cu")
		(net 246)
	)
	(segment
		(start 226.75 134.2)
		(end 227.4 133.55)
		(width 0.1)
		(layer "F.Cu")
		(net 246)
	)
	(segment
		(start 198.05 119.7)
		(end 196.45 119.7)
		(width 0.1)
		(layer "F.Cu")
		(net 246)
	)
	(segment
		(start 210.72 126.06)
		(end 211.36 126.7)
		(width 0.1)
		(layer "F.Cu")
		(net 246)
	)
	(segment
		(start 226.7 124.45)
		(end 221.3 124.45)
		(width 0.1)
		(layer "F.Cu")
		(net 246)
	)
	(segment
		(start 208.46 126.06)
		(end 210.72 126.06)
		(width 0.1)
		(layer "F.Cu")
		(net 246)
	)
	(segment
		(start 227.4 133.55)
		(end 227.4 125.15)
		(width 0.1)
		(layer "F.Cu")
		(net 246)
	)
	(segment
		(start 219.05 126.7)
		(end 211.36 126.7)
		(width 0.1)
		(layer "F.Cu")
		(net 246)
	)
	(segment
		(start 195.3 117.35)
		(end 194.921 116.971)
		(width 0.1)
		(layer "F.Cu")
		(net 246)
	)
	(segment
		(start 200.37384 121.12384)
		(end 200.2 120.95)
		(width 0.1)
		(layer "F.Cu")
		(net 246)
	)
	(segment
		(start 200.2 120.95)
		(end 199.3 120.95)
		(width 0.1)
		(layer "F.Cu")
		(net 246)
	)
	(segment
		(start 204.1 123.6)
		(end 203.25 122.75)
		(width 0.1)
		(layer "F.Cu")
		(net 246)
	)
	(segment
		(start 199.3 120.95)
		(end 198.05 119.7)
		(width 0.1)
		(layer "F.Cu")
		(net 246)
	)
	(segment
		(start 196.15 117.7)
		(end 195.8 117.35)
		(width 0.1)
		(layer "F.Cu")
		(net 246)
	)
	(segment
		(start 200.37384 122.17384)
		(end 200.37384 121.12384)
		(width 0.1)
		(layer "F.Cu")
		(net 246)
	)
	(segment
		(start 207.1 124.7)
		(end 204.35 124.7)
		(width 0.1)
		(layer "F.Cu")
		(net 246)
	)
	(segment
		(start 196.15 119.4)
		(end 196.15 117.7)
		(width 0.1)
		(layer "F.Cu")
		(net 246)
	)
	(segment
		(start 194.921 116.971)
		(end 194.921 116.84)
		(width 0.1)
		(layer "F.Cu")
		(net 246)
	)
	(segment
		(start 227.4 125.15)
		(end 226.7 124.45)
		(width 0.1)
		(layer "F.Cu")
		(net 246)
	)
	(segment
		(start 195.8 117.35)
		(end 195.3 117.35)
		(width 0.1)
		(layer "F.Cu")
		(net 246)
	)
	(segment
		(start 208.46 126.06)
		(end 207.1 124.7)
		(width 0.1)
		(layer "F.Cu")
		(net 246)
	)
	(segment
		(start 204.35 124.7)
		(end 204.1 124.45)
		(width 0.1)
		(layer "F.Cu")
		(net 246)
	)
	(segment
		(start 225.9 134.2)
		(end 226.75 134.2)
		(width 0.1)
		(layer "F.Cu")
		(net 246)
	)
	(segment
		(start 221.3 124.45)
		(end 219.05 126.7)
		(width 0.1)
		(layer "F.Cu")
		(net 246)
	)
	(segment
		(start 203.25 122.75)
		(end 200.95 122.75)
		(width 0.1)
		(layer "F.Cu")
		(net 246)
	)
	(via
		(at 194.921 116.84)
		(size 0.35)
		(drill 0.15)
		(layers "F.Cu" "B.Cu")
		(remove_unused_layers yes)
		(keep_end_layers yes)
		(zone_layer_connections)
		(net 246)
	)
	(via
		(at 225.9 134.2)
		(size 0.35)
		(drill 0.15)
		(layers "F.Cu" "B.Cu")
		(remove_unused_layers yes)
		(keep_end_layers yes)
		(zone_layer_connections)
		(net 246)
	)
	(segment
		(start 222.9305 138.13)
		(end 222.9245 138.136)
		(width 0.256)
		(layer "B.Cu")
		(net 246)
	)
	(segment
		(start 224.353 137.877)
		(end 224.353 136.878)
		(width 0.256)
		(layer "B.Cu")
		(net 246)
	)
	(segment
		(start 222.9245 135.7745)
		(end 222.9245 135.261)
		(width 0.256)
		(layer "B.Cu")
		(net 246)
	)
	(segment
		(start 223.475 136.325)
		(end 222.9245 135.7745)
		(width 0.256)
		(layer "B.Cu")
		(net 246)
	)
	(segment
		(start 224.839 135.261)
		(end 222.9245 135.261)
		(width 0.1)
		(layer "B.Cu")
		(net 246)
	)
	(segment
		(start 224.1 138.13)
		(end 224.353 137.877)
		(width 0.256)
		(layer "B.Cu")
		(net 246)
	)
	(segment
		(start 224.353 136.878)
		(end 223.8 136.325)
		(width 0.256)
		(layer "B.Cu")
		(net 246)
	)
	(segment
		(start 194.921 117.46)
		(end 194.922 117.461)
		(width 0.15)
		(layer "B.Cu")
		(net 246)
	)
	(segment
		(start 224.1 138.13)
		(end 222.9305 138.13)
		(width 0.256)
		(layer "B.Cu")
		(net 246)
	)
	(segment
		(start 223.8 136.325)
		(end 223.475 136.325)
		(width 0.256)
		(layer "B.Cu")
		(net 246)
	)
	(segment
		(start 194.921 116.84)
		(end 194.921 117.46)
		(width 0.15)
		(layer "B.Cu")
		(net 246)
	)
	(segment
		(start 225.9 134.2)
		(end 224.839 135.261)
		(width 0.1)
		(layer "B.Cu")
		(net 246)
	)
	(segment
		(start 213.9425 127.951)
		(end 213.4435 128.45)
		(width 0.15)
		(layer "F.Cu")
		(net 248)
	)
	(segment
		(start 213.9425 127.947)
		(end 213.9425 127.951)
		(width 0.184)
		(layer "F.Cu")
		(net 248)
	)
	(via
		(at 213.9425 127.947)
		(size 0.35)
		(drill 0.15)
		(layers "F.Cu" "B.Cu")
		(remove_unused_layers yes)
		(keep_end_layers yes)
		(zone_layer_connections)
		(net 248)
	)
	(via
		(at 209.7075 130.35)
		(size 0.35)
		(drill 0.15)
		(layers "F.Cu" "B.Cu")
		(remove_unused_layers yes)
		(keep_end_layers yes)
		(zone_layer_connections)
		(net 248)
	)
	(segment
		(start 205.53 122.68)
		(end 206.95 124.1)
		(width 0.15)
		(layer "B.Cu")
		(net 248)
	)
	(segment
		(start 207.56 128.12)
		(end 207.56 128.82)
		(width 0.15)
		(layer "B.Cu")
		(net 248)
	)
	(segment
		(start 205.07 122.68)
		(end 205.53 122.68)
		(width 0.15)
		(layer "B.Cu")
		(net 248)
	)
	(segment
		(start 204.108 121.448)
		(end 204.26 121.6)
		(width 0.15)
		(layer "B.Cu")
		(net 248)
	)
	(segment
		(start 206.95 124.84)
		(end 206.67 125.12)
		(width 0.15)
		(layer "B.Cu")
		(net 248)
	)
	(segment
		(start 206.67 125.12)
		(end 206.67 125.81)
		(width 0.15)
		(layer "B.Cu")
		(net 248)
	)
	(segment
		(start 206.95 127.51)
		(end 207.56 128.12)
		(width 0.15)
		(layer "B.Cu")
		(net 248)
	)
	(segment
		(start 208.92 129.81)
		(end 209.07 129.96)
		(width 0.15)
		(layer "B.Cu")
		(net 248)
	)
	(segment
		(start 206.95 124.1)
		(end 206.95 124.84)
		(width 0.15)
		(layer "B.Cu")
		(net 248)
	)
	(segment
		(start 203.54684 121.448)
		(end 204.108 121.448)
		(width 0.15)
		(layer "B.Cu")
		(net 248)
	)
	(segment
		(start 209.07 130.15)
		(end 209.27 130.35)
		(width 0.15)
		(layer "B.Cu")
		(net 248)
	)
	(segment
		(start 209.27 130.35)
		(end 209.7125 130.35)
		(width 0.15)
		(layer "B.Cu")
		(net 248)
	)
	(segment
		(start 204.26 121.87)
		(end 205.07 122.68)
		(width 0.15)
		(layer "B.Cu")
		(net 248)
	)
	(segment
		(start 209.07 129.96)
		(end 209.07 130.15)
		(width 0.15)
		(layer "B.Cu")
		(net 248)
	)
	(segment
		(start 207.56 128.82)
		(end 208.55 129.81)
		(width 0.15)
		(layer "B.Cu")
		(net 248)
	)
	(segment
		(start 206.67 125.81)
		(end 206.95 126.09)
		(width 0.15)
		(layer "B.Cu")
		(net 248)
	)
	(segment
		(start 204.26 121.6)
		(end 204.26 121.87)
		(width 0.15)
		(layer "B.Cu")
		(net 248)
	)
	(segment
		(start 206.95 126.09)
		(end 206.95 127.51)
		(width 0.15)
		(layer "B.Cu")
		(net 248)
	)
	(segment
		(start 208.55 129.81)
		(end 208.92 129.81)
		(width 0.15)
		(layer "B.Cu")
		(net 248)
	)
	(segment
		(start 213.85 132)
		(end 214.7685 131.0815)
		(width 0.09)
		(layer "In2.Cu")
		(net 248)
	)
	(segment
		(start 214.7685 131.0815)
		(end 214.7685 128.31538)
		(width 0.09)
		(layer "In2.Cu")
		(net 248)
	)
	(segment
		(start 209.3 130.7575)
		(end 209.3 131.55)
		(width 0.09)
		(layer "In2.Cu")
		(net 248)
	)
	(segment
		(start 214.7685 128.31538)
		(end 214.40012 127.947)
		(width 0.09)
		(layer "In2.Cu")
		(net 248)
	)
	(segment
		(start 214.40012 127.947)
		(end 213.9425 127.947)
		(width 0.09)
		(layer "In2.Cu")
		(net 248)
	)
	(segment
		(start 209.75 132)
		(end 213.85 132)
		(width 0.09)
		(layer "In2.Cu")
		(net 248)
	)
	(segment
		(start 209.3 131.55)
		(end 209.75 132)
		(width 0.09)
		(layer "In2.Cu")
		(net 248)
	)
	(segment
		(start 209.7075 130.35)
		(end 209.3 130.7575)
		(width 0.09)
		(layer "In2.Cu")
		(net 248)
	)
	(via
		(at 209.7075 131.347)
		(size 0.35)
		(drill 0.15)
		(layers "F.Cu" "B.Cu")
		(remove_unused_layers yes)
		(keep_end_layers yes)
		(zone_layer_connections)
		(net 249)
	)
	(via
		(at 213.4435 128.95)
		(size 0.35)
		(drill 0.15)
		(layers "F.Cu" "B.Cu")
		(remove_unused_layers yes)
		(keep_end_layers yes)
		(zone_layer_connections)
		(net 249)
	)
	(segment
		(start 206.45 124.53)
		(end 206.19 124.79)
		(width 0.15)
		(layer "B.Cu")
		(net 249)
	)
	(segment
		(start 206.45 124.15)
		(end 206.45 124.53)
		(width 0.15)
		(layer "B.Cu")
		(net 249)
	)
	(segment
		(start 207 128.89)
		(end 209.457 131.347)
		(width 0.15)
		(layer "B.Cu")
		(net 249)
	)
	(segment
		(start 203.54684 121.85)
		(end 203.8 121.85)
		(width 0.15)
		(layer "B.Cu")
		(net 249)
	)
	(segment
		(start 206.19 126.15)
		(end 206.45 126.41)
		(width 0.15)
		(layer "B.Cu")
		(net 249)
	)
	(segment
		(start 206.45 127.58)
		(end 207 128.13)
		(width 0.15)
		(layer "B.Cu")
		(net 249)
	)
	(segment
		(start 206.19 124.79)
		(end 206.19 126.15)
		(width 0.15)
		(layer "B.Cu")
		(net 249)
	)
	(segment
		(start 206.45 126.41)
		(end 206.45 127.58)
		(width 0.15)
		(layer "B.Cu")
		(net 249)
	)
	(segment
		(start 205.18 123.23)
		(end 205.53 123.23)
		(width 0.15)
		(layer "B.Cu")
		(net 249)
	)
	(segment
		(start 205.53 123.23)
		(end 206.45 124.15)
		(width 0.15)
		(layer "B.Cu")
		(net 249)
	)
	(segment
		(start 203.8 121.85)
		(end 205.18 123.23)
		(width 0.15)
		(layer "B.Cu")
		(net 249)
	)
	(segment
		(start 207 128.13)
		(end 207 128.89)
		(width 0.15)
		(layer "B.Cu")
		(net 249)
	)
	(segment
		(start 209.457 131.347)
		(end 209.7075 131.347)
		(width 0.15)
		(layer "B.Cu")
		(net 249)
	)
	(segment
		(start 214.2 128.71)
		(end 213.8 128.71)
		(width 0.09)
		(layer "In2.Cu")
		(net 249)
	)
	(segment
		(start 213.161502 129.501502)
		(end 213.230287 129.461789)
		(width 0.09)
		(layer "In2.Cu")
		(net 249)
	)
	(segment
		(start 212.015388 131.675)
		(end 212.075388 131.675)
		(width 0.09)
		(layer "In2.Cu")
		(net 249)
	)
	(segment
		(start 213.47 129.76)
		(end 213.27 129.76)
		(width 0.09)
		(layer "In2.Cu")
		(net 249)
	)
	(segment
		(start 212.195388 131.555)
		(end 212.195388 130.982965)
		(width 0.09)
		(layer "In2.Cu")
		(net 249)
	)
	(segment
		(start 213.54 128.6)
		(end 213.4435 128.6965)
		(width 0.09)
		(layer "In2.Cu")
		(net 249)
	)
	(segment
		(start 213.12 129.61)
		(end 213.121789 129.570287)
		(width 0.09)
		(layer "In2.Cu")
		(net 249)
	)
	(segment
		(start 210.0355 131.675)
		(end 210.275388 131.675)
		(width 0.09)
		(layer "In2.Cu")
		(net 249)
	)
	(segment
		(start 214.18 129.11)
		(end 214.3 128.99)
		(width 0.09)
		(layer "In2.Cu")
		(net 249)
	)
	(segment
		(start 213.62 129.21)
		(end 213.72 129.11)
		(width 0.09)
		(layer "In2.Cu")
		(net 249)
	)
	(segment
		(start 211.115388 131.362959)
		(end 211.175388 131.362959)
		(width 0.09)
		(layer "In2.Cu")
		(net 249)
	)
	(segment
		(start 213.62 129.91)
		(end 213.618211 129.870287)
		(width 0.09)
		(layer "In2.Cu")
		(net 249)
	)
	(segment
		(start 212.615388 131.675)
		(end 212.675388 131.675)
		(width 0.09)
		(layer "In2.Cu")
		(net 249)
	)
	(segment
		(start 213.618211 129.870287)
		(end 213.578498 129.801502)
		(width 0.09)
		(layer "In2.Cu")
		(net 249)
	)
	(segment
		(start 213.161502 129.718498)
		(end 213.121789 129.649713)
		(width 0.09)
		(layer "In2.Cu")
		(net 249)
	)
	(segment
		(start 211.295388 131.482959)
		(end 211.295388 131.555)
		(width 0.09)
		(layer "In2.Cu")
		(net 249)
	)
	(segment
		(start 214.3 128.99)
		(end 214.3 128.81)
		(width 0.09)
		(layer "In2.Cu")
		(net 249)
	)
	(segment
		(start 210.995388 131.555)
		(end 210.995388 131.482959)
		(width 0.09)
		(layer "In2.Cu")
		(net 249)
	)
	(segment
		(start 213.156907 131.675)
		(end 213.7535 131.078407)
		(width 0.09)
		(layer "In2.Cu")
		(net 249)
	)
	(segment
		(start 210.395388 131.555)
		(end 210.395388 131.532959)
		(width 0.09)
		(layer "In2.Cu")
		(net 249)
	)
	(segment
		(start 213.7535 130.821593)
		(end 213.62 130.688093)
		(width 0.09)
		(layer "In2.Cu")
		(net 249)
	)
	(segment
		(start 214.3 128.81)
		(end 214.2 128.71)
		(width 0.09)
		(layer "In2.Cu")
		(net 249)
	)
	(segment
		(start 213.62 130.688093)
		(end 213.62 129.91)
		(width 0.09)
		(layer "In2.Cu")
		(net 249)
	)
	(segment
		(start 213.27 129.46)
		(end 213.47 129.46)
		(width 0.09)
		(layer "In2.Cu")
		(net 249)
	)
	(segment
		(start 213.121789 129.570287)
		(end 213.161502 129.501502)
		(width 0.09)
		(layer "In2.Cu")
		(net 249)
	)
	(segment
		(start 210.515388 131.412959)
		(end 210.575388 131.412959)
		(width 0.09)
		(layer "In2.Cu")
		(net 249)
	)
	(segment
		(start 213.230287 129.758211)
		(end 213.161502 129.718498)
		(width 0.09)
		(layer "In2.Cu")
		(net 249)
	)
	(segment
		(start 211.415388 131.675)
		(end 211.475388 131.675)
		(width 0.09)
		(layer "In2.Cu")
		(net 249)
	)
	(segment
		(start 212.675388 131.675)
		(end 212.999127 131.675)
		(width 0.09)
		(layer "In2.Cu")
		(net 249)
	)
	(segment
		(start 213.7535 131.078407)
		(end 213.7535 130.821593)
		(width 0.09)
		(layer "In2.Cu")
		(net 249)
	)
	(segment
		(start 213.27 129.76)
		(end 213.230287 129.758211)
		(width 0.09)
		(layer "In2.Cu")
		(net 249)
	)
	(segment
		(start 211.715388 131.362959)
		(end 211.775388 131.362959)
		(width 0.09)
		(layer "In2.Cu")
		(net 249)
	)
	(segment
		(start 213.47 129.46)
		(end 213.509713 129.458211)
		(width 0.09)
		(layer "In2.Cu")
		(net 249)
	)
	(segment
		(start 210.815388 131.675)
		(end 210.875388 131.675)
		(width 0.09)
		(layer "In2.Cu")
		(net 249)
	)
	(segment
		(start 213.72 129.11)
		(end 214.18 129.11)
		(width 0.09)
		(layer "In2.Cu")
		(net 249)
	)
	(segment
		(start 213.230287 129.461789)
		(end 213.27 129.46)
		(width 0.09)
		(layer "In2.Cu")
		(net 249)
	)
	(segment
		(start 213.509713 129.761789)
		(end 213.47 129.76)
		(width 0.09)
		(layer "In2.Cu")
		(net 249)
	)
	(segment
		(start 213.4435 128.6965)
		(end 213.4435 128.95)
		(width 0.09)
		(layer "In2.Cu")
		(net 249)
	)
	(segment
		(start 211.595388 131.555)
		(end 211.595388 131.482959)
		(width 0.09)
		(layer "In2.Cu")
		(net 249)
	)
	(segment
		(start 213.121789 129.649713)
		(end 213.12 129.61)
		(width 0.09)
		(layer "In2.Cu")
		(net 249)
	)
	(segment
		(start 209.7075 131.347)
		(end 210.0355 131.675)
		(width 0.09)
		(layer "In2.Cu")
		(net 249)
	)
	(segment
		(start 210.695388 131.532959)
		(end 210.695388 131.555)
		(width 0.09)
		(layer "In2.Cu")
		(net 249)
	)
	(segment
		(start 212.315388 130.862965)
		(end 212.375388 130.862965)
		(width 0.09)
		(layer "In2.Cu")
		(net 249)
	)
	(segment
		(start 213.62 129.31)
		(end 213.62 129.21)
		(width 0.09)
		(layer "In2.Cu")
		(net 249)
	)
	(segment
		(start 211.895388 131.482959)
		(end 211.895388 131.555)
		(width 0.09)
		(layer "In2.Cu")
		(net 249)
	)
	(segment
		(start 213.578498 129.801502)
		(end 213.509713 129.761789)
		(width 0.09)
		(layer "In2.Cu")
		(net 249)
	)
	(segment
		(start 213.8 128.71)
		(end 213.69 128.6)
		(width 0.09)
		(layer "In2.Cu")
		(net 249)
	)
	(segment
		(start 212.999127 131.675)
		(end 213.156907 131.675)
		(width 0.09)
		(layer "In2.Cu")
		(net 249)
	)
	(segment
		(start 213.578498 129.418498)
		(end 213.618211 129.349713)
		(width 0.09)
		(layer "In2.Cu")
		(net 249)
	)
	(segment
		(start 213.618211 129.349713)
		(end 213.62 129.31)
		(width 0.09)
		(layer "In2.Cu")
		(net 249)
	)
	(segment
		(start 213.69 128.6)
		(end 213.54 128.6)
		(width 0.09)
		(layer "In2.Cu")
		(net 249)
	)
	(segment
		(start 213.509713 129.458211)
		(end 213.578498 129.418498)
		(width 0.09)
		(layer "In2.Cu")
		(net 249)
	)
	(segment
		(start 212.495388 130.982965)
		(end 212.495388 131.555)
		(width 0.09)
		(layer "In2.Cu")
		(net 249)
	)
	(arc
		(start 211.775388 131.362959)
		(mid 211.860241 131.398106)
		(end 211.895388 131.482959)
		(width 0.09)
		(layer "In2.Cu")
		(net 249)
	)
	(arc
		(start 212.195388 130.982965)
		(mid 212.230535 130.898112)
		(end 212.315388 130.862965)
		(width 0.09)
		(layer "In2.Cu")
		(net 249)
	)
	(arc
		(start 212.375388 130.862965)
		(mid 212.460241 130.898112)
		(end 212.495388 130.982965)
		(width 0.09)
		(layer "In2.Cu")
		(net 249)
	)
	(arc
		(start 211.595388 131.482959)
		(mid 211.630535 131.398106)
		(end 211.715388 131.362959)
		(width 0.09)
		(layer "In2.Cu")
		(net 249)
	)
	(arc
		(start 211.895388 131.555)
		(mid 211.930535 131.639853)
		(end 212.015388 131.675)
		(width 0.09)
		(layer "In2.Cu")
		(net 249)
	)
	(arc
		(start 212.495388 131.555)
		(mid 212.530535 131.639853)
		(end 212.615388 131.675)
		(width 0.09)
		(layer "In2.Cu")
		(net 249)
	)
	(arc
		(start 210.875388 131.675)
		(mid 210.960241 131.639853)
		(end 210.995388 131.555)
		(width 0.09)
		(layer "In2.Cu")
		(net 249)
	)
	(arc
		(start 210.995388 131.482959)
		(mid 211.030535 131.398106)
		(end 211.115388 131.362959)
		(width 0.09)
		(layer "In2.Cu")
		(net 249)
	)
	(arc
		(start 211.475388 131.675)
		(mid 211.560241 131.639853)
		(end 211.595388 131.555)
		(width 0.09)
		(layer "In2.Cu")
		(net 249)
	)
	(arc
		(start 210.275388 131.675)
		(mid 210.360241 131.639853)
		(end 210.395388 131.555)
		(width 0.09)
		(layer "In2.Cu")
		(net 249)
	)
	(arc
		(start 212.075388 131.675)
		(mid 212.160241 131.639853)
		(end 212.195388 131.555)
		(width 0.09)
		(layer "In2.Cu")
		(net 249)
	)
	(arc
		(start 211.175388 131.362959)
		(mid 211.260241 131.398106)
		(end 211.295388 131.482959)
		(width 0.09)
		(layer "In2.Cu")
		(net 249)
	)
	(arc
		(start 211.295388 131.555)
		(mid 211.330535 131.639853)
		(end 211.415388 131.675)
		(width 0.09)
		(layer "In2.Cu")
		(net 249)
	)
	(arc
		(start 210.395388 131.532959)
		(mid 210.430535 131.448106)
		(end 210.515388 131.412959)
		(width 0.09)
		(layer "In2.Cu")
		(net 249)
	)
	(arc
		(start 210.695388 131.555)
		(mid 210.730535 131.639853)
		(end 210.815388 131.675)
		(width 0.09)
		(layer "In2.Cu")
		(net 249)
	)
	(arc
		(start 210.575388 131.412959)
		(mid 210.660241 131.448106)
		(end 210.695388 131.532959)
		(width 0.09)
		(layer "In2.Cu")
		(net 249)
	)
	(segment
		(start 212.4435 128.95)
		(end 211.92 128.4265)
		(width 0.15)
		(layer "F.Cu")
		(net 250)
	)
	(segment
		(start 211.92 128.4265)
		(end 211.92 128)
		(width 0.15)
		(layer "F.Cu")
		(net 250)
	)
	(via
		(at 209.7075 132.347)
		(size 0.35)
		(drill 0.15)
		(layers "F.Cu" "B.Cu")
		(net 250)
	)
	(via
		(at 211.92 128)
		(size 0.35)
		(drill 0.15)
		(layers "F.Cu" "B.Cu")
		(net 250)
	)
	(segment
		(start 205.024365 123.531804)
		(end 205.69 124.197439)
		(width 0.15)
		(layer "B.Cu")
		(net 250)
	)
	(segment
		(start 204.472822 123.256033)
		(end 204.472823 123.256033)
		(width 0.15)
		(layer "B.Cu")
		(net 250)
	)
	(segment
		(start 204.472823 123.256033)
		(end 204.218264 123.510591)
		(width 0.15)
		(layer "B.Cu")
		(net 250)
	)
	(segment
		(start 203.54684 122.248)
		(end 203.740561 122.248)
		(width 0.15)
		(layer "B.Cu")
		(net 250)
	)
	(segment
		(start 203.942492 123.23482)
		(end 204.19705 122.980261)
		(width 0.15)
		(layer "B.Cu")
		(net 250)
	)
	(segment
		(start 206.47 129.1095)
		(end 209.7075 132.347)
		(width 0.15)
		(layer "B.Cu")
		(net 250)
	)
	(segment
		(start 203.942492 123.234819)
		(end 203.942492 123.23482)
		(width 0.15)
		(layer "B.Cu")
		(net 250)
	)
	(segment
		(start 203.921279 122.70449)
		(end 203.92128 122.70449)
		(width 0.15)
		(layer "B.Cu")
		(net 250)
	)
	(segment
		(start 209.7125 132.347)
		(end 209.7075 132.347)
		(width 0.15)
		(layer "B.Cu")
		(net 250)
	)
	(segment
		(start 203.92128 122.70449)
		(end 203.666721 122.959048)
		(width 0.15)
		(layer "B.Cu")
		(net 250)
	)
	(segment
		(start 204.494035 123.786363)
		(end 204.748593 123.531804)
		(width 0.15)
		(layer "B.Cu")
		(net 250)
	)
	(segment
		(start 205.69 127.396439)
		(end 206.47 128.176439)
		(width 0.15)
		(layer "B.Cu")
		(net 250)
	)
	(segment
		(start 204.494035 123.786362)
		(end 204.494035 123.786363)
		(width 0.15)
		(layer "B.Cu")
		(net 250)
	)
	(segment
		(start 203.740561 122.248)
		(end 203.92128 122.428719)
		(width 0.15)
		(layer "B.Cu")
		(net 250)
	)
	(segment
		(start 206.47 128.176439)
		(end 206.47 129.1095)
		(width 0.15)
		(layer "B.Cu")
		(net 250)
	)
	(segment
		(start 205.69 124.197439)
		(end 205.69 127.396439)
		(width 0.15)
		(layer "B.Cu")
		(net 250)
	)
	(segment
		(start 204.472822 122.980261)
		(end 204.472823 122.980262)
		(width 0.15)
		(layer "B.Cu")
		(net 250)
	)
	(arc
		(start 203.666721 122.959048)
		(mid 203.609607 123.096934)
		(end 203.666721 123.23482)
		(width 0.15)
		(layer "B.Cu")
		(net 250)
	)
	(arc
		(start 204.472823 122.980262)
		(mid 204.529937 123.118148)
		(end 204.472822 123.256033)
		(width 0.15)
		(layer "B.Cu")
		(net 250)
	)
	(arc
		(start 204.218264 123.786363)
		(mid 204.35615 123.843477)
		(end 204.494035 123.786362)
		(width 0.15)
		(layer "B.Cu")
		(net 250)
	)
	(arc
		(start 204.218264 123.510591)
		(mid 204.16115 123.648477)
		(end 204.218264 123.786363)
		(width 0.15)
		(layer "B.Cu")
		(net 250)
	)
	(arc
		(start 204.748593 123.531804)
		(mid 204.886479 123.47469)
		(end 205.024365 123.531804)
		(width 0.15)
		(layer "B.Cu")
		(net 250)
	)
	(arc
		(start 203.92128 122.428719)
		(mid 203.978394 122.566605)
		(end 203.921279 122.70449)
		(width 0.15)
		(layer "B.Cu")
		(net 250)
	)
	(arc
		(start 203.666721 123.23482)
		(mid 203.804607 123.291934)
		(end 203.942492 123.234819)
		(width 0.15)
		(layer "B.Cu")
		(net 250)
	)
	(arc
		(start 204.19705 122.980261)
		(mid 204.334936 122.923147)
		(end 204.472822 122.980261)
		(width 0.15)
		(layer "B.Cu")
		(net 250)
	)
	(segment
		(start 209.58 128.69)
		(end 210.31 128.69)
		(width 0.09)
		(layer "In2.Cu")
		(net 250)
	)
	(segment
		(start 209.257525 128.687209)
		(end 209.335307 128.764991)
		(width 0.09)
		(layer "In2.Cu")
		(net 250)
	)
	(segment
		(start 209.27 130.420138)
		(end 209.16 130.420138)
		(width 0.09)
		(layer "In2.Cu")
		(net 250)
	)
	(segment
		(start 209.39 130.240138)
		(end 209.39 130.300138)
		(width 0.09)
		(layer "In2.Cu")
		(net 250)
	)
	(segment
		(start 209.045393 128.729634)
		(end 209.087819 128.687209)
		(width 0.09)
		(layer "In2.Cu")
		(net 250)
	)
	(segment
		(start 209.04 130.600138)
		(end 209.04 130.627241)
		(width 0.09)
		(layer "In2.Cu")
		(net 250)
	)
	(segment
		(start 209.04 130.540138)
		(end 209.04 130.600138)
		(width 0.09)
		(layer "In2.Cu")
		(net 250)
	)
	(segment
		(start 209.04 129.400138)
		(end 209.04 129.23)
		(width 0.09)
		(layer "In2.Cu")
		(net 250)
	)
	(segment
		(start 209.505013 128.764991)
		(end 209.547439 128.722562)
		(width 0.09)
		(layer "In2.Cu")
		(net 250)
	)
	(segment
		(start 209.04 131.6795)
		(end 209.7075 132.347)
		(width 0.09)
		(layer "In2.Cu")
		(net 250)
	)
	(segment
		(start 209.565178 128.704822)
		(end 209.58 128.69)
		(width 0.09)
		(layer "In2.Cu")
		(net 250)
	)
	(segment
		(start 209.04 130.627241)
		(end 209.04 131.6795)
		(width 0.09)
		(layer "In2.Cu")
		(net 250)
	)
	(segment
		(start 209.16 130.120138)
		(end 209.27 130.120138)
		(width 0.09)
		(layer "In2.Cu")
		(net 250)
	)
	(segment
		(start 209.16 129.520138)
		(end 209.22 129.520138)
		(width 0.09)
		(layer "In2.Cu")
		(net 250)
	)
	(segment
		(start 209.123174 128.977121)
		(end 209.045393 128.89934)
		(width 0.09)
		(layer "In2.Cu")
		(net 250)
	)
	(segment
		(start 209.547439 128.722562)
		(end 209.565178 128.704822)
		(width 0.09)
		(layer "In2.Cu")
		(net 250)
	)
	(segment
		(start 209.34 129.640138)
		(end 209.34 129.700138)
		(width 0.09)
		(layer "In2.Cu")
		(net 250)
	)
	(segment
		(start 209.04 129.23)
		(end 209.123173 129.146827)
		(width 0.09)
		(layer "In2.Cu")
		(net 250)
	)
	(segment
		(start 209.22 129.820138)
		(end 209.16 129.820138)
		(width 0.09)
		(layer "In2.Cu")
		(net 250)
	)
	(segment
		(start 211.62 127.7)
		(end 211.92 128)
		(width 0.09)
		(layer "In2.Cu")
		(net 250)
	)
	(segment
		(start 209.04 129.940138)
		(end 209.04 130.000138)
		(width 0.09)
		(layer "In2.Cu")
		(net 250)
	)
	(segment
		(start 210.31 128.69)
		(end 211.3 127.7)
		(width 0.09)
		(layer "In2.Cu")
		(net 250)
	)
	(segment
		(start 211.3 127.7)
		(end 211.62 127.7)
		(width 0.09)
		(layer "In2.Cu")
		(net 250)
	)
	(arc
		(start 209.22 129.520138)
		(mid 209.304853 129.555285)
		(end 209.34 129.640138)
		(width 0.09)
		(layer "In2.Cu")
		(net 250)
	)
	(arc
		(start 209.27 130.120138)
		(mid 209.354853 130.155285)
		(end 209.39 130.240138)
		(width 0.09)
		(layer "In2.Cu")
		(net 250)
	)
	(arc
		(start 209.087819 128.687209)
		(mid 209.172672 128.652062)
		(end 209.257525 128.687209)
		(width 0.09)
		(layer "In2.Cu")
		(net 250)
	)
	(arc
		(start 209.04 130.000138)
		(mid 209.075147 130.084991)
		(end 209.16 130.120138)
		(width 0.09)
		(layer "In2.Cu")
		(net 250)
	)
	(arc
		(start 209.045393 128.89934)
		(mid 209.010246 128.814487)
		(end 209.045393 128.729634)
		(width 0.09)
		(layer "In2.Cu")
		(net 250)
	)
	(arc
		(start 209.123173 129.146827)
		(mid 209.158321 129.061974)
		(end 209.123174 128.977121)
		(width 0.09)
		(layer "In2.Cu")
		(net 250)
	)
	(arc
		(start 209.335307 128.764991)
		(mid 209.42016 128.800138)
		(end 209.505013 128.764991)
		(width 0.09)
		(layer "In2.Cu")
		(net 250)
	)
	(arc
		(start 209.16 130.420138)
		(mid 209.075147 130.455285)
		(end 209.04 130.540138)
		(width 0.09)
		(layer "In2.Cu")
		(net 250)
	)
	(arc
		(start 209.16 129.820138)
		(mid 209.075147 129.855285)
		(end 209.04 129.940138)
		(width 0.09)
		(layer "In2.Cu")
		(net 250)
	)
	(arc
		(start 209.39 130.300138)
		(mid 209.354853 130.384991)
		(end 209.27 130.420138)
		(width 0.09)
		(layer "In2.Cu")
		(net 250)
	)
	(arc
		(start 209.34 129.700138)
		(mid 209.304853 129.784991)
		(end 209.22 129.820138)
		(width 0.09)
		(layer "In2.Cu")
		(net 250)
	)
	(arc
		(start 209.04 129.400138)
		(mid 209.075147 129.484991)
		(end 209.16 129.520138)
		(width 0.09)
		(layer "In2.Cu")
		(net 250)
	)
	(segment
		(start 202.54884 122.2)
		(end 202.50084 122.2)
		(width 0.15)
		(layer "F.Cu")
		(net 251)
	)
	(segment
		(start 202.50084 122.2)
		(end 202.14884 121.848)
		(width 0.15)
		(layer "F.Cu")
		(net 251)
	)
	(via
		(at 199.699 128.3)
		(size 0.35)
		(drill 0.15)
		(layers "F.Cu" "B.Cu")
		(remove_unused_layers yes)
		(keep_end_layers yes)
		(zone_layer_connections)
		(net 251)
	)
	(via
		(at 202.54884 122.2)
		(size 0.35)
		(drill 0.15)
		(layers "F.Cu" "B.Cu")
		(remove_unused_layers yes)
		(keep_end_layers yes)
		(zone_layer_connections)
		(net 251)
	)
	(segment
		(start 202.59684 122.248)
		(end 202.54884 122.2)
		(width 0.15)
		(layer "B.Cu")
		(net 251)
	)
	(segment
		(start 202.94884 122.248)
		(end 202.59684 122.248)
		(width 0.15)
		(layer "B.Cu")
		(net 251)
	)
	(segment
		(start 200.09 123.81)
		(end 201.275 122.625)
		(width 0.09)
		(layer "In4.Cu")
		(net 251)
	)
	(segment
		(start 200.25 126.165)
		(end 200.23 126.165)
		(width 0.09)
		(layer "In4.Cu")
		(net 251)
	)
	(segment
		(start 200.29 124.7)
		(end 200.29 124.62)
		(width 0.09)
		(layer "In4.Cu")
		(net 251)
	)
	(segment
		(start 199.699 128.3)
		(end 199.699 128.651)
		(width 0.09)
		(layer "In4.Cu")
		(net 251)
	)
	(segment
		(start 199.375 128.975)
		(end 199.125 128.975)
		(width 0.09)
		(layer "In4.Cu")
		(net 251)
	)
	(segment
		(start 202.06 122.625)
		(end 202.12384 122.625)
		(width 0.09)
		(layer "In4.Cu")
		(net 251)
	)
	(segment
		(start 200.09 124.42)
		(end 200.09 123.81)
		(width 0.09)
		(layer "In4.Cu")
		(net 251)
	)
	(segment
		(start 200.09 126.865)
		(end 200.09 126.585)
		(width 0.09)
		(layer "In4.Cu")
		(net 251)
	)
	(segment
		(start 199.699 128.651)
		(end 199.375 128.975)
		(width 0.09)
		(layer "In4.Cu")
		(net 251)
	)
	(segment
		(start 199.9 127.85)
		(end 200.33 127.42)
		(width 0.09)
		(layer "In4.Cu")
		(net 251)
	)
	(segment
		(start 200.09 125.22)
		(end 200.09 124.9)
		(width 0.09)
		(layer "In4.Cu")
		(net 251)
	)
	(segment
		(start 200.09 126.025)
		(end 200.09 125.8)
		(width 0.09)
		(layer "In4.Cu")
		(net 251)
	)
	(segment
		(start 198.675 128)
		(end 198.825 127.85)
		(width 0.09)
		(layer "In4.Cu")
		(net 251)
	)
	(segment
		(start 198.675 128.525)
		(end 198.675 128)
		(width 0.09)
		(layer "In4.Cu")
		(net 251)
	)
	(segment
		(start 198.825 127.85)
		(end 198.925 127.85)
		(width 0.09)
		(layer "In4.Cu")
		(net 251)
	)
	(segment
		(start 200.23 126.445)
		(end 200.25 126.445)
		(width 0.09)
		(layer "In4.Cu")
		(net 251)
	)
	(segment
		(start 200.33 127.42)
		(end 200.33 127.105)
		(width 0.09)
		(layer "In4.Cu")
		(net 251)
	)
	(segment
		(start 199.065 127.99)
		(end 199.065 128.46)
		(width 0.09)
		(layer "In4.Cu")
		(net 251)
	)
	(segment
		(start 201.92 121.865)
		(end 201.92 122.485)
		(width 0.09)
		(layer "In4.Cu")
		(net 251)
	)
	(segment
		(start 200.33 127.105)
		(end 200.09 126.865)
		(width 0.09)
		(layer "In4.Cu")
		(net 251)
	)
	(segment
		(start 199.125 128.975)
		(end 198.675 128.525)
		(width 0.09)
		(layer "In4.Cu")
		(net 251)
	)
	(segment
		(start 199.345 128.46)
		(end 199.345 127.99)
		(width 0.09)
		(layer "In4.Cu")
		(net 251)
	)
	(segment
		(start 202.12384 122.625)
		(end 202.54884 122.2)
		(width 0.09)
		(layer "In4.Cu")
		(net 251)
	)
	(segment
		(start 201.64 122.485)
		(end 201.64 121.865)
		(width 0.09)
		(layer "In4.Cu")
		(net 251)
	)
	(segment
		(start 201.275 122.625)
		(end 201.5 122.625)
		(width 0.09)
		(layer "In4.Cu")
		(net 251)
	)
	(segment
		(start 200.34 125.55)
		(end 200.34 125.47)
		(width 0.09)
		(layer "In4.Cu")
		(net 251)
	)
	(segment
		(start 199.485 127.85)
		(end 199.9 127.85)
		(width 0.09)
		(layer "In4.Cu")
		(net 251)
	)
	(arc
		(start 201.64 121.865)
		(mid 201.681005 121.766005)
		(end 201.78 121.725)
		(width 0.09)
		(layer "In4.Cu")
		(net 251)
	)
	(arc
		(start 199.205 128.6)
		(mid 199.303995 128.558995)
		(end 199.345 128.46)
		(width 0.09)
		(layer "In4.Cu")
		(net 251)
	)
	(arc
		(start 198.925 127.85)
		(mid 199.023995 127.891005)
		(end 199.065 127.99)
		(width 0.09)
		(layer "In4.Cu")
		(net 251)
	)
	(arc
		(start 200.215 125.345)
		(mid 200.126612 125.308388)
		(end 200.09 125.22)
		(width 0.09)
		(layer "In4.Cu")
		(net 251)
	)
	(arc
		(start 200.29 124.62)
		(mid 200.260711 124.549289)
		(end 200.19 124.52)
		(width 0.09)
		(layer "In4.Cu")
		(net 251)
	)
	(arc
		(start 200.215 125.675)
		(mid 200.303388 125.638388)
		(end 200.34 125.55)
		(width 0.09)
		(layer "In4.Cu")
		(net 251)
	)
	(arc
		(start 201.5 122.625)
		(mid 201.598995 122.583995)
		(end 201.64 122.485)
		(width 0.09)
		(layer "In4.Cu")
		(net 251)
	)
	(arc
		(start 200.39 126.305)
		(mid 200.348995 126.206005)
		(end 200.25 126.165)
		(width 0.09)
		(layer "In4.Cu")
		(net 251)
	)
	(arc
		(start 200.09 124.9)
		(mid 200.119289 124.829289)
		(end 200.19 124.8)
		(width 0.09)
		(layer "In4.Cu")
		(net 251)
	)
	(arc
		(start 200.09 126.585)
		(mid 200.131005 126.486005)
		(end 200.23 126.445)
		(width 0.09)
		(layer "In4.Cu")
		(net 251)
	)
	(arc
		(start 200.25 126.445)
		(mid 200.348995 126.403995)
		(end 200.39 126.305)
		(width 0.09)
		(layer "In4.Cu")
		(net 251)
	)
	(arc
		(start 200.34 125.47)
		(mid 200.303388 125.381612)
		(end 200.215 125.345)
		(width 0.09)
		(layer "In4.Cu")
		(net 251)
	)
	(arc
		(start 201.92 122.485)
		(mid 201.961005 122.583995)
		(end 202.06 122.625)
		(width 0.09)
		(layer "In4.Cu")
		(net 251)
	)
	(arc
		(start 199.065 128.46)
		(mid 199.106005 128.558995)
		(end 199.205 128.6)
		(width 0.09)
		(layer "In4.Cu")
		(net 251)
	)
	(arc
		(start 200.23 126.165)
		(mid 200.131005 126.123995)
		(end 200.09 126.025)
		(width 0.09)
		(layer "In4.Cu")
		(net 251)
	)
	(arc
		(start 200.09 125.8)
		(mid 200.126612 125.711612)
		(end 200.215 125.675)
		(width 0.09)
		(layer "In4.Cu")
		(net 251)
	)
	(arc
		(start 200.19 124.8)
		(mid 200.260711 124.770711)
		(end 200.29 124.7)
		(width 0.09)
		(layer "In4.Cu")
		(net 251)
	)
	(arc
		(start 201.78 121.725)
		(mid 201.878995 121.766005)
		(end 201.92 121.865)
		(width 0.09)
		(layer "In4.Cu")
		(net 251)
	)
	(arc
		(start 200.19 124.52)
		(mid 200.119289 124.490711)
		(end 200.09 124.42)
		(width 0.09)
		(layer "In4.Cu")
		(net 251)
	)
	(arc
		(start 199.345 127.99)
		(mid 199.386005 127.891005)
		(end 199.485 127.85)
		(width 0.09)
		(layer "In4.Cu")
		(net 251)
	)
	(segment
		(start 202.94884 121.85)
		(end 202.54884 121.45)
		(width 0.15)
		(layer "F.Cu")
		(net 252)
	)
	(segment
		(start 202.54884 121.45)
		(end 202.14884 121.45)
		(width 0.15)
		(layer "F.Cu")
		(net 252)
	)
	(via
		(at 199.699 125.901)
		(size 0.35)
		(drill 0.15)
		(layers "F.Cu" "B.Cu")
		(remove_unused_layers yes)
		(keep_end_layers yes)
		(zone_layer_connections)
		(net 252)
	)
	(via
		(at 202.94884 121.85)
		(size 0.35)
		(drill 0.15)
		(layers "F.Cu" "B.Cu")
		(remove_unused_layers yes)
		(keep_end_layers yes)
		(zone_layer_connections)
		(net 252)
	)
	(segment
		(start 201.405 120.878)
		(end 201.406393 120.840484)
		(width 0.09)
		(layer "In4.Cu")
		(net 252)
	)
	(segment
		(start 202.445 121.798)
		(end 202.445 121.678)
		(width 0.09)
		(layer "In4.Cu")
		(net 252)
	)
	(segment
		(start 199.6 123.31)
		(end 199.6 121.66)
		(width 0.09)
		(layer "In4.Cu")
		(net 252)
	)
	(segment
		(start 199.73 125.5)
		(end 199.698807 125.5)
		(width 0.09)
		(layer "In4.Cu")
		(net 252)
	)
	(segment
		(start 202.443381 121.835079)
		(end 202.445 121.798)
		(width 0.09)
		(layer "In4.Cu")
		(net 252)
	)
	(segment
		(start 201.405 121.348)
		(end 201.405 120.878)
		(width 0.09)
		(layer "In4.Cu")
		(net 252)
	)
	(segment
		(start 199.699 125.901)
		(end 199.87 125.73)
		(width 0.09)
		(layer "In4.Cu")
		(net 252)
	)
	(segment
		(start 202.406302 121.899302)
		(end 202.443381 121.835079)
		(width 0.09)
		(layer "In4.Cu")
		(net 252)
	)
	(segment
		(start 201.557484 120.689393)
		(end 201.595 120.688)
		(width 0.09)
		(layer "In4.Cu")
		(net 252)
	)
	(segment
		(start 200.475 122.735)
		(end 200.475 122.855)
		(width 0.09)
		(layer "In4.Cu")
		(net 252)
	)
	(segment
		(start 201.435107 120.771163)
		(end 201.488163 120.718107)
		(width 0.09)
		(layer "In4.Cu")
		(net 252)
	)
	(segment
		(start 202.166619 121.835079)
		(end 202.203698 121.899302)
		(width 0.09)
		(layer "In4.Cu")
		(net 252)
	)
	(segment
		(start 199.87 125.08)
		(end 199.87 124.97)
		(width 0.09)
		(layer "In4.Cu")
		(net 252)
	)
	(segment
		(start 202.445 121.678)
		(end 202.446619 121.640921)
		(width 0.09)
		(layer "In4.Cu")
		(net 252)
	)
	(segment
		(start 200.88 122.34)
		(end 200.36 122.34)
		(width 0.09)
		(layer "In4.Cu")
		(net 252)
	)
	(segment
		(start 199.8 121.57)
		(end 199.89 121.66)
		(width 0.09)
		(layer "In4.Cu")
		(net 252)
	)
	(segment
		(start 201.632516 120.689393)
		(end 201.701837 120.718107)
		(width 0.09)
		(layer "In4.Cu")
		(net 252)
	)
	(segment
		(start 199.8 123.54)
		(end 199.8 123.51)
		(width 0.09)
		(layer "In4.Cu")
		(net 252)
	)
	(segment
		(start 202.305 121.938)
		(end 202.342079 121.936381)
		(width 0.09)
		(layer "In4.Cu")
		(net 252)
	)
	(segment
		(start 202.165 121.798)
		(end 202.166619 121.835079)
		(width 0.09)
		(layer "In4.Cu")
		(net 252)
	)
	(segment
		(start 202.549222 121.380778)
		(end 202.910778 121.380778)
		(width 0.09)
		(layer "In4.Cu")
		(net 252)
	)
	(segment
		(start 201.868163 121.507893)
		(end 201.937484 121.536607)
		(width 0.09)
		(layer "In4.Cu")
		(net 252)
	)
	(segment
		(start 201.785 120.878)
		(end 201.785 121.348)
		(width 0.09)
		(layer "In4.Cu")
		(net 252)
	)
	(segment
		(start 202.910778 121.380778)
		(end 202.94884 121.41884)
		(width 0.09)
		(layer "In4.Cu")
		(net 252)
	)
	(segment
		(start 199.6 121.66)
		(end 199.69 121.57)
		(width 0.09)
		(layer "In4.Cu")
		(net 252)
	)
	(segment
		(start 199.6 123.825)
		(end 199.6 123.74)
		(width 0.09)
		(layer "In4.Cu")
		(net 252)
	)
	(segment
		(start 202.163381 121.640921)
		(end 202.165 121.678)
		(width 0.09)
		(layer "In4.Cu")
		(net 252)
	)
	(segment
		(start 202.025 121.538)
		(end 202.062079 121.539619)
		(width 0.09)
		(layer "In4.Cu")
		(net 252)
	)
	(segment
		(start 202.062079 121.539619)
		(end 202.126302 121.576698)
		(width 0.09)
		(layer "In4.Cu")
		(net 252)
	)
	(segment
		(start 201.374893 121.454837)
		(end 201.403607 121.385516)
		(width 0.09)
		(layer "In4.Cu")
		(net 252)
	)
	(segment
		(start 199.698807 125.22)
		(end 199.73 125.22)
		(width 0.09)
		(layer "In4.Cu")
		(net 252)
	)
	(segment
		(start 202.483698 121.576698)
		(end 202.483698 121.446302)
		(width 0.09)
		(layer "In4.Cu")
		(net 252)
	)
	(segment
		(start 201.215 121.538)
		(end 201.252516 121.536607)
		(width 0.09)
		(layer "In4.Cu")
		(net 252)
	)
	(segment
		(start 201.975 121.538)
		(end 202.025 121.538)
		(width 0.09)
		(layer "In4.Cu")
		(net 252)
	)
	(segment
		(start 202.126302 121.576698)
		(end 202.163381 121.640921)
		(width 0.09)
		(layer "In4.Cu")
		(net 252)
	)
	(segment
		(start 200.82 122.62)
		(end 200.88 122.62)
		(width 0.09)
		(layer "In4.Cu")
		(net 252)
	)
	(segment
		(start 199.389 124.489)
		(end 199.389 124.036)
		(width 0.09)
		(layer "In4.Cu")
		(net 252)
	)
	(segment
		(start 202.342079 121.936381)
		(end 202.406302 121.899302)
		(width 0.09)
		(layer "In4.Cu")
		(net 252)
	)
	(segment
		(start 201.937484 121.536607)
		(end 201.975 121.538)
		(width 0.09)
		(layer "In4.Cu")
		(net 252)
	)
	(segment
		(start 202.267921 121.936381)
		(end 202.305 121.938)
		(width 0.09)
		(layer "In4.Cu")
		(net 252)
	)
	(segment
		(start 201.406393 120.840484)
		(end 201.435107 120.771163)
		(width 0.09)
		(layer "In4.Cu")
		(net 252)
	)
	(segment
		(start 202.203698 121.899302)
		(end 202.267921 121.936381)
		(width 0.09)
		(layer "In4.Cu")
		(net 252)
	)
	(segment
		(start 201.815107 121.454837)
		(end 201.868163 121.507893)
		(width 0.09)
		(layer "In4.Cu")
		(net 252)
	)
	(segment
		(start 201.488163 120.718107)
		(end 201.557484 120.689393)
		(width 0.09)
		(layer "In4.Cu")
		(net 252)
	)
	(segment
		(start 200.22 122.2)
		(end 200.22 121.703)
		(width 0.09)
		(layer "In4.Cu")
		(net 252)
	)
	(segment
		(start 202.165 121.678)
		(end 202.165 121.798)
		(width 0.09)
		(layer "In4.Cu")
		(net 252)
	)
	(segment
		(start 202.483698 121.446302)
		(end 202.549222 121.380778)
		(width 0.09)
		(layer "In4.Cu")
		(net 252)
	)
	(segment
		(start 199.87 124.97)
		(end 199.389 124.489)
		(width 0.09)
		(layer "In4.Cu")
		(net 252)
	)
	(segment
		(start 201.785 121.348)
		(end 201.786393 121.385516)
		(width 0.09)
		(layer "In4.Cu")
		(net 252)
	)
	(segment
		(start 201.403607 121.385516)
		(end 201.405 121.348)
		(width 0.09)
		(layer "In4.Cu")
		(net 252)
	)
	(segment
		(start 201.701837 120.718107)
		(end 201.754893 120.771163)
		(width 0.09)
		(layer "In4.Cu")
		(net 252)
	)
	(segment
		(start 202.94884 121.41884)
		(end 202.94884 121.85)
		(width 0.09)
		(layer "In4.Cu")
		(net 252)
	)
	(segment
		(start 201.783607 120.840484)
		(end 201.785 120.878)
		(width 0.09)
		(layer "In4.Cu")
		(net 252)
	)
	(segment
		(start 201.252516 121.536607)
		(end 201.321837 121.507893)
		(width 0.09)
		(layer "In4.Cu")
		(net 252)
	)
	(segment
		(start 201.595 120.688)
		(end 201.632516 120.689393)
		(width 0.09)
		(layer "In4.Cu")
		(net 252)
	)
	(segment
		(start 199.389 124.036)
		(end 199.6 123.825)
		(width 0.09)
		(layer "In4.Cu")
		(net 252)
	)
	(segment
		(start 201.321837 121.507893)
		(end 201.374893 121.454837)
		(width 0.09)
		(layer "In4.Cu")
		(net 252)
	)
	(segment
		(start 202.446619 121.640921)
		(end 202.483698 121.576698)
		(width 0.09)
		(layer "In4.Cu")
		(net 252)
	)
	(segment
		(start 200.705 122.855)
		(end 200.705 122.735)
		(width 0.09)
		(layer "In4.Cu")
		(net 252)
	)
	(segment
		(start 200.385 121.538)
		(end 201.215 121.538)
		(width 0.09)
		(layer "In4.Cu")
		(net 252)
	)
	(segment
		(start 199.87 125.73)
		(end 199.87 125.64)
		(width 0.09)
		(layer "In4.Cu")
		(net 252)
	)
	(segment
		(start 201.754893 120.771163)
		(end 201.783607 120.840484)
		(width 0.09)
		(layer "In4.Cu")
		(net 252)
	)
	(segment
		(start 201.786393 121.385516)
		(end 201.815107 121.454837)
		(width 0.09)
		(layer "In4.Cu")
		(net 252)
	)
	(segment
		(start 199.89 121.66)
		(end 199.89 123.123)
		(width 0.09)
		(layer "In4.Cu")
		(net 252)
	)
	(segment
		(start 200.22 123.123)
		(end 200.22 122.76)
		(width 0.09)
		(layer "In4.Cu")
		(net 252)
	)
	(segment
		(start 199.69 121.57)
		(end 199.8 121.57)
		(width 0.09)
		(layer "In4.Cu")
		(net 252)
	)
	(arc
		(start 200.22 122.76)
		(mid 200.261005 122.661005)
		(end 200.36 122.62)
		(width 0.09)
		(layer "In4.Cu")
		(net 252)
	)
	(arc
		(start 200.705 122.735)
		(mid 200.738683 122.653683)
		(end 200.82 122.62)
		(width 0.09)
		(layer "In4.Cu")
		(net 252)
	)
	(arc
		(start 199.7 123.64)
		(mid 199.770711 123.610711)
		(end 199.8 123.54)
		(width 0.09)
		(layer "In4.Cu")
		(net 252)
	)
	(arc
		(start 200.36 122.34)
		(mid 200.261005 122.298995)
		(end 200.22 122.2)
		(width 0.09)
		(layer "In4.Cu")
		(net 252)
	)
	(arc
		(start 199.7 123.41)
		(mid 199.629289 123.380711)
		(end 199.6 123.31)
		(width 0.09)
		(layer "In4.Cu")
		(net 252)
	)
	(arc
		(start 200.22 121.703)
		(mid 200.268327 121.586327)
		(end 200.385 121.538)
		(width 0.09)
		(layer "In4.Cu")
		(net 252)
	)
	(arc
		(start 200.36 122.62)
		(mid 200.441317 122.653683)
		(end 200.475 122.735)
		(width 0.09)
		(layer "In4.Cu")
		(net 252)
	)
	(arc
		(start 200.88 122.62)
		(mid 200.978995 122.578995)
		(end 201.02 122.48)
		(width 0.09)
		(layer "In4.Cu")
		(net 252)
	)
	(arc
		(start 200.59 122.97)
		(mid 200.671317 122.936317)
		(end 200.705 122.855)
		(width 0.09)
		(layer "In4.Cu")
		(net 252)
	)
	(arc
		(start 200.055 123.288)
		(mid 200.171673 123.239673)
		(end 200.22 123.123)
		(width 0.09)
		(layer "In4.Cu")
		(net 252)
	)
	(arc
		(start 199.6 123.74)
		(mid 199.629289 123.669289)
		(end 199.7 123.64)
		(width 0.09)
		(layer "In4.Cu")
		(net 252)
	)
	(arc
		(start 199.698807 125.5)
		(mid 199.599812 125.458995)
		(end 199.558807 125.36)
		(width 0.09)
		(layer "In4.Cu")
		(net 252)
	)
	(arc
		(start 199.73 125.22)
		(mid 199.828995 125.178995)
		(end 199.87 125.08)
		(width 0.09)
		(layer "In4.Cu")
		(net 252)
	)
	(arc
		(start 199.87 125.64)
		(mid 199.828995 125.541005)
		(end 199.73 125.5)
		(width 0.09)
		(layer "In4.Cu")
		(net 252)
	)
	(arc
		(start 199.89 123.123)
		(mid 199.938327 123.239673)
		(end 200.055 123.288)
		(width 0.09)
		(layer "In4.Cu")
		(net 252)
	)
	(arc
		(start 199.558807 125.36)
		(mid 199.599812 125.261005)
		(end 199.698807 125.22)
		(width 0.09)
		(layer "In4.Cu")
		(net 252)
	)
	(arc
		(start 201.02 122.48)
		(mid 200.978995 122.381005)
		(end 200.88 122.34)
		(width 0.09)
		(layer "In4.Cu")
		(net 252)
	)
	(arc
		(start 200.475 122.855)
		(mid 200.508683 122.936317)
		(end 200.59 122.97)
		(width 0.09)
		(layer "In4.Cu")
		(net 252)
	)
	(arc
		(start 199.8 123.51)
		(mid 199.770711 123.439289)
		(end 199.7 123.41)
		(width 0.09)
		(layer "In4.Cu")
		(net 252)
	)
	(segment
		(start 217.05 124.346321)
		(end 217.05 123.875)
		(width 0.1)
		(layer "F.Cu")
		(net 253)
	)
	(segment
		(start 216.68 125.4)
		(end 217.190999 124.889001)
		(width 0.1)
		(layer "F.Cu")
		(net 253)
	)
	(segment
		(start 217.190999 124.889001)
		(end 217.190999 124.48732)
		(width 0.1)
		(layer "F.Cu")
		(net 253)
	)
	(segment
		(start 217.190999 124.48732)
		(end 217.05 124.346321)
		(width 0.1)
		(layer "F.Cu")
		(net 253)
	)
	(segment
		(start 216.4 125.4)
		(end 216.68 125.4)
		(width 0.1)
		(layer "F.Cu")
		(net 253)
	)
	(via
		(at 224.7 123.9)
		(size 0.35)
		(drill 0.15)
		(layers "F.Cu" "B.Cu")
		(remove_unused_layers yes)
		(keep_end_layers yes)
		(zone_layer_connections)
		(net 253)
	)
	(via
		(at 216.4 125.4)
		(size 0.35)
		(drill 0.15)
		(layers "F.Cu" "B.Cu")
		(remove_unused_layers yes)
		(keep_end_layers yes)
		(zone_layer_connections)
		(net 253)
	)
	(segment
		(start 223.15 123.9)
		(end 222.75 124.3)
		(width 0.09)
		(layer "In9.Cu")
		(net 253)
	)
	(segment
		(start 224.7 123.9)
		(end 223.15 123.9)
		(width 0.09)
		(layer "In9.Cu")
		(net 253)
	)
	(segment
		(start 218.35 124.3)
		(end 217.25 125.4)
		(width 0.09)
		(layer "In9.Cu")
		(net 253)
	)
	(segment
		(start 217.25 125.4)
		(end 216.4 125.4)
		(width 0.09)
		(layer "In9.Cu")
		(net 253)
	)
	(segment
		(start 222.75 124.3)
		(end 218.35 124.3)
		(width 0.09)
		(layer "In9.Cu")
		(net 253)
	)
	(via
		(at 201.3 131.501)
		(size 0.35)
		(drill 0.15)
		(layers "F.Cu" "B.Cu")
		(remove_unused_layers yes)
		(keep_end_layers yes)
		(zone_layer_connections)
		(net 254)
	)
	(segment
		(start 204.174 131.669975)
		(end 204.174 131.51538)
		(width 0.1)
		(layer "B.Cu")
		(net 254)
	)
	(segment
		(start 205.35 132.65)
		(end 205.154025 132.65)
		(width 0.1)
		(layer "B.Cu")
		(net 254)
	)
	(segment
		(start 205.96438 133.427)
		(end 205.774 133.23662)
		(width 0.1)
		(layer "B.Cu")
		(net 254)
	)
	(segment
		(start 205.774 133.23662)
		(end 205.774 133.074)
		(width 0.1)
		(layer "B.Cu")
		(net 254)
	)
	(segment
		(start 204.174 131.51538)
		(end 203.75862 131.1)
		(width 0.1)
		(layer "B.Cu")
		(net 254)
	)
	(segment
		(start 201.701 131.1)
		(end 201.3 131.501)
		(width 0.1)
		(layer "B.Cu")
		(net 254)
	)
	(segment
		(start 205.774 133.074)
		(end 205.35 132.65)
		(width 0.1)
		(layer "B.Cu")
		(net 254)
	)
	(segment
		(start 207.35 134.35)
		(end 206.427 133.427)
		(width 0.1)
		(layer "B.Cu")
		(net 254)
	)
	(segment
		(start 206.427 133.427)
		(end 205.96438 133.427)
		(width 0.1)
		(layer "B.Cu")
		(net 254)
	)
	(segment
		(start 205.154025 132.65)
		(end 204.174 131.669975)
		(width 0.1)
		(layer "B.Cu")
		(net 254)
	)
	(segment
		(start 207.77 134.35)
		(end 207.35 134.35)
		(width 0.1)
		(layer "B.Cu")
		(net 254)
	)
	(segment
		(start 203.75862 131.1)
		(end 201.701 131.1)
		(width 0.1)
		(layer "B.Cu")
		(net 254)
	)
	(via
		(at 200.499 130.701)
		(size 0.35)
		(drill 0.15)
		(layers "F.Cu" "B.Cu")
		(remove_unused_layers yes)
		(keep_end_layers yes)
		(zone_layer_connections)
		(net 255)
	)
	(segment
		(start 207.1 130.75)
		(end 206.65 130.3)
		(width 0.1)
		(layer "B.Cu")
		(net 255)
	)
	(segment
		(start 207.35 133.35)
		(end 207.1 133.1)
		(width 0.1)
		(layer "B.Cu")
		(net 255)
	)
	(segment
		(start 207.77 133.35)
		(end 207.35 133.35)
		(width 0.1)
		(layer "B.Cu")
		(net 255)
	)
	(segment
		(start 207.1 133.1)
		(end 207.1 130.75)
		(width 0.1)
		(layer "B.Cu")
		(net 255)
	)
	(segment
		(start 200.9 130.3)
		(end 200.499 130.701)
		(width 0.1)
		(layer "B.Cu")
		(net 255)
	)
	(segment
		(start 206.65 130.3)
		(end 200.9 130.3)
		(width 0.1)
		(layer "B.Cu")
		(net 255)
	)
	(via
		(at 200.499 132.3)
		(size 0.35)
		(drill 0.15)
		(layers "F.Cu" "B.Cu")
		(remove_unused_layers yes)
		(keep_end_layers yes)
		(zone_layer_connections)
		(net 256)
	)
	(segment
		(start 207.35 135.35)
		(end 206.3 134.3)
		(width 0.1)
		(layer "B.Cu")
		(net 256)
	)
	(segment
		(start 204.85 133.11362)
		(end 204.85 132.85)
		(width 0.1)
		(layer "B.Cu")
		(net 256)
	)
	(segment
		(start 204.85 132.85)
		(end 203.9 131.9)
		(width 0.1)
		(layer "B.Cu")
		(net 256)
	)
	(segment
		(start 203.9 131.9)
		(end 200.899 131.9)
		(width 0.1)
		(layer "B.Cu")
		(net 256)
	)
	(segment
		(start 205.5 133.55)
		(end 205.28638 133.55)
		(width 0.1)
		(layer "B.Cu")
		(net 256)
	)
	(segment
		(start 206.03838 134.3)
		(end 205.65 133.91162)
		(width 0.1)
		(layer "B.Cu")
		(net 256)
	)
	(segment
		(start 207.77 135.35)
		(end 207.35 135.35)
		(width 0.1)
		(layer "B.Cu")
		(net 256)
	)
	(segment
		(start 206.3 134.3)
		(end 206.03838 134.3)
		(width 0.1)
		(layer "B.Cu")
		(net 256)
	)
	(segment
		(start 205.28638 133.55)
		(end 204.85 133.11362)
		(width 0.1)
		(layer "B.Cu")
		(net 256)
	)
	(segment
		(start 205.65 133.91162)
		(end 205.65 133.7)
		(width 0.1)
		(layer "B.Cu")
		(net 256)
	)
	(segment
		(start 200.899 131.9)
		(end 200.499 132.3)
		(width 0.1)
		(layer "B.Cu")
		(net 256)
	)
	(segment
		(start 205.65 133.7)
		(end 205.5 133.55)
		(width 0.1)
		(layer "B.Cu")
		(net 256)
	)
	(segment
		(start 214.55 116.45)
		(end 214.55 116.925)
		(width 0.1)
		(layer "F.Cu")
		(net 257)
	)
	(segment
		(start 214.4 116.3)
		(end 214.55 116.45)
		(width 0.1)
		(layer "F.Cu")
		(net 257)
	)
	(segment
		(start 219.447 144.142)
		(end 219.8265 144.142)
		(width 0.1)
		(layer "F.Cu")
		(net 257)
	)
	(segment
		(start 219.09 143.8)
		(end 219.105 143.8)
		(width 0.1)
		(layer "F.Cu")
		(net 257)
	)
	(segment
		(start 212.2 116.3)
		(end 214.4 116.3)
		(width 0.1)
		(layer "F.Cu")
		(net 257)
	)
	(segment
		(start 211.8 116.7)
		(end 212.2 116.3)
		(width 0.1)
		(layer "F.Cu")
		(net 257)
	)
	(segment
		(start 219.105 143.8)
		(end 219.447 144.142)
		(width 0.1)
		(layer "F.Cu")
		(net 257)
	)
	(via
		(at 219.09 143.8)
		(size 0.35)
		(drill 0.15)
		(layers "F.Cu" "B.Cu")
		(remove_unused_layers yes)
		(keep_end_layers yes)
		(zone_layer_connections)
		(net 257)
	)
	(via
		(at 211.8 116.7)
		(size 0.35)
		(drill 0.15)
		(layers "F.Cu" "B.Cu")
		(remove_unused_layers yes)
		(keep_end_layers yes)
		(zone_layer_connections)
		(net 257)
	)
	(segment
		(start 220.39 135.76)
		(end 220.39 139.31)
		(width 0.1)
		(layer "In11.Cu")
		(net 257)
	)
	(segment
		(start 212.9 117.5)
		(end 213.4 117)
		(width 0.1)
		(layer "In11.Cu")
		(net 257)
	)
	(segment
		(start 220.296 142.594206)
		(end 220.296 142.944679)
		(width 0.1)
		(layer "In11.Cu")
		(net 257)
	)
	(segment
		(start 211.8 116.80962)
		(end 212.49038 117.5)
		(width 0.1)
		(layer "In11.Cu")
		(net 257)
	)
	(segment
		(start 220.8 127.11)
		(end 220.8 135.35)
		(width 0.1)
		(layer "In11.Cu")
		(net 257)
	)
	(segment
		(start 220.39 139.31)
		(end 219.446 140.254)
		(width 0.1)
		(layer "In11.Cu")
		(net 257)
	)
	(segment
		(start 220.296 142.944679)
		(end 220.85 143.498679)
		(width 0.1)
		(layer "In11.Cu")
		(net 257)
	)
	(segment
		(start 220.075 126.385)
		(end 220.8 127.11)
		(width 0.1)
		(layer "In11.Cu")
		(net 257)
	)
	(segment
		(start 220.8 135.35)
		(end 220.39 135.76)
		(width 0.1)
		(layer "In11.Cu")
		(net 257)
	)
	(segment
		(start 213.4 117)
		(end 215.9 117)
		(width 0.1)
		(layer "In11.Cu")
		(net 257)
	)
	(segment
		(start 219.635794 141.934)
		(end 220.296 142.594206)
		(width 0.1)
		(layer "In11.Cu")
		(net 257)
	)
	(segment
		(start 216.1 116.8)
		(end 219.7 116.8)
		(width 0.1)
		(layer "In11.Cu")
		(net 257)
	)
	(segment
		(start 220.67 144.24)
		(end 219.53 144.24)
		(width 0.1)
		(layer "In11.Cu")
		(net 257)
	)
	(segment
		(start 220.075 117.175)
		(end 220.075 126.385)
		(width 0.1)
		(layer "In11.Cu")
		(net 257)
	)
	(segment
		(start 212.49038 117.5)
		(end 212.9 117.5)
		(width 0.1)
		(layer "In11.Cu")
		(net 257)
	)
	(segment
		(start 220.85 144.06)
		(end 220.67 144.24)
		(width 0.1)
		(layer "In11.Cu")
		(net 257)
	)
	(segment
		(start 219.7 116.8)
		(end 220.075 117.175)
		(width 0.1)
		(layer "In11.Cu")
		(net 257)
	)
	(segment
		(start 219.446 140.254)
		(end 219.446 140.756)
		(width 0.1)
		(layer "In11.Cu")
		(net 257)
	)
	(segment
		(start 219.635794 140.945794)
		(end 219.635794 141.934)
		(width 0.1)
		(layer "In11.Cu")
		(net 257)
	)
	(segment
		(start 219.53 144.24)
		(end 219.09 143.8)
		(width 0.1)
		(layer "In11.Cu")
		(net 257)
	)
	(segment
		(start 220.85 143.498679)
		(end 220.85 144.06)
		(width 0.1)
		(layer "In11.Cu")
		(net 257)
	)
	(segment
		(start 215.9 117)
		(end 216.1 116.8)
		(width 0.1)
		(layer "In11.Cu")
		(net 257)
	)
	(segment
		(start 219.446 140.756)
		(end 219.635794 140.945794)
		(width 0.1)
		(layer "In11.Cu")
		(net 257)
	)
	(segment
		(start 211.8 116.7)
		(end 211.8 116.80962)
		(width 0.1)
		(layer "In11.Cu")
		(net 257)
	)
	(via
		(at 224.86 133.275)
		(size 0.35)
		(drill 0.15)
		(layers "F.Cu" "B.Cu")
		(remove_unused_layers yes)
		(keep_end_layers yes)
		(zone_layer_connections)
		(net 258)
	)
	(via
		(at 223.59 125.465)
		(size 0.35)
		(drill 0.15)
		(layers "F.Cu" "B.Cu")
		(remove_unused_layers yes)
		(keep_end_layers yes)
		(zone_layer_connections)
		(net 259)
	)
	(via
		(at 176.45 148.15)
		(size 0.35)
		(drill 0.15)
		(layers "F.Cu" "B.Cu")
		(remove_unused_layers yes)
		(keep_end_layers yes)
		(zone_layer_connections)
		(net 260)
	)
	(segment
		(start 176.45 148.635)
		(end 176.45 148.15)
		(width 0.15)
		(layer "B.Cu")
		(net 260)
	)
	(segment
		(start 176.715 148.9)
		(end 176.45 148.635)
		(width 0.15)
		(layer "B.Cu")
		(net 260)
	)
	(via
		(at 198.899 126.701)
		(size 0.35)
		(drill 0.15)
		(layers "F.Cu" "B.Cu")
		(remove_unused_layers yes)
		(keep_end_layers yes)
		(zone_layer_connections)
		(net 261)
	)
	(via
		(at 202.14884 121.048)
		(size 0.35)
		(drill 0.15)
		(layers "F.Cu" "B.Cu")
		(remove_unused_layers yes)
		(keep_end_layers yes)
		(zone_layer_connections)
		(net 261)
	)
	(segment
		(start 202.54884 121.448)
		(end 202.94884 121.448)
		(width 0.15)
		(layer "B.Cu")
		(net 261)
	)
	(segment
		(start 202.14884 121.048)
		(end 202.54884 121.448)
		(width 0.15)
		(layer "B.Cu")
		(net 261)
	)
	(segment
		(start 202.926883 120.904409)
		(end 202.683292 121.148)
		(width 0.09)
		(layer "In4.Cu")
		(net 261)
	)
	(segment
		(start 202.24884 121.148)
		(end 202.14884 121.048)
		(width 0.09)
		(layer "In4.Cu")
		(net 261)
	)
	(segment
		(start 198.601 126.701)
		(end 198.2 126.3)
		(width 0.09)
		(layer "In4.Cu")
		(net 261)
	)
	(segment
		(start 202.51 120.21)
		(end 202.926883 120.626883)
		(width 0.09)
		(layer "In4.Cu")
		(net 261)
	)
	(segment
		(start 195.489722 121.046871)
		(end 196.326593 120.21)
		(width 0.09)
		(layer "In4.Cu")
		(net 261)
	)
	(segment
		(start 195.489722 123.809722)
		(end 195.489722 121.046871)
		(width 0.09)
		(layer "In4.Cu")
		(net 261)
	)
	(segment
		(start 198.899 126.701)
		(end 198.601 126.701)
		(width 0.09)
		(layer "In4.Cu")
		(net 261)
	)
	(segment
		(start 197.98 126.3)
		(end 195.489722 123.809722)
		(width 0.09)
		(layer "In4.Cu")
		(net 261)
	)
	(segment
		(start 196.326593 120.21)
		(end 202.51 120.21)
		(width 0.09)
		(layer "In4.Cu")
		(net 261)
	)
	(segment
		(start 202.683292 121.148)
		(end 202.24884 121.148)
		(width 0.09)
		(layer "In4.Cu")
		(net 261)
	)
	(segment
		(start 198.2 126.3)
		(end 197.98 126.3)
		(width 0.09)
		(layer "In4.Cu")
		(net 261)
	)
	(segment
		(start 202.926883 120.626883)
		(end 202.926883 120.904409)
		(width 0.09)
		(layer "In4.Cu")
		(net 261)
	)
	(segment
		(start 202.616883 120.776002)
		(end 202.490881 120.65)
		(width 0.15)
		(layer "F.Cu")
		(net 262)
	)
	(segment
		(start 202.490881 120.65)
		(end 202.14884 120.65)
		(width 0.15)
		(layer "F.Cu")
		(net 262)
	)
	(via
		(at 202.616883 120.776002)
		(size 0.35)
		(drill 0.15)
		(layers "F.Cu" "B.Cu")
		(remove_unused_layers yes)
		(keep_end_layers yes)
		(zone_layer_connections)
		(net 262)
	)
	(via
		(at 199.699 126.701)
		(size 0.35)
		(drill 0.15)
		(layers "F.Cu" "B.Cu")
		(remove_unused_layers yes)
		(keep_end_layers yes)
		(zone_layer_connections)
		(net 262)
	)
	(segment
		(start 202.94884 121.05)
		(end 202.890881 121.05)
		(width 0.184)
		(layer "B.Cu")
		(net 262)
	)
	(segment
		(start 202.890881 121.05)
		(end 202.616883 120.776002)
		(width 0.15)
		(layer "B.Cu")
		(net 262)
	)
	(segment
		(start 198.635 123.825)
		(end 198.46 124)
		(width 0.09)
		(layer "In4.Cu")
		(net 262)
	)
	(segment
		(start 198.46 124)
		(end 198.46 124.43)
		(width 0.09)
		(layer "In4.Cu")
		(net 262)
	)
	(segment
		(start 202.616883 120.776002)
		(end 202.306883 120.466002)
		(width 0.09)
		(layer "In4.Cu")
		(net 262)
	)
	(segment
		(start 199.2125 123.825)
		(end 198.635 123.825)
		(width 0.09)
		(layer "In4.Cu")
		(net 262)
	)
	(segment
		(start 198.725 121.65)
		(end 199.225 121.65)
		(width 0.09)
		(layer "In4.Cu")
		(net 262)
	)
	(segment
		(start 198.3 120.725)
		(end 198.3 121.225)
		(width 0.09)
		(layer "In4.Cu")
		(net 262)
	)
	(segment
		(start 199.145 121.209417)
		(end 199.145 120.681002)
		(width 0.09)
		(layer "In4.Cu")
		(net 262)
	)
	(segment
		(start 199.575 120.681002)
		(end 199.575 121.209417)
		(width 0.09)
		(layer "In4.Cu")
		(net 262)
	)
	(segment
		(start 198.93 120.466002)
		(end 198.558998 120.466002)
		(width 0.09)
		(layer "In4.Cu")
		(net 262)
	)
	(segment
		(start 198.65 124.62)
		(end 198.856407 124.62)
		(width 0.09)
		(layer "In4.Cu")
		(net 262)
	)
	(segment
		(start 198.46 124.43)
		(end 198.65 124.62)
		(width 0.09)
		(layer "In4.Cu")
		(net 262)
	)
	(segment
		(start 199.25 126.252)
		(end 199.699 126.701)
		(width 0.09)
		(layer "In4.Cu")
		(net 262)
	)
	(segment
		(start 198.558998 120.466002)
		(end 198.3 120.725)
		(width 0.09)
		(layer "In4.Cu")
		(net 262)
	)
	(segment
		(start 200.005 121.059413)
		(end 200.005 120.681002)
		(width 0.09)
		(layer "In4.Cu")
		(net 262)
	)
	(segment
		(start 199.25 125.013593)
		(end 199.25 126.252)
		(width 0.09)
		(layer "In4.Cu")
		(net 262)
	)
	(segment
		(start 198.856407 124.62)
		(end 199.25 125.013593)
		(width 0.09)
		(layer "In4.Cu")
		(net 262)
	)
	(segment
		(start 198.3 121.225)
		(end 198.725 121.65)
		(width 0.09)
		(layer "In4.Cu")
		(net 262)
	)
	(segment
		(start 199.3375 121.7625)
		(end 199.3375 123.7)
		(width 0.09)
		(layer "In4.Cu")
		(net 262)
	)
	(segment
		(start 199.225 121.65)
		(end 199.3375 121.7625)
		(width 0.09)
		(layer "In4.Cu")
		(net 262)
	)
	(segment
		(start 199.3375 123.7)
		(end 199.2125 123.825)
		(width 0.09)
		(layer "In4.Cu")
		(net 262)
	)
	(segment
		(start 202.306883 120.466002)
		(end 200.65 120.466002)
		(width 0.09)
		(layer "In4.Cu")
		(net 262)
	)
	(segment
		(start 200.435 120.681002)
		(end 200.435 121.059413)
		(width 0.09)
		(layer "In4.Cu")
		(net 262)
	)
	(arc
		(start 200.435 121.059413)
		(mid 200.372028 121.211441)
		(end 200.22 121.274413)
		(width 0.09)
		(layer "In4.Cu")
		(net 262)
	)
	(arc
		(start 200.005 120.681002)
		(mid 199.942028 120.528974)
		(end 199.79 120.466002)
		(width 0.09)
		(layer "In4.Cu")
		(net 262)
	)
	(arc
		(start 199.79 120.466002)
		(mid 199.637972 120.528974)
		(end 199.575 120.681002)
		(width 0.09)
		(layer "In4.Cu")
		(net 262)
	)
	(arc
		(start 200.22 121.274413)
		(mid 200.067972 121.211441)
		(end 200.005 121.059413)
		(width 0.09)
		(layer "In4.Cu")
		(net 262)
	)
	(arc
		(start 200.65 120.466002)
		(mid 200.497972 120.528974)
		(end 200.435 120.681002)
		(width 0.09)
		(layer "In4.Cu")
		(net 262)
	)
	(arc
		(start 199.145 120.681002)
		(mid 199.082028 120.528974)
		(end 198.93 120.466002)
		(width 0.09)
		(layer "In4.Cu")
		(net 262)
	)
	(arc
		(start 199.36 121.424417)
		(mid 199.207972 121.361445)
		(end 199.145 121.209417)
		(width 0.09)
		(layer "In4.Cu")
		(net 262)
	)
	(arc
		(start 199.575 121.209417)
		(mid 199.512028 121.361445)
		(end 199.36 121.424417)
		(width 0.09)
		(layer "In4.Cu")
		(net 262)
	)
	(via
		(at 176.95 147.65)
		(size 0.35)
		(drill 0.15)
		(layers "F.Cu" "B.Cu")
		(remove_unused_layers yes)
		(keep_end_layers yes)
		(zone_layer_connections)
		(net 263)
	)
	(segment
		(start 176.95 147.65)
		(end 176.95 147.165)
		(width 0.15)
		(layer "B.Cu")
		(net 263)
	)
	(segment
		(start 176.95 147.165)
		(end 176.635 146.85)
		(width 0.15)
		(layer "B.Cu")
		(net 263)
	)
	(via
		(at 213.9435 133.949)
		(size 0.35)
		(drill 0.15)
		(layers "F.Cu" "B.Cu")
		(remove_unused_layers yes)
		(keep_end_layers yes)
		(zone_layer_connections)
		(net 264)
	)
	(via
		(at 197.350707 121.058436)
		(size 0.35)
		(drill 0.15)
		(layers "F.Cu" "B.Cu")
		(remove_unused_layers yes)
		(keep_end_layers yes)
		(zone_layer_connections)
		(net 264)
	)
	(segment
		(start 197.342271 121.05)
		(end 197.350707 121.058436)
		(width 0.15)
		(layer "B.Cu")
		(net 264)
	)
	(segment
		(start 197.008 121.05)
		(end 197.342271 121.05)
		(width 0.15)
		(layer "B.Cu")
		(net 264)
	)
	(segment
		(start 197.350707 121.058436)
		(end 197.350707 121.450707)
		(width 0.09)
		(layer "In2.Cu")
		(net 264)
	)
	(segment
		(start 212.575 132.575)
		(end 213.9435 133.9435)
		(width 0.09)
		(layer "In2.Cu")
		(net 264)
	)
	(segment
		(start 208.7 132.15)
		(end 209.207 132.657)
		(width 0.09)
		(layer "In2.Cu")
		(net 264)
	)
	(segment
		(start 197.350707 121.450707)
		(end 198.85 122.95)
		(width 0.09)
		(layer "In2.Cu")
		(net 264)
	)
	(segment
		(start 208.775 124.015)
		(end 208.775 128.575)
		(width 0.09)
		(layer "In2.Cu")
		(net 264)
	)
	(segment
		(start 209.917907 132.575)
		(end 212.575 132.575)
		(width 0.09)
		(layer "In2.Cu")
		(net 264)
	)
	(segment
		(start 209.835907 132.657)
		(end 209.917907 132.575)
		(width 0.09)
		(layer "In2.Cu")
		(net 264)
	)
	(segment
		(start 207.71 122.95)
		(end 208.775 124.015)
		(width 0.09)
		(layer "In2.Cu")
		(net 264)
	)
	(segment
		(start 208.775 128.575)
		(end 208.7 128.65)
		(width 0.09)
		(layer "In2.Cu")
		(net 264)
	)
	(segment
		(start 208.7 128.65)
		(end 208.7 132.15)
		(width 0.09)
		(layer "In2.Cu")
		(net 264)
	)
	(segment
		(start 198.85 122.95)
		(end 207.71 122.95)
		(width 0.09)
		(layer "In2.Cu")
		(net 264)
	)
	(segment
		(start 209.207 132.657)
		(end 209.835907 132.657)
		(width 0.09)
		(layer "In2.Cu")
		(net 264)
	)
	(segment
		(start 213.9435 133.9435)
		(end 213.9435 133.949)
		(width 0.09)
		(layer "In2.Cu")
		(net 264)
	)
	(via
		(at 199.699 124.3)
		(size 0.35)
		(drill 0.15)
		(layers "F.Cu" "B.Cu")
		(remove_unused_layers yes)
		(keep_end_layers yes)
		(zone_layer_connections)
		(net 265)
	)
	(via
		(at 196.395209 121.048)
		(size 0.35)
		(drill 0.15)
		(layers "F.Cu" "B.Cu")
		(remove_unused_layers yes)
		(keep_end_layers yes)
		(zone_layer_connections)
		(net 265)
	)
	(segment
		(start 196.395209 121.048)
		(end 196.688 121.048)
		(width 0.09)
		(layer "In2.Cu")
		(net 265)
	)
	(segment
		(start 199.424786 123.92)
		(end 199.699 124.194214)
		(width 0.09)
		(layer "In2.Cu")
		(net 265)
	)
	(segment
		(start 196.859381 123.54)
		(end 196.859381 123.699381)
		(width 0.09)
		(layer "In2.Cu")
		(net 265)
	)
	(segment
		(start 196.669381 122.97)
		(end 194.087338 122.97)
		(width 0.09)
		(layer "In2.Cu")
		(net 265)
	)
	(segment
		(start 196.69 122.21)
		(end 194.087338 122.21)
		(width 0.09)
		(layer "In2.Cu")
		(net 265)
	)
	(segment
		(start 196.859381 123.699381)
		(end 197.08 123.92)
		(width 0.09)
		(layer "In2.Cu")
		(net 265)
	)
	(segment
		(start 197.08 123.92)
		(end 199.424786 123.92)
		(width 0.09)
		(layer "In2.Cu")
		(net 265)
	)
	(segment
		(start 194.087338 123.35)
		(end 196.669381 123.35)
		(width 0.09)
		(layer "In2.Cu")
		(net 265)
	)
	(segment
		(start 196.95 121.31)
		(end 196.95 121.95)
		(width 0.09)
		(layer "In2.Cu")
		(net 265)
	)
	(segment
		(start 199.699 124.194214)
		(end 199.699 124.3)
		(width 0.09)
		(layer "In2.Cu")
		(net 265)
	)
	(segment
		(start 194.087338 122.59)
		(end 196.669381 122.59)
		(width 0.09)
		(layer "In2.Cu")
		(net 265)
	)
	(segment
		(start 196.688 121.048)
		(end 196.95 121.31)
		(width 0.09)
		(layer "In2.Cu")
		(net 265)
	)
	(segment
		(start 196.95 121.95)
		(end 196.88 122.02)
		(width 0.09)
		(layer "In2.Cu")
		(net 265)
	)
	(arc
		(start 196.669381 122.59)
		(mid 196.803731 122.64565)
		(end 196.859381 122.78)
		(width 0.09)
		(layer "In2.Cu")
		(net 265)
	)
	(arc
		(start 196.88 122.02)
		(mid 196.82435 122.15435)
		(end 196.69 122.21)
		(width 0.09)
		(layer "In2.Cu")
		(net 265)
	)
	(arc
		(start 196.669381 123.35)
		(mid 196.803731 123.40565)
		(end 196.859381 123.54)
		(width 0.09)
		(layer "In2.Cu")
		(net 265)
	)
	(arc
		(start 194.087338 122.21)
		(mid 193.952988 122.26565)
		(end 193.897338 122.4)
		(width 0.09)
		(layer "In2.Cu")
		(net 265)
	)
	(arc
		(start 193.897338 123.16)
		(mid 193.952988 123.29435)
		(end 194.087338 123.35)
		(width 0.09)
		(layer "In2.Cu")
		(net 265)
	)
	(arc
		(start 196.859381 122.78)
		(mid 196.803731 122.91435)
		(end 196.669381 122.97)
		(width 0.09)
		(layer "In2.Cu")
		(net 265)
	)
	(arc
		(start 194.087338 122.97)
		(mid 193.952988 123.02565)
		(end 193.897338 123.16)
		(width 0.09)
		(layer "In2.Cu")
		(net 265)
	)
	(arc
		(start 193.897338 122.4)
		(mid 193.952988 122.53435)
		(end 194.087338 122.59)
		(width 0.09)
		(layer "In2.Cu")
		(net 265)
	)
	(segment
		(start 204.866968 120.775391)
		(end 204.892359 120.75)
		(width 0.15)
		(layer "F.Cu")
		(net 266)
	)
	(segment
		(start 205.103983 120.65)
		(end 205.295002 120.65)
		(width 0.15)
		(layer "F.Cu")
		(net 266)
	)
	(segment
		(start 205.003983 120.75)
		(end 205.103983 120.65)
		(width 0.15)
		(layer "F.Cu")
		(net 266)
	)
	(segment
		(start 204.892359 120.75)
		(end 205.003983 120.75)
		(width 0.15)
		(layer "F.Cu")
		(net 266)
	)
	(via
		(at 197.321 116.84)
		(size 0.35)
		(drill 0.15)
		(layers "F.Cu" "B.Cu")
		(remove_unused_layers yes)
		(keep_end_layers yes)
		(zone_layer_connections)
		(net 266)
	)
	(via
		(at 204.866968 120.775391)
		(size 0.35)
		(drill 0.15)
		(layers "F.Cu" "B.Cu")
		(remove_unused_layers yes)
		(keep_end_layers yes)
		(zone_layer_connections)
		(net 266)
	)
	(segment
		(start 197.321 117.457)
		(end 197.317 117.461)
		(width 0.15)
		(layer "B.Cu")
		(net 266)
	)
	(segment
		(start 197.321 116.84)
		(end 197.321 117.457)
		(width 0.15)
		(layer "B.Cu")
		(net 266)
	)
	(segment
		(start 197.321 117.171)
		(end 197.55 117.4)
		(width 0.09)
		(layer "In2.Cu")
		(net 266)
	)
	(segment
		(start 204.152343 118.75)
		(end 204.626968 118.75)
		(width 0.09)
		(layer "In2.Cu")
		(net 266)
	)
	(segment
		(start 204.866968 118.99)
		(end 204.866968 120.775391)
		(width 0.09)
		(layer "In2.Cu")
		(net 266)
	)
	(segment
		(start 204.626968 118.27)
		(end 204.152343 118.27)
		(width 0.09)
		(layer "In2.Cu")
		(net 266)
	)
	(segment
		(start 204.37 117.4)
		(end 204.866968 117.896968)
		(width 0.09)
		(layer "In2.Cu")
		(net 266)
	)
	(segment
		(start 204.866968 117.896968)
		(end 204.866968 118.03)
		(width 0.09)
		(layer "In2.Cu")
		(net 266)
	)
	(segment
		(start 197.55 117.4)
		(end 204.37 117.4)
		(width 0.09)
		(layer "In2.Cu")
		(net 266)
	)
	(segment
		(start 197.321 116.84)
		(end 197.321 117.171)
		(width 0.09)
		(layer "In2.Cu")
		(net 266)
	)
	(arc
		(start 204.152343 118.27)
		(mid 203.982637 118.340294)
		(end 203.912343 118.51)
		(width 0.09)
		(layer "In2.Cu")
		(net 266)
	)
	(arc
		(start 204.626968 118.75)
		(mid 204.796674 118.820294)
		(end 204.866968 118.99)
		(width 0.09)
		(layer "In2.Cu")
		(net 266)
	)
	(arc
		(start 203.912343 118.51)
		(mid 203.982637 118.679706)
		(end 204.152343 118.75)
		(width 0.09)
		(layer "In2.Cu")
		(net 266)
	)
	(arc
		(start 204.866968 118.03)
		(mid 204.796674 118.199706)
		(end 204.626968 118.27)
		(width 0.09)
		(layer "In2.Cu")
		(net 266)
	)
	(segment
		(start 205.225 121.048)
		(end 205.295002 121.048)
		(width 0.15)
		(layer "F.Cu")
		(net 267)
	)
	(via
		(at 196.922 117.05)
		(size 0.35)
		(drill 0.15)
		(layers "F.Cu" "B.Cu")
		(remove_unused_layers yes)
		(keep_end_layers yes)
		(zone_layer_connections)
		(net 267)
	)
	(via
		(at 205.225 121.048)
		(size 0.35)
		(drill 0.15)
		(layers "F.Cu" "B.Cu")
		(remove_unused_layers yes)
		(keep_end_layers yes)
		(zone_layer_connections)
		(net 267)
	)
	(segment
		(start 203.583039 120.253039)
		(end 203.58304 120.25304)
		(width 0.09)
		(layer "In2.Cu")
		(net 267)
	)
	(segment
		(start 203.583039 120.055051)
		(end 203.904293 119.733796)
		(width 0.09)
		(layer "In2.Cu")
		(net 267)
	)
	(segment
		(start 199.8 117.63)
		(end 199.65 117.78)
		(width 0.09)
		(layer "In2.Cu")
		(net 267)
	)
	(segment
		(start 204.177009 120.649019)
		(end 204.180047 120.645982)
		(width 0.09)
		(layer "In2.Cu")
		(net 267)
	)
	(segment
		(start 203.187059 119.857059)
		(end 203.18706 119.85706)
		(width 0.09)
		(layer "In2.Cu")
		(net 267)
	)
	(segment
		(start 203.781029 120.253039)
		(end 204.102304 119.931765)
		(width 0.09)
		(layer "In2.Cu")
		(net 267)
	)
	(segment
		(start 203.385049 119.857059)
		(end 203.706304 119.535805)
		(width 0.09)
		(layer "In2.Cu")
		(net 267)
	)
	(segment
		(start 203.979019 120.649019)
		(end 203.97902 120.64902)
		(width 0.09)
		(layer "In2.Cu")
		(net 267)
	)
	(segment
		(start 204.374999 120.847011)
		(end 204.378036 120.843973)
		(width 0.09)
		(layer "In2.Cu")
		(net 267)
	)
	(segment
		(start 203.979019 120.451031)
		(end 204.300293 120.129756)
		(width 0.09)
		(layer "In2.Cu")
		(net 267)
	)
	(segment
		(start 199.65 117.78)
		(end 198.39 117.78)
		(width 0.09)
		(layer "In2.Cu")
		(net 267)
	)
	(segment
		(start 197.3 117.63)
		(end 196.922 117.252)
		(width 0.09)
		(layer "In2.Cu")
		(net 267)
	)
	(segment
		(start 205.187609 121.085391)
		(end 204.415391 121.085391)
		(width 0.09)
		(layer "In2.Cu")
		(net 267)
	)
	(segment
		(start 205.225 121.048)
		(end 205.187609 121.085391)
		(width 0.09)
		(layer "In2.Cu")
		(net 267)
	)
	(segment
		(start 202.045407 117.63)
		(end 199.8 117.63)
		(width 0.09)
		(layer "In2.Cu")
		(net 267)
	)
	(segment
		(start 204.415391 121.085391)
		(end 204.375 121.045)
		(width 0.09)
		(layer "In2.Cu")
		(net 267)
	)
	(segment
		(start 198.24 117.63)
		(end 197.3 117.63)
		(width 0.09)
		(layer "In2.Cu")
		(net 267)
	)
	(segment
		(start 196.922 117.252)
		(end 196.922 117.05)
		(width 0.09)
		(layer "In2.Cu")
		(net 267)
	)
	(segment
		(start 202.85 118.434593)
		(end 202.045407 117.63)
		(width 0.09)
		(layer "In2.Cu")
		(net 267)
	)
	(segment
		(start 202.85 119.52)
		(end 202.85 118.434593)
		(width 0.09)
		(layer "In2.Cu")
		(net 267)
	)
	(segment
		(start 198.39 117.78)
		(end 198.24 117.63)
		(width 0.09)
		(layer "In2.Cu")
		(net 267)
	)
	(segment
		(start 203.18706 119.85706)
		(end 202.85 119.52)
		(width 0.09)
		(layer "In2.Cu")
		(net 267)
	)
	(arc
		(start 204.177009 120.649019)
		(mid 204.078014 120.690024)
		(end 203.979019 120.649019)
		(width 0.09)
		(layer "In2.Cu")
		(net 267)
	)
	(arc
		(start 204.375 121.045)
		(mid 204.333995 120.946006)
		(end 204.374999 120.847011)
		(width 0.09)
		(layer "In2.Cu")
		(net 267)
	)
	(arc
		(start 203.904293 119.733796)
		(mid 203.945298 119.634801)
		(end 203.904293 119.535806)
		(width 0.09)
		(layer "In2.Cu")
		(net 267)
	)
	(arc
		(start 203.97902 120.64902)
		(mid 203.938015 120.550026)
		(end 203.979019 120.451031)
		(width 0.09)
		(layer "In2.Cu")
		(net 267)
	)
	(arc
		(start 204.378036 120.843973)
		(mid 204.419041 120.744978)
		(end 204.378036 120.645983)
		(width 0.09)
		(layer "In2.Cu")
		(net 267)
	)
	(arc
		(start 203.781029 120.253039)
		(mid 203.682034 120.294044)
		(end 203.583039 120.253039)
		(width 0.09)
		(layer "In2.Cu")
		(net 267)
	)
	(arc
		(start 204.300293 120.129756)
		(mid 204.341298 120.030761)
		(end 204.300293 119.931766)
		(width 0.09)
		(layer "In2.Cu")
		(net 267)
	)
	(arc
		(start 203.385049 119.857059)
		(mid 203.286054 119.898064)
		(end 203.187059 119.857059)
		(width 0.09)
		(layer "In2.Cu")
		(net 267)
	)
	(arc
		(start 203.904293 119.535806)
		(mid 203.805299 119.494801)
		(end 203.706304 119.535805)
		(width 0.09)
		(layer "In2.Cu")
		(net 267)
	)
	(arc
		(start 204.378036 120.645983)
		(mid 204.279042 120.604978)
		(end 204.180047 120.645982)
		(width 0.09)
		(layer "In2.Cu")
		(net 267)
	)
	(arc
		(start 204.300293 119.931766)
		(mid 204.201299 119.890761)
		(end 204.102304 119.931765)
		(width 0.09)
		(layer "In2.Cu")
		(net 267)
	)
	(arc
		(start 203.58304 120.25304)
		(mid 203.542035 120.154046)
		(end 203.583039 120.055051)
		(width 0.09)
		(layer "In2.Cu")
		(net 267)
	)
	(segment
		(start 205.075685 121.45175)
		(end 205.077435 121.45)
		(width 0.15)
		(layer "F.Cu")
		(net 268)
	)
	(segment
		(start 204.998179 121.45175)
		(end 205.075685 121.45175)
		(width 0.15)
		(layer "F.Cu")
		(net 268)
	)
	(segment
		(start 204.974929 121.475)
		(end 204.998179 121.45175)
		(width 0.15)
		(layer "F.Cu")
		(net 268)
	)
	(segment
		(start 205.077435 121.45)
		(end 205.295002 121.45)
		(width 0.15)
		(layer "F.Cu")
		(net 268)
	)
	(via
		(at 196.514 118.71)
		(size 0.35)
		(drill 0.15)
		(layers "F.Cu" "B.Cu")
		(remove_unused_layers yes)
		(keep_end_layers yes)
		(zone_layer_connections)
		(net 268)
	)
	(via
		(at 204.974929 121.475)
		(size 0.35)
		(drill 0.15)
		(layers "F.Cu" "B.Cu")
		(remove_unused_layers yes)
		(keep_end_layers yes)
		(zone_layer_connections)
		(net 268)
	)
	(segment
		(start 196.919 120.168)
		(end 196.922 120.171)
		(width 0.15)
		(layer "B.Cu")
		(net 268)
	)
	(segment
		(start 196.919 119.119)
		(end 196.919 120.168)
		(width 0.15)
		(layer "B.Cu")
		(net 268)
	)
	(segment
		(start 196.514 118.71)
		(end 196.514 118.714)
		(width 0.15)
		(layer "B.Cu")
		(net 268)
	)
	(segment
		(start 196.514 118.714)
		(end 196.919 119.119)
		(width 0.15)
		(layer "B.Cu")
		(net 268)
	)
	(segment
		(start 200.985 119.445)
		(end 200.985 118.38)
		(width 0.09)
		(layer "In2.Cu")
		(net 268)
	)
	(segment
		(start 204.195 121.475)
		(end 202.63 119.91)
		(width 0.09)
		(layer "In2.Cu")
		(net 268)
	)
	(segment
		(start 196.514 117.896)
		(end 196.514 118.71)
		(width 0.09)
		(layer "In2.Cu")
		(net 268)
	)
	(segment
		(start 204.974929 121.475)
		(end 204.195 121.475)
		(width 0.09)
		(layer "In2.Cu")
		(net 268)
	)
	(segment
		(start 200.985 118.38)
		(end 200.471507 117.866507)
		(width 0.09)
		(layer "In2.Cu")
		(net 268)
	)
	(segment
		(start 202.63 119.91)
		(end 201.45 119.91)
		(width 0.09)
		(layer "In2.Cu")
		(net 268)
	)
	(segment
		(start 197.108407 117.82)
		(end 197.018407 117.73)
		(width 0.09)
		(layer "In2.Cu")
		(net 268)
	)
	(segment
		(start 200.471507 117.866507)
		(end 199.923493 117.866507)
		(width 0.09)
		(layer "In2.Cu")
		(net 268)
	)
	(segment
		(start 196.68 117.73)
		(end 196.514 117.896)
		(width 0.09)
		(layer "In2.Cu")
		(net 268)
	)
	(segment
		(start 199.73 118.06)
		(end 198.27 118.06)
		(width 0.09)
		(layer "In2.Cu")
		(net 268)
	)
	(segment
		(start 197.018407 117.73)
		(end 196.68 117.73)
		(width 0.09)
		(layer "In2.Cu")
		(net 268)
	)
	(segment
		(start 201.45 119.91)
		(end 200.985 119.445)
		(width 0.09)
		(layer "In2.Cu")
		(net 268)
	)
	(segment
		(start 199.923493 117.866507)
		(end 199.73 118.06)
		(width 0.09)
		(layer "In2.Cu")
		(net 268)
	)
	(segment
		(start 198.27 118.06)
		(end 198.03 117.82)
		(width 0.09)
		(layer "In2.Cu")
		(net 268)
	)
	(segment
		(start 198.03 117.82)
		(end 197.108407 117.82)
		(width 0.09)
		(layer "In2.Cu")
		(net 268)
	)
	(segment
		(start 205.225 121.848)
		(end 205.295002 121.848)
		(width 0.15)
		(layer "F.Cu")
		(net 269)
	)
	(via
		(at 194.9 118.677)
		(size 0.35)
		(drill 0.15)
		(layers "F.Cu" "B.Cu")
		(remove_unused_layers yes)
		(keep_end_layers yes)
		(zone_layer_connections)
		(net 269)
	)
	(via
		(at 205.225 121.848)
		(size 0.35)
		(drill 0.15)
		(layers "F.Cu" "B.Cu")
		(remove_unused_layers yes)
		(keep_end_layers yes)
		(zone_layer_connections)
		(net 269)
	)
	(segment
		(start 194.9 118.677)
		(end 195.038 118.815)
		(width 0.15)
		(layer "B.Cu")
		(net 269)
	)
	(segment
		(start 195.038 118.815)
		(end 195.19215 118.815)
		(width 0.15)
		(layer "B.Cu")
		(net 269)
	)
	(segment
		(start 195.19215 118.815)
		(end 195.72 119.34285)
		(width 0.15)
		(layer "B.Cu")
		(net 269)
	)
	(segment
		(start 195.72 119.34285)
		(end 195.72 119.841)
		(width 0.15)
		(layer "B.Cu")
		(net 269)
	)
	(segment
		(start 195.52 119.55)
		(end 196.13 120.16)
		(width 0.09)
		(layer "In2.Cu")
		(net 269)
	)
	(segment
		(start 194.9 118.677)
		(end 195.217 118.677)
		(width 0.09)
		(layer "In2.Cu")
		(net 269)
	)
	(segment
		(start 203.535 121.5)
		(end 203.883 121.848)
		(width 0.09)
		(layer "In2.Cu")
		(net 269)
	)
	(segment
		(start 195.52 118.98)
		(end 195.52 119.55)
		(width 0.09)
		(layer "In2.Cu")
		(net 269)
	)
	(segment
		(start 198.89 120.16)
		(end 200.23 121.5)
		(width 0.09)
		(layer "In2.Cu")
		(net 269)
	)
	(segment
		(start 203.883 121.848)
		(end 205.225 121.848)
		(width 0.09)
		(layer "In2.Cu")
		(net 269)
	)
	(segment
		(start 200.23 121.5)
		(end 203.535 121.5)
		(width 0.09)
		(layer "In2.Cu")
		(net 269)
	)
	(segment
		(start 196.13 120.16)
		(end 198.89 120.16)
		(width 0.09)
		(layer "In2.Cu")
		(net 269)
	)
	(segment
		(start 195.217 118.677)
		(end 195.52 118.98)
		(width 0.09)
		(layer "In2.Cu")
		(net 269)
	)
	(via
		(at 192.499 126.701)
		(size 0.35)
		(drill 0.15)
		(layers "F.Cu" "B.Cu")
		(remove_unused_layers yes)
		(keep_end_layers yes)
		(zone_layer_connections)
		(net 270)
	)
	(segment
		(start 192.886 123.914)
		(end 192.886 126.314)
		(width 0.174)
		(layer "B.Cu")
		(net 270)
	)
	(segment
		(start 192.485 123.25)
		(end 192.485 123.513)
		(width 0.174)
		(layer "B.Cu")
		(net 270)
	)
	(segment
		(start 192.485 123.513)
		(end 192.886 123.914)
		(width 0.174)
		(layer "B.Cu")
		(net 270)
	)
	(segment
		(start 193.465 123.25)
		(end 193.465 123.335)
		(width 0.174)
		(layer "B.Cu")
		(net 270)
	)
	(segment
		(start 192.886 126.314)
		(end 192.499 126.701)
		(width 0.174)
		(layer "B.Cu")
		(net 270)
	)
	(segment
		(start 193.465 123.335)
		(end 192.886 123.914)
		(width 0.174)
		(layer "B.Cu")
		(net 270)
	)
	(segment
		(start 178.804 122.766)
		(end 179.2035 122.4415)
		(width 0.174)
		(layer "F.Cu")
		(net 271)
	)
	(via
		(at 179.2035 122.4415)
		(size 0.35)
		(drill 0.15)
		(layers "F.Cu" "B.Cu")
		(remove_unused_layers yes)
		(keep_end_layers yes)
		(zone_layer_connections)
		(net 271)
	)
	(segment
		(start 179.945 121.7)
		(end 183.65 121.7)
		(width 0.15)
		(layer "B.Cu")
		(net 271)
	)
	(segment
		(start 179.2035 122.4415)
		(end 179.945 121.7)
		(width 0.15)
		(layer "B.Cu")
		(net 271)
	)
	(segment
		(start 183.865 121.915)
		(end 183.865 122.4)
		(width 0.15)
		(layer "B.Cu")
		(net 271)
	)
	(segment
		(start 183.65 121.7)
		(end 183.865 121.915)
		(width 0.15)
		(layer "B.Cu")
		(net 271)
	)
	(segment
		(start 182.204436 140.504436)
		(end 182.171372 140.5375)
		(width 0.174)
		(layer "F.Cu")
		(net 272)
	)
	(segment
		(start 182.171372 140.5375)
		(end 181.725 140.5375)
		(width 0.174)
		(layer "F.Cu")
		(net 272)
	)
	(via
		(at 184.575 140.4)
		(size 0.35)
		(drill 0.15)
		(layers "F.Cu" "B.Cu")
		(remove_unused_layers yes)
		(keep_end_layers yes)
		(zone_layer_connections)
		(net 272)
	)
	(via
		(at 184.825 140.075)
		(size 0.35)
		(drill 0.15)
		(layers "F.Cu" "B.Cu")
		(remove_unused_layers yes)
		(keep_end_layers yes)
		(zone_layer_connections)
		(net 272)
	)
	(via
		(at 184.375994 140.045066)
		(size 0.35)
		(drill 0.15)
		(layers "F.Cu" "B.Cu")
		(remove_unused_layers yes)
		(keep_end_layers yes)
		(zone_layer_connections)
		(net 272)
	)
	(via
		(at 185 140.4835)
		(size 0.35)
		(drill 0.15)
		(layers "F.Cu" "B.Cu")
		(remove_unused_layers yes)
		(keep_end_layers yes)
		(zone_layer_connections)
		(net 272)
	)
	(via
		(at 182.204436 140.504436)
		(size 0.35)
		(drill 0.15)
		(layers "F.Cu" "B.Cu")
		(remove_unused_layers yes)
		(keep_end_layers yes)
		(zone_layer_connections)
		(net 272)
	)
	(segment
		(start 183.525 139.825)
		(end 182.845564 140.504436)
		(width 0.174)
		(layer "B.Cu")
		(net 272)
	)
	(segment
		(start 183.91 138.35)
		(end 182.58 138.35)
		(width 0.1)
		(layer "B.Cu")
		(net 272)
	)
	(segment
		(start 183.525 139.25)
		(end 183.525 139.2)
		(width 0.1)
		(layer "B.Cu")
		(net 272)
	)
	(segment
		(start 182.845564 140.504436)
		(end 182.204436 140.504436)
		(width 0.174)
		(layer "B.Cu")
		(net 272)
	)
	(segment
		(start 183.525 139.2)
		(end 184.075 138.65)
		(width 0.1)
		(layer "B.Cu")
		(net 272)
	)
	(segment
		(start 184.075 138.515)
		(end 183.91 138.35)
		(width 0.1)
		(layer "B.Cu")
		(net 272)
	)
	(segment
		(start 183.525 139.25)
		(end 183.525 139.825)
		(width 0.174)
		(layer "B.Cu")
		(net 272)
	)
	(segment
		(start 182.58 138.35)
		(end 182.41 138.52)
		(width 0.1)
		(layer "B.Cu")
		(net 272)
	)
	(segment
		(start 184.075 138.65)
		(end 184.075 138.515)
		(width 0.1)
		(layer "B.Cu")
		(net 272)
	)
	(segment
		(start 182.41 138.52)
		(end 182.41 138.82)
		(width 0.1)
		(layer "B.Cu")
		(net 272)
	)
	(segment
		(start 200.99884 120.776002)
		(end 201.124842 120.65)
		(width 0.15)
		(layer "F.Cu")
		(net 273)
	)
	(segment
		(start 201.124842 120.65)
		(end 201.55084 120.65)
		(width 0.15)
		(layer "F.Cu")
		(net 273)
	)
	(via
		(at 200.99884 120.776002)
		(size 0.35)
		(drill 0.15)
		(layers "F.Cu" "B.Cu")
		(remove_unused_layers yes)
		(keep_end_layers yes)
		(zone_layer_connections)
		(net 273)
	)
	(via
		(at 196.122 117.05)
		(size 0.35)
		(drill 0.15)
		(layers "F.Cu" "B.Cu")
		(remove_unused_layers yes)
		(keep_end_layers yes)
		(zone_layer_connections)
		(net 273)
	)
	(segment
		(start 200.795 119.585)
		(end 200.72 119.51)
		(width 0.09)
		(layer "In2.Cu")
		(net 273)
	)
	(segment
		(start 201.106126 120.26382)
		(end 201.190979 120.178968)
		(width 0.09)
		(layer "In2.Cu")
		(net 273)
	)
	(segment
		(start 199.89 118.71)
		(end 199.89 119.08)
		(width 0.09)
		(layer "In2.Cu")
		(net 273)
	)
	(segment
		(start 200.795 119.782989)
		(end 200.794999 119.782989)
		(width 0.09)
		(layer "In2.Cu")
		(net 273)
	)
	(segment
		(start 200.72 118.78)
		(end 200.45 118.51)
		(width 0.09)
		(layer "In2.Cu")
		(net 273)
	)
	(segment
		(start 200.555 119.335)
		(end 200.385 119.335)
		(width 0.09)
		(layer "In2.Cu")
		(net 273)
	)
	(segment
		(start 200.385 119.005)
		(end 200.555 119.005)
		(width 0.09)
		(layer "In2.Cu")
		(net 273)
	)
	(segment
		(start 201.190979 119.980979)
		(end 201.190978 119.980978)
		(width 0.09)
		(layer "In2.Cu")
		(net 273)
	)
	(segment
		(start 200.72 118.84)
		(end 200.72 118.78)
		(width 0.09)
		(layer "In2.Cu")
		(net 273)
	)
	(segment
		(start 201.388967 120.376957)
		(end 201.304115 120.46181)
		(width 0.09)
		(layer "In2.Cu")
		(net 273)
	)
	(segment
		(start 201.190979 120.178968)
		(end 201.190978 120.178968)
		(width 0.09)
		(layer "In2.Cu")
		(net 273)
	)
	(segment
		(start 200.99884 120.776002)
		(end 201.282838 121.06)
		(width 0.09)
		(layer "In2.Cu")
		(net 273)
	)
	(segment
		(start 200.09 118.51)
		(end 199.89 118.71)
		(width 0.09)
		(layer "In2.Cu")
		(net 273)
	)
	(segment
		(start 200.992988 119.980978)
		(end 200.908136 120.065831)
		(width 0.09)
		(layer "In2.Cu")
		(net 273)
	)
	(segment
		(start 200.45 118.51)
		(end 200.09 118.51)
		(width 0.09)
		(layer "In2.Cu")
		(net 273)
	)
	(segment
		(start 196.122 119.45)
		(end 196.122 117.05)
		(width 0.09)
		(layer "In2.Cu")
		(net 273)
	)
	(segment
		(start 201.282838 121.06)
		(end 201.54 121.06)
		(width 0.09)
		(layer "In2.Cu")
		(net 273)
	)
	(segment
		(start 200.72 119.51)
		(end 200.72 119.5)
		(width 0.09)
		(layer "In2.Cu")
		(net 273)
	)
	(segment
		(start 196.285357 119.613357)
		(end 196.122 119.45)
		(width 0.09)
		(layer "In2.Cu")
		(net 273)
	)
	(segment
		(start 199.89 119.08)
		(end 199.356643 119.613357)
		(width 0.09)
		(layer "In2.Cu")
		(net 273)
	)
	(segment
		(start 199.356643 119.613357)
		(end 196.285357 119.613357)
		(width 0.09)
		(layer "In2.Cu")
		(net 273)
	)
	(segment
		(start 201.64 120.96)
		(end 201.64 120.43)
		(width 0.09)
		(layer "In2.Cu")
		(net 273)
	)
	(segment
		(start 201.64 120.43)
		(end 201.586957 120.376957)
		(width 0.09)
		(layer "In2.Cu")
		(net 273)
	)
	(segment
		(start 201.54 121.06)
		(end 201.64 120.96)
		(width 0.09)
		(layer "In2.Cu")
		(net 273)
	)
	(segment
		(start 200.710147 119.867841)
		(end 200.795 119.782989)
		(width 0.09)
		(layer "In2.Cu")
		(net 273)
	)
	(segment
		(start 200.908136 120.065831)
		(end 200.908136 120.06583)
		(width 0.09)
		(layer "In2.Cu")
		(net 273)
	)
	(segment
		(start 201.304115 120.46181)
		(end 201.304115 120.461809)
		(width 0.09)
		(layer "In2.Cu")
		(net 273)
	)
	(arc
		(start 200.710147 120.065831)
		(mid 200.669142 119.966836)
		(end 200.710147 119.867841)
		(width 0.09)
		(layer "In2.Cu")
		(net 273)
	)
	(arc
		(start 200.555 119.005)
		(mid 200.671673 118.956673)
		(end 200.72 118.84)
		(width 0.09)
		(layer "In2.Cu")
		(net 273)
	)
	(arc
		(start 201.190978 120.178968)
		(mid 201.231983 120.079974)
		(end 201.190979 119.980979)
		(width 0.09)
		(layer "In2.Cu")
		(net 273)
	)
	(arc
		(start 200.22 119.17)
		(mid 200.268327 119.053327)
		(end 200.385 119.005)
		(width 0.09)
		(layer "In2.Cu")
		(net 273)
	)
	(arc
		(start 200.72 119.5)
		(mid 200.671673 119.383327)
		(end 200.555 119.335)
		(width 0.09)
		(layer "In2.Cu")
		(net 273)
	)
	(arc
		(start 200.908136 120.06583)
		(mid 200.809142 120.106835)
		(end 200.710147 120.065831)
		(width 0.09)
		(layer "In2.Cu")
		(net 273)
	)
	(arc
		(start 200.385 119.335)
		(mid 200.268327 119.286673)
		(end 200.22 119.17)
		(width 0.09)
		(layer "In2.Cu")
		(net 273)
	)
	(arc
		(start 201.190978 119.980978)
		(mid 201.091983 119.939973)
		(end 200.992988 119.980978)
		(width 0.09)
		(layer "In2.Cu")
		(net 273)
	)
	(arc
		(start 200.794999 119.782989)
		(mid 200.836004 119.683995)
		(end 200.795 119.585)
		(width 0.09)
		(layer "In2.Cu")
		(net 273)
	)
	(arc
		(start 201.304115 120.461809)
		(mid 201.205121 120.502814)
		(end 201.106126 120.46181)
		(width 0.09)
		(layer "In2.Cu")
		(net 273)
	)
	(arc
		(start 201.106126 120.46181)
		(mid 201.065121 120.362815)
		(end 201.106126 120.26382)
		(width 0.09)
		(layer "In2.Cu")
		(net 273)
	)
	(arc
		(start 201.586957 120.376957)
		(mid 201.487962 120.335952)
		(end 201.388967 120.376957)
		(width 0.09)
		(layer "In2.Cu")
		(net 273)
	)
	(segment
		(start 201.455838 121.143002)
		(end 201.55084 121.048)
		(width 0.15)
		(layer "F.Cu")
		(net 274)
	)
	(segment
		(start 200.793544 121.175558)
		(end 200.8261 121.143002)
		(width 0.15)
		(layer "F.Cu")
		(net 274)
	)
	(segment
		(start 200.8261 121.143002)
		(end 201.455838 121.143002)
		(width 0.15)
		(layer "F.Cu")
		(net 274)
	)
	(via
		(at 200.793544 121.175558)
		(size 0.35)
		(drill 0.15)
		(layers "F.Cu" "B.Cu")
		(remove_unused_layers yes)
		(keep_end_layers yes)
		(zone_layer_connections)
		(net 274)
	)
	(via
		(at 195.72 116.84)
		(size 0.35)
		(drill 0.15)
		(layers "F.Cu" "B.Cu")
		(remove_unused_layers yes)
		(keep_end_layers yes)
		(zone_layer_connections)
		(net 274)
	)
	(segment
		(start 195.72 116.84)
		(end 195.72 117.459)
		(width 0.15)
		(layer "B.Cu")
		(net 274)
	)
	(segment
		(start 195.72 117.459)
		(end 195.722 117.461)
		(width 0.15)
		(layer "B.Cu")
		(net 274)
	)
	(segment
		(start 199.11 119.87)
		(end 199.195 119.955)
		(width 0.09)
		(layer "In2.Cu")
		(net 274)
	)
	(segment
		(start 199.986956 120.746956)
		(end 199.986958 120.746958)
		(width 0.09)
		(layer "In2.Cu")
		(net 274)
	)
	(segment
		(start 199.590977 120.350977)
		(end 199.590979 120.350979)
		(width 0.09)
		(layer "In2.Cu")
		(net 274)
	)
	(segment
		(start 200.184947 120.746957)
		(end 200.184948 120.746959)
		(width 0.09)
		(layer "In2.Cu")
		(net 274)
	)
	(segment
		(start 200.723567 120.604315)
		(end 200.723569 120.604316)
		(width 0.09)
		(layer "In2.Cu")
		(net 274)
	)
	(segment
		(start 195.86 119.51)
		(end 196.22 119.87)
		(width 0.09)
		(layer "In2.Cu")
		(net 274)
	)
	(segment
		(start 200.789102 121.18)
		(end 200.793544 121.175558)
		(width 0.09)
		(layer "In2.Cu")
		(net 274)
	)
	(segment
		(start 200.42 121.18)
		(end 200.789102 121.18)
		(width 0.09)
		(layer "In2.Cu")
		(net 274)
	)
	(segment
		(start 199.788969 120.35098)
		(end 200.129562 120.010384)
		(width 0.09)
		(layer "In2.Cu")
		(net 274)
	)
	(segment
		(start 200.382936 121.142936)
		(end 200.42 121.18)
		(width 0.09)
		(layer "In2.Cu")
		(net 274)
	)
	(segment
		(start 199.39299 119.955001)
		(end 199.733583 119.614405)
		(width 0.09)
		(layer "In2.Cu")
		(net 274)
	)
	(segment
		(start 200.327551 120.010383)
		(end 200.327552 120.010384)
		(width 0.09)
		(layer "In2.Cu")
		(net 274)
	)
	(segment
		(start 195.72 116.84)
		(end 195.72 117.11)
		(width 0.09)
		(layer "In2.Cu")
		(net 274)
	)
	(segment
		(start 199.931574 119.812395)
		(end 199.590978 120.152988)
		(width 0.09)
		(layer "In2.Cu")
		(net 274)
	)
	(segment
		(start 200.184948 120.746959)
		(end 200.525578 120.406326)
		(width 0.09)
		(layer "In2.Cu")
		(net 274)
	)
	(segment
		(start 199.931572 119.614404)
		(end 199.931573 119.614405)
		(width 0.09)
		(layer "In2.Cu")
		(net 274)
	)
	(segment
		(start 196.22 119.87)
		(end 199.11 119.87)
		(width 0.09)
		(layer "In2.Cu")
		(net 274)
	)
	(segment
		(start 200.327553 120.208374)
		(end 199.986957 120.548967)
		(width 0.09)
		(layer "In2.Cu")
		(net 274)
	)
	(segment
		(start 199.788968 120.350978)
		(end 199.788969 120.35098)
		(width 0.09)
		(layer "In2.Cu")
		(net 274)
	)
	(segment
		(start 195.72 117.11)
		(end 195.86 117.25)
		(width 0.09)
		(layer "In2.Cu")
		(net 274)
	)
	(segment
		(start 199.392989 119.954999)
		(end 199.39299 119.955001)
		(width 0.09)
		(layer "In2.Cu")
		(net 274)
	)
	(segment
		(start 200.723569 120.604316)
		(end 200.382936 120.944946)
		(width 0.09)
		(layer "In2.Cu")
		(net 274)
	)
	(segment
		(start 199.931572 119.812394)
		(end 199.931574 119.812395)
		(width 0.09)
		(layer "In2.Cu")
		(net 274)
	)
	(segment
		(start 195.86 117.25)
		(end 195.86 119.51)
		(width 0.09)
		(layer "In2.Cu")
		(net 274)
	)
	(segment
		(start 200.327551 120.208373)
		(end 200.327553 120.208374)
		(width 0.09)
		(layer "In2.Cu")
		(net 274)
	)
	(arc
		(start 200.723568 120.406326)
		(mid 200.764573 120.505322)
		(end 200.723567 120.604315)
		(width 0.09)
		(layer "In2.Cu")
		(net 274)
	)
	(arc
		(start 199.986958 120.746958)
		(mid 200.085954 120.787963)
		(end 200.184947 120.746957)
		(width 0.09)
		(layer "In2.Cu")
		(net 274)
	)
	(arc
		(start 199.986957 120.548967)
		(mid 199.945953 120.647962)
		(end 199.986956 120.746956)
		(width 0.09)
		(layer "In2.Cu")
		(net 274)
	)
	(arc
		(start 199.195 119.955)
		(mid 199.293996 119.996005)
		(end 199.392989 119.954999)
		(width 0.09)
		(layer "In2.Cu")
		(net 274)
	)
	(arc
		(start 199.590978 120.152988)
		(mid 199.549974 120.251983)
		(end 199.590977 120.350977)
		(width 0.09)
		(layer "In2.Cu")
		(net 274)
	)
	(arc
		(start 199.590979 120.350979)
		(mid 199.689975 120.391984)
		(end 199.788968 120.350978)
		(width 0.09)
		(layer "In2.Cu")
		(net 274)
	)
	(arc
		(start 200.382936 120.944946)
		(mid 200.341931 121.043941)
		(end 200.382936 121.142936)
		(width 0.09)
		(layer "In2.Cu")
		(net 274)
	)
	(arc
		(start 200.525578 120.406326)
		(mid 200.624573 120.365321)
		(end 200.723568 120.406326)
		(width 0.09)
		(layer "In2.Cu")
		(net 274)
	)
	(arc
		(start 199.733583 119.614405)
		(mid 199.832578 119.573401)
		(end 199.931572 119.614404)
		(width 0.09)
		(layer "In2.Cu")
		(net 274)
	)
	(arc
		(start 200.129562 120.010384)
		(mid 200.228557 119.96938)
		(end 200.327551 120.010383)
		(width 0.09)
		(layer "In2.Cu")
		(net 274)
	)
	(arc
		(start 200.327552 120.010384)
		(mid 200.368557 120.10938)
		(end 200.327551 120.208373)
		(width 0.09)
		(layer "In2.Cu")
		(net 274)
	)
	(arc
		(start 199.931573 119.614405)
		(mid 199.972578 119.713401)
		(end 199.931572 119.812394)
		(width 0.09)
		(layer "In2.Cu")
		(net 274)
	)
	(segment
		(start 186.077 153.547)
		(end 186.475 153.945)
		(width 0.15)
		(layer "B.Cu")
		(net 275)
	)
	(segment
		(start 186.077 153.075)
		(end 186.077 153.547)
		(width 0.15)
		(layer "B.Cu")
		(net 275)
	)
	(segment
		(start 200.69884 121.789279)
		(end 201.038119 121.45)
		(width 0.15)
		(layer "F.Cu")
		(net 276)
	)
	(segment
		(start 200.69884 121.95)
		(end 200.69884 121.789279)
		(width 0.15)
		(layer "F.Cu")
		(net 276)
	)
	(segment
		(start 201.038119 121.45)
		(end 201.55084 121.45)
		(width 0.15)
		(layer "F.Cu")
		(net 276)
	)
	(via
		(at 194.53978 119.092446)
		(size 0.35)
		(drill 0.15)
		(layers "F.Cu" "B.Cu")
		(remove_unused_layers yes)
		(keep_end_layers yes)
		(zone_layer_connections)
		(net 276)
	)
	(via
		(at 200.69884 121.95)
		(size 0.35)
		(drill 0.15)
		(layers "F.Cu" "B.Cu")
		(remove_unused_layers yes)
		(keep_end_layers yes)
		(zone_layer_connections)
		(net 276)
	)
	(segment
		(start 195.078656 119.089)
		(end 195.32 119.330344)
		(width 0.15)
		(layer "B.Cu")
		(net 276)
	)
	(segment
		(start 194.543226 119.089)
		(end 195.078656 119.089)
		(width 0.15)
		(layer "B.Cu")
		(net 276)
	)
	(segment
		(start 194.53978 119.092446)
		(end 194.543226 119.089)
		(width 0.15)
		(layer "B.Cu")
		(net 276)
	)
	(segment
		(start 195.32 119.330344)
		(end 195.32 119.841)
		(width 0.15)
		(layer "B.Cu")
		(net 276)
	)
	(segment
		(start 195.53 120.31)
		(end 195.53 120.19)
		(width 0.09)
		(layer "In2.Cu")
		(net 276)
	)
	(segment
		(start 199.43 122.13)
		(end 200.51884 122.13)
		(width 0.09)
		(layer "In2.Cu")
		(net 276)
	)
	(segment
		(start 194.63 120.1)
		(end 194.96 120.1)
		(width 0.09)
		(layer "In2.Cu")
		(net 276)
	)
	(segment
		(start 198.797989 121.299999)
		(end 198.79799 121.300001)
		(width 0.09)
		(layer "In2.Cu")
		(net 276)
	)
	(segment
		(start 195.95 120.45)
		(end 198 120.45)
		(width 0.09)
		(layer "In2.Cu")
		(net 276)
	)
	(segment
		(start 195.81 120.19)
		(end 195.81 120.31)
		(width 0.09)
		(layer "In2.Cu")
		(net 276)
	)
	(segment
		(start 199.391957 122.091957)
		(end 199.43 122.13)
		(width 0.09)
		(layer "In2.Cu")
		(net 276)
	)
	(segment
		(start 198 120.45)
		(end 198.28 120.73)
		(width 0.09)
		(layer "In2.Cu")
		(net 276)
	)
	(segment
		(start 199.193969 121.69598)
		(end 199.512304 121.377642)
		(width 0.09)
		(layer "In2.Cu")
		(net 276)
	)
	(segment
		(start 194.53978 119.092446)
		(end 194.53978 120.00978)
		(width 0.09)
		(layer "In2.Cu")
		(net 276)
	)
	(segment
		(start 199.314277 121.179689)
		(end 199.314279 121.17969)
		(width 0.09)
		(layer "In2.Cu")
		(net 276)
	)
	(segment
		(start 198.79799 121.300001)
		(end 199.116288 120.9817)
		(width 0.09)
		(layer "In2.Cu")
		(net 276)
	)
	(segment
		(start 198.28 120.98)
		(end 198.6 121.3)
		(width 0.09)
		(layer "In2.Cu")
		(net 276)
	)
	(segment
		(start 199.710293 121.575631)
		(end 199.710295 121.575632)
		(width 0.09)
		(layer "In2.Cu")
		(net 276)
	)
	(segment
		(start 199.710295 121.575632)
		(end 199.391957 121.893967)
		(width 0.09)
		(layer "In2.Cu")
		(net 276)
	)
	(segment
		(start 200.51884 122.13)
		(end 200.69884 121.95)
		(width 0.09)
		(layer "In2.Cu")
		(net 276)
	)
	(segment
		(start 195.31 120.45)
		(end 195.39 120.45)
		(width 0.09)
		(layer "In2.Cu")
		(net 276)
	)
	(segment
		(start 194.53978 120.00978)
		(end 194.63 120.1)
		(width 0.09)
		(layer "In2.Cu")
		(net 276)
	)
	(segment
		(start 194.96 120.1)
		(end 195.31 120.45)
		(width 0.09)
		(layer "In2.Cu")
		(net 276)
	)
	(segment
		(start 199.193968 121.695978)
		(end 199.193969 121.69598)
		(width 0.09)
		(layer "In2.Cu")
		(net 276)
	)
	(segment
		(start 198.28 120.73)
		(end 198.28 120.98)
		(width 0.09)
		(layer "In2.Cu")
		(net 276)
	)
	(segment
		(start 198.995978 121.695978)
		(end 198.995979 121.695979)
		(width 0.09)
		(layer "In2.Cu")
		(net 276)
	)
	(segment
		(start 199.314279 121.17969)
		(end 198.995978 121.497988)
		(width 0.09)
		(layer "In2.Cu")
		(net 276)
	)
	(arc
		(start 195.67 120.05)
		(mid 195.768995 120.091005)
		(end 195.81 120.19)
		(width 0.09)
		(layer "In2.Cu")
		(net 276)
	)
	(arc
		(start 195.81 120.31)
		(mid 195.851005 120.408995)
		(end 195.95 120.45)
		(width 0.09)
		(layer "In2.Cu")
		(net 276)
	)
	(arc
		(start 199.314278 120.9817)
		(mid 199.355283 121.080696)
		(end 199.314277 121.179689)
		(width 0.09)
		(layer "In2.Cu")
		(net 276)
	)
	(arc
		(start 199.391957 121.893967)
		(mid 199.350952 121.992962)
		(end 199.391957 122.091957)
		(width 0.09)
		(layer "In2.Cu")
		(net 276)
	)
	(arc
		(start 198.995979 121.695979)
		(mid 199.094975 121.736984)
		(end 199.193968 121.695978)
		(width 0.09)
		(layer "In2.Cu")
		(net 276)
	)
	(arc
		(start 198.6 121.3)
		(mid 198.698996 121.341005)
		(end 198.797989 121.299999)
		(width 0.09)
		(layer "In2.Cu")
		(net 276)
	)
	(arc
		(start 199.512304 121.377642)
		(mid 199.611299 121.336637)
		(end 199.710294 121.377642)
		(width 0.09)
		(layer "In2.Cu")
		(net 276)
	)
	(arc
		(start 198.995978 121.497988)
		(mid 198.954973 121.596983)
		(end 198.995978 121.695978)
		(width 0.09)
		(layer "In2.Cu")
		(net 276)
	)
	(arc
		(start 199.710294 121.377642)
		(mid 199.751299 121.476638)
		(end 199.710293 121.575631)
		(width 0.09)
		(layer "In2.Cu")
		(net 276)
	)
	(arc
		(start 199.116288 120.9817)
		(mid 199.215283 120.940695)
		(end 199.314278 120.9817)
		(width 0.09)
		(layer "In2.Cu")
		(net 276)
	)
	(arc
		(start 195.53 120.19)
		(mid 195.571005 120.091005)
		(end 195.67 120.05)
		(width 0.09)
		(layer "In2.Cu")
		(net 276)
	)
	(arc
		(start 195.39 120.45)
		(mid 195.488995 120.408995)
		(end 195.53 120.31)
		(width 0.09)
		(layer "In2.Cu")
		(net 276)
	)
	(segment
		(start 201.245859 121.848)
		(end 201.55084 121.848)
		(width 0.15)
		(layer "F.Cu")
		(net 277)
	)
	(via
		(at 201.245859 121.848)
		(size 0.35)
		(drill 0.15)
		(layers "F.Cu" "B.Cu")
		(remove_unused_layers yes)
		(keep_end_layers yes)
		(zone_layer_connections)
		(net 277)
	)
	(via
		(at 194.6 118.201)
		(size 0.35)
		(drill 0.15)
		(layers "F.Cu" "B.Cu")
		(remove_unused_layers yes)
		(keep_end_layers yes)
		(zone_layer_connections)
		(net 277)
	)
	(segment
		(start 195.006656 118.201)
		(end 196.122 119.316344)
		(width 0.15)
		(layer "B.Cu")
		(net 277)
	)
	(segment
		(start 194.6 118.201)
		(end 195.006656 118.201)
		(width 0.15)
		(layer "B.Cu")
		(net 277)
	)
	(segment
		(start 196.122 119.316344)
		(end 196.122 120.171)
		(width 0.15)
		(layer "B.Cu")
		(net 277)
	)
	(segment
		(start 194.14 120.25)
		(end 194.31 120.42)
		(width 0.09)
		(layer "In2.Cu")
		(net 277)
	)
	(segment
		(start 194.31 120.42)
		(end 194.85 120.42)
		(width 0.09)
		(layer "In2.Cu")
		(net 277)
	)
	(segment
		(start 199.31 122.46)
		(end 200.633859 122.46)
		(width 0.09)
		(layer "In2.Cu")
		(net 277)
	)
	(segment
		(start 194.14 118.661)
		(end 194.14 120.25)
		(width 0.09)
		(layer "In2.Cu")
		(net 277)
	)
	(segment
		(start 200.633859 122.46)
		(end 201.245859 121.848)
		(width 0.09)
		(layer "In2.Cu")
		(net 277)
	)
	(segment
		(start 194.85 120.42)
		(end 195.16 120.73)
		(width 0.09)
		(layer "In2.Cu")
		(net 277)
	)
	(segment
		(start 195.16 120.73)
		(end 197.58 120.73)
		(width 0.09)
		(layer "In2.Cu")
		(net 277)
	)
	(segment
		(start 194.6 118.201)
		(end 194.14 118.661)
		(width 0.09)
		(layer "In2.Cu")
		(net 277)
	)
	(segment
		(start 197.58 120.73)
		(end 199.31 122.46)
		(width 0.09)
		(layer "In2.Cu")
		(net 277)
	)
	(via
		(at 195.927 121.048)
		(size 0.35)
		(drill 0.15)
		(layers "F.Cu" "B.Cu")
		(remove_unused_layers yes)
		(keep_end_layers yes)
		(zone_layer_connections)
		(net 278)
	)
	(via
		(at 198.12 116.84)
		(size 0.35)
		(drill 0.15)
		(layers "F.Cu" "B.Cu")
		(remove_unused_layers yes)
		(keep_end_layers yes)
		(zone_layer_connections)
		(net 278)
	)
	(segment
		(start 198.12 117.459)
		(end 198.122 117.461)
		(width 0.15)
		(layer "B.Cu")
		(net 278)
	)
	(segment
		(start 198.12 116.84)
		(end 198.12 117.459)
		(width 0.15)
		(layer "B.Cu")
		(net 278)
	)
	(segment
		(start 195.927 121.82)
		(end 194.55 121.82)
		(width 0.09)
		(layer "In2.Cu")
		(net 278)
	)
	(segment
		(start 193.81 117.99)
		(end 193.81 117.323593)
		(width 0.09)
		(layer "In2.Cu")
		(net 278)
	)
	(segment
		(start 196.109722 121.637278)
		(end 195.927 121.82)
		(width 0.09)
		(layer "In2.Cu")
		(net 278)
	)
	(segment
		(start 196.109722 121.230722)
		(end 196.109722 121.637278)
		(width 0.09)
		(layer "In2.Cu")
		(net 278)
	)
	(segment
		(start 193.81 117.323593)
		(end 194.952593 116.181)
		(width 0.09)
		(layer "In2.Cu")
		(net 278)
	)
	(segment
		(start 198.12 116.561593)
		(end 198.12 116.84)
		(width 0.09)
		(layer "In2.Cu")
		(net 278)
	)
	(segment
		(start 195.927 121.048)
		(end 196.109722 121.230722)
		(width 0.09)
		(layer "In2.Cu")
		(net 278)
	)
	(segment
		(start 192.98 118.82)
		(end 193.81 117.99)
		(width 0.09)
		(layer "In2.Cu")
		(net 278)
	)
	(segment
		(start 192.98 120.25)
		(end 192.98 118.82)
		(width 0.09)
		(layer "In2.Cu")
		(net 278)
	)
	(segment
		(start 194.952593 116.181)
		(end 197.739407 116.181)
		(width 0.09)
		(layer "In2.Cu")
		(net 278)
	)
	(segment
		(start 197.739407 116.181)
		(end 198.12 116.561593)
		(width 0.09)
		(layer "In2.Cu")
		(net 278)
	)
	(segment
		(start 194.55 121.82)
		(end 192.98 120.25)
		(width 0.09)
		(layer "In2.Cu")
		(net 278)
	)
	(via
		(at 217.265 141.15)
		(size 0.35)
		(drill 0.15)
		(layers "F.Cu" "B.Cu")
		(remove_unused_layers yes)
		(keep_end_layers yes)
		(zone_layer_connections)
		(net 279)
	)
	(segment
		(start 216.95 141.1)
		(end 217.215 141.1)
		(width 0.174)
		(layer "B.Cu")
		(net 279)
	)
	(segment
		(start 217.215 141.1)
		(end 217.265 141.15)
		(width 0.174)
		(layer "B.Cu")
		(net 279)
	)
	(via
		(at 213.265 143.65)
		(size 0.35)
		(drill 0.15)
		(layers "F.Cu" "B.Cu")
		(remove_unused_layers yes)
		(keep_end_layers yes)
		(zone_layer_connections)
		(net 280)
	)
	(segment
		(start 212.945 144.15)
		(end 212.945 144.075)
		(width 0.15)
		(layer "B.Cu")
		(net 280)
	)
	(segment
		(start 213.265 143.755)
		(end 213.265 143.65)
		(width 0.15)
		(layer "B.Cu")
		(net 280)
	)
	(segment
		(start 212.945 144.075)
		(end 213.265 143.755)
		(width 0.15)
		(layer "B.Cu")
		(net 280)
	)
	(segment
		(start 223.6235 146.595)
		(end 223.6015 146.617)
		(width 0.15)
		(layer "F.Cu")
		(net 281)
	)
	(segment
		(start 223.64 145.96)
		(end 223.6235 145.9765)
		(width 0.15)
		(layer "F.Cu")
		(net 281)
	)
	(segment
		(start 223.6235 145.9765)
		(end 223.6235 146.595)
		(width 0.15)
		(layer "F.Cu")
		(net 281)
	)
	(via
		(at 223.64 145.96)
		(size 0.35)
		(drill 0.15)
		(layers "F.Cu" "B.Cu")
		(remove_unused_layers yes)
		(keep_end_layers yes)
		(zone_layer_connections)
		(net 281)
	)
	(segment
		(start 224.165 145.96)
		(end 224.525 146.32)
		(width 0.15)
		(layer "B.Cu")
		(net 281)
	)
	(segment
		(start 223.64 145.96)
		(end 224.165 145.96)
		(width 0.15)
		(layer "B.Cu")
		(net 281)
	)
	(segment
		(start 224.525 146.32)
		(end 225.1075 146.32)
		(width 0.15)
		(layer "B.Cu")
		(net 281)
	)
	(segment
		(start 214.55 123.875)
		(end 214.55 124.365)
		(width 0.15)
		(layer "F.Cu")
		(net 282)
	)
	(segment
		(start 214.161 124.754)
		(end 214.061 124.754)
		(width 0.15)
		(layer "F.Cu")
		(net 282)
	)
	(segment
		(start 214.55 124.365)
		(end 214.161 124.754)
		(width 0.15)
		(layer "F.Cu")
		(net 282)
	)
	(via
		(at 214.061 124.754)
		(size 0.35)
		(drill 0.15)
		(layers "F.Cu" "B.Cu")
		(remove_unused_layers yes)
		(keep_end_layers yes)
		(zone_layer_connections)
		(net 282)
	)
	(segment
		(start 214.576 124.754)
		(end 213.596 124.754)
		(width 0.174)
		(layer "B.Cu")
		(net 282)
	)
	(segment
		(start 191.49522 146.75)
		(end 192.14 146.75)
		(width 0.15)
		(layer "F.Cu")
		(net 283)
	)
	(segment
		(start 191.494751 146.749531)
		(end 191.49522 146.75)
		(width 0.15)
		(layer "F.Cu")
		(net 283)
	)
	(via
		(at 191.494751 146.749531)
		(size 0.35)
		(drill 0.15)
		(layers "F.Cu" "B.Cu")
		(remove_unused_layers yes)
		(keep_end_layers yes)
		(zone_layer_connections)
		(net 283)
	)
	(segment
		(start 191.35 146.60478)
		(end 191.494751 146.749531)
		(width 0.15)
		(layer "B.Cu")
		(net 283)
	)
	(segment
		(start 191.87 143.15)
		(end 191.87 143.326715)
		(width 0.15)
		(layer "B.Cu")
		(net 283)
	)
	(segment
		(start 191.35 143.846715)
		(end 191.35 146.60478)
		(width 0.15)
		(layer "B.Cu")
		(net 283)
	)
	(segment
		(start 191.87 143.326715)
		(end 191.35 143.846715)
		(width 0.15)
		(layer "B.Cu")
		(net 283)
	)
	(segment
		(start 206.801 125.901)
		(end 206.1 125.901)
		(width 0.1)
		(layer "F.Cu")
		(net 285)
	)
	(segment
		(start 219.68 126.95)
		(end 211.19 126.95)
		(width 0.1)
		(layer "F.Cu")
		(net 285)
	)
	(segment
		(start 220.46 126.17)
		(end 219.68 126.95)
		(width 0.1)
		(layer "F.Cu")
		(net 285)
	)
	(segment
		(start 210.65 126.41)
		(end 211.19 126.95)
		(width 0.1)
		(layer "F.Cu")
		(net 285)
	)
	(segment
		(start 207.31 126.41)
		(end 206.801 125.901)
		(width 0.1)
		(layer "F.Cu")
		(net 285)
	)
	(segment
		(start 207.31 126.41)
		(end 210.65 126.41)
		(width 0.1)
		(layer "F.Cu")
		(net 285)
	)
	(via
		(at 221.46 151.13)
		(size 0.35)
		(drill 0.15)
		(layers "F.Cu" "B.Cu")
		(remove_unused_layers yes)
		(keep_end_layers yes)
		(zone_layer_connections)
		(net 285)
	)
	(via
		(at 220.46 126.17)
		(size 0.35)
		(drill 0.15)
		(layers "F.Cu" "B.Cu")
		(remove_unused_layers yes)
		(keep_end_layers yes)
		(zone_layer_connections)
		(net 285)
	)
	(segment
		(start 225.075 148.725)
		(end 225.075 148.305)
		(width 0.1)
		(layer "B.Cu")
		(net 285)
	)
	(segment
		(start 224.8 149)
		(end 225.075 148.725)
		(width 0.1)
		(layer "B.Cu")
		(net 285)
	)
	(segment
		(start 221.46 150.55)
		(end 223.01 149)
		(width 0.1)
		(layer "B.Cu")
		(net 285)
	)
	(segment
		(start 223.01 149)
		(end 224.8 149)
		(width 0.1)
		(layer "B.Cu")
		(net 285)
	)
	(segment
		(start 221.46 151.13)
		(end 221.46 150.55)
		(width 0.1)
		(layer "B.Cu")
		(net 285)
	)
	(segment
		(start 220.6 129.875)
		(end 220.46 129.735)
		(width 0.1)
		(layer "In9.Cu")
		(net 285)
	)
	(segment
		(start 220.12 144.52)
		(end 220.12 142.48)
		(width 0.1)
		(layer "In9.Cu")
		(net 285)
	)
	(segment
		(start 220.46 129.735)
		(end 220.46 126.17)
		(width 0.1)
		(layer "In9.Cu")
		(net 285)
	)
	(segment
		(start 220.6 138.925)
		(end 220.6 129.875)
		(width 0.1)
		(layer "In9.Cu")
		(net 285)
	)
	(segment
		(start 221.46 149.71)
		(end 220.41 148.66)
		(width 0.1)
		(layer "In9.Cu")
		(net 285)
	)
	(segment
		(start 220.12 142.48)
		(end 220.92 141.68)
		(width 0.1)
		(layer "In9.Cu")
		(net 285)
	)
	(segment
		(start 220.41 144.81)
		(end 220.12 144.52)
		(width 0.1)
		(layer "In9.Cu")
		(net 285)
	)
	(segment
		(start 220.92 139.245)
		(end 220.6 138.925)
		(width 0.1)
		(layer "In9.Cu")
		(net 285)
	)
	(segment
		(start 220.92 141.68)
		(end 220.92 139.245)
		(width 0.1)
		(layer "In9.Cu")
		(net 285)
	)
	(segment
		(start 220.41 148.66)
		(end 220.41 144.81)
		(width 0.1)
		(layer "In9.Cu")
		(net 285)
	)
	(segment
		(start 221.46 151.13)
		(end 221.46 149.71)
		(width 0.1)
		(layer "In9.Cu")
		(net 285)
	)
	(segment
		(start 202.9 128.3)
		(end 203.0375 128.4375)
		(width 0.1)
		(layer "F.Cu")
		(net 286)
	)
	(segment
		(start 203.2875 128.4375)
		(end 203.55 128.7)
		(width 0.1)
		(layer "F.Cu")
		(net 286)
	)
	(segment
		(start 221.45 126.5)
		(end 224.6 126.5)
		(width 0.1)
		(layer "F.Cu")
		(net 286)
	)
	(segment
		(start 207.225 128.55)
		(end 207.225 128.471241)
		(width 0.1)
		(layer "F.Cu")
		(net 286)
	)
	(segment
		(start 224.86 126.24)
		(end 224.86 125.475)
		(width 0.1)
		(layer "F.Cu")
		(net 286)
	)
	(segment
		(start 208.78 128.7)
		(end 208.875 128.7)
		(width 0.1)
		(layer "F.Cu")
		(net 286)
	)
	(segment
		(start 209.2 129.025)
		(end 209.2 135.31412)
		(width 0.1)
		(layer "F.Cu")
		(net 286)
	)
	(segment
		(start 207.525 128.471241)
		(end 207.525 128.55)
		(width 0.1)
		(layer "F.Cu")
		(net 286)
	)
	(segment
		(start 224.6 126.5)
		(end 224.86 126.24)
		(width 0.1)
		(layer "F.Cu")
		(net 286)
	)
	(segment
		(start 203.0375 128.4375)
		(end 203.2875 128.4375)
		(width 0.1)
		(layer "F.Cu")
		(net 286)
	)
	(segment
		(start 208.345 128.555)
		(end 208.345 128.227251)
		(width 0.1)
		(layer "F.Cu")
		(net 286)
	)
	(segment
		(start 209.2 135.31412)
		(end 209.55788 135.672)
		(width 0.1)
		(layer "F.Cu")
		(net 286)
	)
	(segment
		(start 207.675 128.7)
		(end 208.2 128.7)
		(width 0.1)
		(layer "F.Cu")
		(net 286)
	)
	(segment
		(start 210.67 136.17)
		(end 219.98 136.17)
		(width 0.1)
		(layer "F.Cu")
		(net 286)
	)
	(segment
		(start 203.55 128.7)
		(end 206.475 128.7)
		(width 0.1)
		(layer "F.Cu")
		(net 286)
	)
	(segment
		(start 206.625 128.55)
		(end 206.625 128.471241)
		(width 0.1)
		(layer "F.Cu")
		(net 286)
	)
	(segment
		(start 220.525 135.625)
		(end 220.525 127.425)
		(width 0.1)
		(layer "F.Cu")
		(net 286)
	)
	(segment
		(start 219.98 136.17)
		(end 220.525 135.625)
		(width 0.1)
		(layer "F.Cu")
		(net 286)
	)
	(segment
		(start 209.55788 135.672)
		(end 210.172 135.672)
		(width 0.1)
		(layer "F.Cu")
		(net 286)
	)
	(segment
		(start 208.635 128.227251)
		(end 208.635 128.555)
		(width 0.1)
		(layer "F.Cu")
		(net 286)
	)
	(segment
		(start 206.925 128.471241)
		(end 206.925 128.55)
		(width 0.1)
		(layer "F.Cu")
		(net 286)
	)
	(segment
		(start 208.875 128.7)
		(end 209.2 129.025)
		(width 0.1)
		(layer "F.Cu")
		(net 286)
	)
	(segment
		(start 210.172 135.672)
		(end 210.67 136.17)
		(width 0.1)
		(layer "F.Cu")
		(net 286)
	)
	(segment
		(start 220.525 127.425)
		(end 221.45 126.5)
		(width 0.1)
		(layer "F.Cu")
		(net 286)
	)
	(arc
		(start 208.2 128.7)
		(mid 208.30253 128.65753)
		(end 208.345 128.555)
		(width 0.1)
		(layer "F.Cu")
		(net 286)
	)
	(arc
		(start 206.475 128.7)
		(mid 206.581066 128.656066)
		(end 206.625 128.55)
		(width 0.1)
		(layer "F.Cu")
		(net 286)
	)
	(arc
		(start 206.925 128.55)
		(mid 206.968934 128.656066)
		(end 207.075 128.7)
		(width 0.1)
		(layer "F.Cu")
		(net 286)
	)
	(arc
		(start 207.075 128.7)
		(mid 207.181066 128.656066)
		(end 207.225 128.55)
		(width 0.1)
		(layer "F.Cu")
		(net 286)
	)
	(arc
		(start 208.49 128.082251)
		(mid 208.59253 128.124721)
		(end 208.635 128.227251)
		(width 0.1)
		(layer "F.Cu")
		(net 286)
	)
	(arc
		(start 206.775 128.321241)
		(mid 206.881066 128.365175)
		(end 206.925 128.471241)
		(width 0.1)
		(layer "F.Cu")
		(net 286)
	)
	(arc
		(start 207.525 128.55)
		(mid 207.568934 128.656066)
		(end 207.675 128.7)
		(width 0.1)
		(layer "F.Cu")
		(net 286)
	)
	(arc
		(start 208.635 128.555)
		(mid 208.67747 128.65753)
		(end 208.78 128.7)
		(width 0.1)
		(layer "F.Cu")
		(net 286)
	)
	(arc
		(start 208.345 128.227251)
		(mid 208.38747 128.124721)
		(end 208.49 128.082251)
		(width 0.1)
		(layer "F.Cu")
		(net 286)
	)
	(arc
		(start 207.375 128.321241)
		(mid 207.481066 128.365175)
		(end 207.525 128.471241)
		(width 0.1)
		(layer "F.Cu")
		(net 286)
	)
	(arc
		(start 207.225 128.471241)
		(mid 207.268934 128.365175)
		(end 207.375 128.321241)
		(width 0.1)
		(layer "F.Cu")
		(net 286)
	)
	(arc
		(start 206.625 128.471241)
		(mid 206.668934 128.365175)
		(end 206.775 128.321241)
		(width 0.1)
		(layer "F.Cu")
		(net 286)
	)
	(segment
		(start 210.39 136.42)
		(end 220.43 136.42)
		(width 0.1)
		(layer "F.Cu")
		(net 287)
	)
	(segment
		(start 209.26 135.91)
		(end 209.88 135.91)
		(width 0.1)
		(layer "F.Cu")
		(net 287)
	)
	(segment
		(start 220.95 135.9)
		(end 220.95 127.95)
		(width 0.1)
		(layer "F.Cu")
		(net 287)
	)
	(segment
		(start 203.1 128.7)
		(end 203.3 128.9)
		(width 0.1)
		(layer "F.Cu")
		(net 287)
	)
	(segment
		(start 208.8 129.4)
		(end 208.8 135.45)
		(width 0.1)
		(layer "F.Cu")
		(net 287)
	)
	(segment
		(start 203.5 129.5)
		(end 206.4 129.5)
		(width 0.1)
		(layer "F.Cu")
		(net 287)
	)
	(segment
		(start 220.43 136.42)
		(end 220.95 135.9)
		(width 0.1)
		(layer "F.Cu")
		(net 287)
	)
	(segment
		(start 208.8 135.45)
		(end 209.26 135.91)
		(width 0.1)
		(layer "F.Cu")
		(net 287)
	)
	(segment
		(start 220.95 127.95)
		(end 221.8 127.1)
		(width 0.1)
		(layer "F.Cu")
		(net 287)
	)
	(segment
		(start 202.1 129.1)
		(end 202.5 128.7)
		(width 0.1)
		(layer "F.Cu")
		(net 287)
	)
	(segment
		(start 202.5 128.7)
		(end 203.1 128.7)
		(width 0.1)
		(layer "F.Cu")
		(net 287)
	)
	(segment
		(start 225.45 127.1)
		(end 226.13 126.42)
		(width 0.1)
		(layer "F.Cu")
		(net 287)
	)
	(segment
		(start 208.5 129.1)
		(end 208.8 129.4)
		(width 0.1)
		(layer "F.Cu")
		(net 287)
	)
	(segment
		(start 203.3 129.3)
		(end 203.5 129.5)
		(width 0.1)
		(layer "F.Cu")
		(net 287)
	)
	(segment
		(start 226.13 126.42)
		(end 226.13 125.475)
		(width 0.1)
		(layer "F.Cu")
		(net 287)
	)
	(segment
		(start 203.3 128.9)
		(end 203.3 129.3)
		(width 0.1)
		(layer "F.Cu")
		(net 287)
	)
	(segment
		(start 221.8 127.1)
		(end 225.45 127.1)
		(width 0.1)
		(layer "F.Cu")
		(net 287)
	)
	(segment
		(start 206.4 129.5)
		(end 206.8 129.1)
		(width 0.1)
		(layer "F.Cu")
		(net 287)
	)
	(segment
		(start 209.88 135.91)
		(end 210.39 136.42)
		(width 0.1)
		(layer "F.Cu")
		(net 287)
	)
	(segment
		(start 206.8 129.1)
		(end 208.5 129.1)
		(width 0.1)
		(layer "F.Cu")
		(net 287)
	)
	(segment
		(start 221.525 131.925)
		(end 221.7 131.925)
		(width 0.1)
		(layer "F.Cu")
		(net 288)
	)
	(segment
		(start 222.025 135.475)
		(end 222.025 134.775)
		(width 0.1)
		(layer "F.Cu")
		(net 288)
	)
	(segment
		(start 223.125 132.075)
		(end 223.125 132.925)
		(width 0.1)
		(layer "F.Cu")
		(net 288)
	)
	(segment
		(start 222.15 132.425)
		(end 222.15 132.075)
		(width 0.1)
		(layer "F.Cu")
		(net 288)
	)
	(segment
		(start 210.05962 136.775)
		(end 216.55 136.775)
		(width 0.1)
		(layer "F.Cu")
		(net 288)
	)
	(segment
		(start 219.6 136.775)
		(end 220.725 136.775)
		(width 0.1)
		(layer "F.Cu")
		(net 288)
	)
	(segment
		(start 209.45962 136.175)
		(end 210.05962 136.775)
		(width 0.1)
		(layer "F.Cu")
		(net 288)
	)
	(segment
		(start 219.25 137.125)
		(end 219.6 136.775)
		(width 0.1)
		(layer "F.Cu")
		(net 288)
	)
	(segment
		(start 208.4 129.775)
		(end 208.4 135.7)
		(width 0.1)
		(layer "F.Cu")
		(net 288)
	)
	(segment
		(start 208.15 129.525)
		(end 208.4 129.775)
		(width 0.1)
		(layer "F.Cu")
		(net 288)
	)
	(segment
		(start 201.7 129.5)
		(end 203.1 129.5)
		(width 0.1)
		(layer "F.Cu")
		(net 288)
	)
	(segment
		(start 207.146094 129.525)
		(end 208.15 129.525)
		(width 0.1)
		(layer "F.Cu")
		(net 288)
	)
	(segment
		(start 221.268298 135.312464)
		(end 221.268297 135.312465)
		(width 0.1)
		(layer "F.Cu")
		(net 288)
	)
	(segment
		(start 222.975 131.925)
		(end 223.125 132.075)
		(width 0.1)
		(layer "F.Cu")
		(net 288)
	)
	(segment
		(start 223.125 132.925)
		(end 222.775 133.275)
		(width 0.1)
		(layer "F.Cu")
		(net 288)
	)
	(segment
		(start 221.508715 135.312464)
		(end 221.727919 135.531668)
		(width 0.1)
		(layer "F.Cu")
		(net 288)
	)
	(segment
		(start 221.833952 134.325)
		(end 221.875 134.325)
		(width 0.1)
		(layer "F.Cu")
		(net 288)
	)
	(segment
		(start 222.025 134.125)
		(end 221.3 133.4)
		(width 0.1)
		(layer "F.Cu")
		(net 288)
	)
	(segment
		(start 216.55 136.775)
		(end 216.9 137.125)
		(width 0.1)
		(layer "F.Cu")
		(net 288)
	)
	(segment
		(start 221.968336 135.531667)
		(end 221.968335 135.531668)
		(width 0.1)
		(layer "F.Cu")
		(net 288)
	)
	(segment
		(start 220.725 136.775)
		(end 221.4875 136.0125)
		(width 0.1)
		(layer "F.Cu")
		(net 288)
	)
	(segment
		(start 222.025 134.175)
		(end 222.025 134.125)
		(width 0.1)
		(layer "F.Cu")
		(net 288)
	)
	(segment
		(start 203.3 130.1)
		(end 203.475 130.275)
		(width 0.1)
		(layer "F.Cu")
		(net 288)
	)
	(segment
		(start 222.9 131.925)
		(end 222.975 131.925)
		(width 0.1)
		(layer "F.Cu")
		(net 288)
	)
	(segment
		(start 221.508715 135.312465)
		(end 221.508715 135.312464)
		(width 0.1)
		(layer "F.Cu")
		(net 288)
	)
	(segment
		(start 203.3 129.7)
		(end 203.3 130.1)
		(width 0.1)
		(layer "F.Cu")
		(net 288)
	)
	(segment
		(start 222.775 133.275)
		(end 222.32 133.275)
		(width 0.1)
		(layer "F.Cu")
		(net 288)
	)
	(segment
		(start 203.475 130.275)
		(end 206.396094 130.275)
		(width 0.1)
		(layer "F.Cu")
		(net 288)
	)
	(segment
		(start 221.3 132.775)
		(end 221.3 132.15)
		(width 0.1)
		(layer "F.Cu")
		(net 288)
	)
	(segment
		(start 221.3 133.4)
		(end 221.3 133.375)
		(width 0.1)
		(layer "F.Cu")
		(net 288)
	)
	(segment
		(start 222.45 132.075)
		(end 222.45 132.425)
		(width 0.1)
		(layer "F.Cu")
		(net 288)
	)
	(segment
		(start 221.875 134.625)
		(end 221.833952 134.625)
		(width 0.1)
		(layer "F.Cu")
		(net 288)
	)
	(segment
		(start 221.4875 135.772084)
		(end 221.268297 135.552881)
		(width 0.1)
		(layer "F.Cu")
		(net 288)
	)
	(segment
		(start 206.396094 130.275)
		(end 207.146094 129.525)
		(width 0.1)
		(layer "F.Cu")
		(net 288)
	)
	(segment
		(start 221.7 132.925)
		(end 221.45 132.925)
		(width 0.1)
		(layer "F.Cu")
		(net 288)
	)
	(segment
		(start 221.968335 135.531668)
		(end 222.025 135.475)
		(width 0.1)
		(layer "F.Cu")
		(net 288)
	)
	(segment
		(start 216.9 137.125)
		(end 219.25 137.125)
		(width 0.1)
		(layer "F.Cu")
		(net 288)
	)
	(segment
		(start 208.4 135.7)
		(end 208.875 136.175)
		(width 0.1)
		(layer "F.Cu")
		(net 288)
	)
	(segment
		(start 221.85 132.075)
		(end 221.85 132.425)
		(width 0.1)
		(layer "F.Cu")
		(net 288)
	)
	(segment
		(start 222.75 132.425)
		(end 222.75 132.075)
		(width 0.1)
		(layer "F.Cu")
		(net 288)
	)
	(segment
		(start 208.875 136.175)
		(end 209.45962 136.175)
		(width 0.1)
		(layer "F.Cu")
		(net 288)
	)
	(segment
		(start 201.3 129.1)
		(end 201.7 129.5)
		(width 0.1)
		(layer "F.Cu")
		(net 288)
	)
	(segment
		(start 203.1 129.5)
		(end 203.3 129.7)
		(width 0.1)
		(layer "F.Cu")
		(net 288)
	)
	(segment
		(start 221.45 133.225)
		(end 221.7 133.225)
		(width 0.1)
		(layer "F.Cu")
		(net 288)
	)
	(segment
		(start 221.3 132.15)
		(end 221.525 131.925)
		(width 0.1)
		(layer "F.Cu")
		(net 288)
	)
	(arc
		(start 221.85 132.425)
		(mid 221.893934 132.531066)
		(end 222 132.575)
		(width 0.1)
		(layer "F.Cu")
		(net 288)
	)
	(arc
		(start 221.683952 134.475)
		(mid 221.727886 134.368934)
		(end 221.833952 134.325)
		(width 0.1)
		(layer "F.Cu")
		(net 288)
	)
	(arc
		(start 222.15 132.075)
		(mid 222.193934 131.968934)
		(end 222.3 131.925)
		(width 0.1)
		(layer "F.Cu")
		(net 288)
	)
	(arc
		(start 221.833952 134.625)
		(mid 221.727886 134.581066)
		(end 221.683952 134.475)
		(width 0.1)
		(layer "F.Cu")
		(net 288)
	)
	(arc
		(start 221.268297 135.312465)
		(mid 221.388507 135.262672)
		(end 221.508715 135.312465)
		(width 0.1)
		(layer "F.Cu")
		(net 288)
	)
	(arc
		(start 221.45 132.925)
		(mid 221.343934 132.881066)
		(end 221.3 132.775)
		(width 0.1)
		(layer "F.Cu")
		(net 288)
	)
	(arc
		(start 222.6 132.575)
		(mid 222.706066 132.531066)
		(end 222.75 132.425)
		(width 0.1)
		(layer "F.Cu")
		(net 288)
	)
	(arc
		(start 221.268297 135.552881)
		(mid 221.218506 135.432672)
		(end 221.268298 135.312464)
		(width 0.1)
		(layer "F.Cu")
		(net 288)
	)
	(arc
		(start 221.875 134.325)
		(mid 221.981066 134.281066)
		(end 222.025 134.175)
		(width 0.1)
		(layer "F.Cu")
		(net 288)
	)
	(arc
		(start 221.727919 135.531668)
		(mid 221.848128 135.581459)
		(end 221.968336 135.531667)
		(width 0.1)
		(layer "F.Cu")
		(net 288)
	)
	(arc
		(start 221.7 133.225)
		(mid 221.806066 133.181066)
		(end 221.85 133.075)
		(width 0.1)
		(layer "F.Cu")
		(net 288)
	)
	(arc
		(start 222.025 134.775)
		(mid 221.981066 134.668934)
		(end 221.875 134.625)
		(width 0.1)
		(layer "F.Cu")
		(net 288)
	)
	(arc
		(start 221.85 133.075)
		(mid 221.806066 132.968934)
		(end 221.7 132.925)
		(width 0.1)
		(layer "F.Cu")
		(net 288)
	)
	(arc
		(start 222 132.575)
		(mid 222.106066 132.531066)
		(end 222.15 132.425)
		(width 0.1)
		(layer "F.Cu")
		(net 288)
	)
	(arc
		(start 221.4875 136.0125)
		(mid 221.537292 135.892292)
		(end 221.4875 135.772084)
		(width 0.1)
		(layer "F.Cu")
		(net 288)
	)
	(arc
		(start 221.7 131.925)
		(mid 221.806066 131.968934)
		(end 221.85 132.075)
		(width 0.1)
		(layer "F.Cu")
		(net 288)
	)
	(arc
		(start 221.3 133.375)
		(mid 221.343934 133.268934)
		(end 221.45 133.225)
		(width 0.1)
		(layer "F.Cu")
		(net 288)
	)
	(arc
		(start 222.3 131.925)
		(mid 222.406066 131.968934)
		(end 222.45 132.075)
		(width 0.1)
		(layer "F.Cu")
		(net 288)
	)
	(arc
		(start 222.45 132.425)
		(mid 222.493934 132.531066)
		(end 222.6 132.575)
		(width 0.1)
		(layer "F.Cu")
		(net 288)
	)
	(arc
		(start 222.75 132.075)
		(mid 222.793934 131.968934)
		(end 222.9 131.925)
		(width 0.1)
		(layer "F.Cu")
		(net 288)
	)
	(via
		(at 205.665 142.6)
		(size 0.35)
		(drill 0.15)
		(layers "F.Cu" "B.Cu")
		(remove_unused_layers yes)
		(keep_end_layers yes)
		(zone_layer_connections)
		(net 289)
	)
	(via
		(at 205.649 145.451)
		(size 0.35)
		(drill 0.15)
		(layers "F.Cu" "B.Cu")
		(remove_unused_layers yes)
		(keep_end_layers yes)
		(zone_layer_connections)
		(net 289)
	)
	(via
		(at 202.9 136.3)
		(size 0.35)
		(drill 0.15)
		(layers "F.Cu" "B.Cu")
		(remove_unused_layers yes)
		(keep_end_layers yes)
		(zone_layer_connections)
		(net 289)
	)
	(segment
		(start 205.649 145.451)
		(end 205.324 145.126)
		(width 0.1)
		(layer "In2.Cu")
		(net 289)
	)
	(segment
		(start 203.3 142.5)
		(end 203.3 136.7)
		(width 0.1)
		(layer "In2.Cu")
		(net 289)
	)
	(segment
		(start 203.3 136.7)
		(end 202.9 136.3)
		(width 0.1)
		(layer "In2.Cu")
		(net 289)
	)
	(segment
		(start 205.324 145.126)
		(end 204.86438 145.126)
		(width 0.1)
		(layer "In2.Cu")
		(net 289)
	)
	(segment
		(start 204.674 144.93562)
		(end 204.674 143.874)
		(width 0.1)
		(layer "In2.Cu")
		(net 289)
	)
	(segment
		(start 204.86438 145.126)
		(end 204.674 144.93562)
		(width 0.1)
		(layer "In2.Cu")
		(net 289)
	)
	(segment
		(start 204.674 143.874)
		(end 203.3 142.5)
		(width 0.1)
		(layer "In2.Cu")
		(net 289)
	)
	(segment
		(start 205.974 145.126)
		(end 205.649 145.451)
		(width 0.1)
		(layer "In7.Cu")
		(net 289)
	)
	(segment
		(start 205.665 142.6)
		(end 205.974 142.909)
		(width 0.1)
		(layer "In7.Cu")
		(net 289)
	)
	(segment
		(start 205.974 142.909)
		(end 205.974 145.126)
		(width 0.1)
		(layer "In7.Cu")
		(net 289)
	)
	(segment
		(start 223.59 133.275)
		(end 223.59 133.51)
		(width 0.1)
		(layer "F.Cu")
		(net 290)
	)
	(segment
		(start 207.425 132.05)
		(end 207.875 132.05)
		(width 0.1)
		(layer "F.Cu")
		(net 290)
	)
	(segment
		(start 223.59 133.51)
		(end 222.9 134.2)
		(width 0.1)
		(layer "F.Cu")
		(net 290)
	)
	(segment
		(start 222.9 135.3)
		(end 221.025 137.175)
		(width 0.1)
		(layer "F.Cu")
		(net 290)
	)
	(segment
		(start 207.875 130.8)
		(end 207.225 130.8)
		(width 0.1)
		(layer "F.Cu")
		(net 290)
	)
	(segment
		(start 206.475 131.136)
		(end 200.864 131.136)
		(width 0.1)
		(layer "F.Cu")
		(net 290)
	)
	(segment
		(start 207.225 131.05)
		(end 207.875 131.05)
		(width 0.1)
		(layer "F.Cu")
		(net 290)
	)
	(segment
		(start 200.864 131.136)
		(end 200.499 131.501)
		(width 0.1)
		(layer "F.Cu")
		(net 290)
	)
	(segment
		(start 207.875 131.3)
		(end 207.225 131.3)
		(width 0.1)
		(layer "F.Cu")
		(net 290)
	)
	(segment
		(start 219.975 137.175)
		(end 219.5 137.65)
		(width 0.1)
		(layer "F.Cu")
		(net 290)
	)
	(segment
		(start 222.9 134.2)
		(end 222.9 135.3)
		(width 0.1)
		(layer "F.Cu")
		(net 290)
	)
	(segment
		(start 208 130.425)
		(end 208 130.15)
		(width 0.1)
		(layer "F.Cu")
		(net 290)
	)
	(segment
		(start 208 130.15)
		(end 207.8 129.95)
		(width 0.1)
		(layer "F.Cu")
		(net 290)
	)
	(segment
		(start 209.075 137.175)
		(end 208 136.1)
		(width 0.1)
		(layer "F.Cu")
		(net 290)
	)
	(segment
		(start 208 136.1)
		(end 208 132.425)
		(width 0.1)
		(layer "F.Cu")
		(net 290)
	)
	(segment
		(start 206.75 130.55)
		(end 206.75 130.861)
		(width 0.1)
		(layer "F.Cu")
		(net 290)
	)
	(segment
		(start 206.75 130.861)
		(end 206.475 131.136)
		(width 0.1)
		(layer "F.Cu")
		(net 290)
	)
	(segment
		(start 207.35 129.95)
		(end 206.75 130.55)
		(width 0.1)
		(layer "F.Cu")
		(net 290)
	)
	(segment
		(start 216.625 137.65)
		(end 216.15 137.175)
		(width 0.1)
		(layer "F.Cu")
		(net 290)
	)
	(segment
		(start 207.8 129.95)
		(end 207.35 129.95)
		(width 0.1)
		(layer "F.Cu")
		(net 290)
	)
	(segment
		(start 207.875 132.3)
		(end 207.425 132.3)
		(width 0.1)
		(layer "F.Cu")
		(net 290)
	)
	(segment
		(start 219.5 137.65)
		(end 216.625 137.65)
		(width 0.1)
		(layer "F.Cu")
		(net 290)
	)
	(segment
		(start 207.225 130.55)
		(end 207.875 130.55)
		(width 0.1)
		(layer "F.Cu")
		(net 290)
	)
	(segment
		(start 221.025 137.175)
		(end 219.975 137.175)
		(width 0.1)
		(layer "F.Cu")
		(net 290)
	)
	(segment
		(start 207.875 131.8)
		(end 207.225 131.8)
		(width 0.1)
		(layer "F.Cu")
		(net 290)
	)
	(segment
		(start 216.15 137.175)
		(end 209.075 137.175)
		(width 0.1)
		(layer "F.Cu")
		(net 290)
	)
	(segment
		(start 207.225 131.55)
		(end 207.875 131.55)
		(width 0.1)
		(layer "F.Cu")
		(net 290)
	)
	(arc
		(start 208 131.925)
		(mid 207.963388 131.836612)
		(end 207.875 131.8)
		(width 0.1)
		(layer "F.Cu")
		(net 290)
	)
	(arc
		(start 207.225 131.8)
		(mid 207.136612 131.763388)
		(end 207.1 131.675)
		(width 0.1)
		(layer "F.Cu")
		(net 290)
	)
	(arc
		(start 207.225 131.3)
		(mid 207.136612 131.263388)
		(end 207.1 131.175)
		(width 0.1)
		(layer "F.Cu")
		(net 290)
	)
	(arc
		(start 208 130.925)
		(mid 207.963388 130.836612)
		(end 207.875 130.8)
		(width 0.1)
		(layer "F.Cu")
		(net 290)
	)
	(arc
		(start 207.1 131.175)
		(mid 207.136612 131.086612)
		(end 207.225 131.05)
		(width 0.1)
		(layer "F.Cu")
		(net 290)
	)
	(arc
		(start 207.1 131.675)
		(mid 207.136612 131.586612)
		(end 207.225 131.55)
		(width 0.1)
		(layer "F.Cu")
		(net 290)
	)
	(arc
		(start 207.425 132.3)
		(mid 207.336612 132.263388)
		(end 207.3 132.175)
		(width 0.1)
		(layer "F.Cu")
		(net 290)
	)
	(arc
		(start 207.3 132.175)
		(mid 207.336612 132.086612)
		(end 207.425 132.05)
		(width 0.1)
		(layer "F.Cu")
		(net 290)
	)
	(arc
		(start 208 131.425)
		(mid 207.963388 131.336612)
		(end 207.875 131.3)
		(width 0.1)
		(layer "F.Cu")
		(net 290)
	)
	(arc
		(start 208 132.425)
		(mid 207.963388 132.336612)
		(end 207.875 132.3)
		(width 0.1)
		(layer "F.Cu")
		(net 290)
	)
	(arc
		(start 207.875 131.05)
		(mid 207.963388 131.013388)
		(end 208 130.925)
		(width 0.1)
		(layer "F.Cu")
		(net 290)
	)
	(arc
		(start 207.875 132.05)
		(mid 207.963388 132.013388)
		(end 208 131.925)
		(width 0.1)
		(layer "F.Cu")
		(net 290)
	)
	(arc
		(start 207.875 131.55)
		(mid 207.963388 131.513388)
		(end 208 131.425)
		(width 0.1)
		(layer "F.Cu")
		(net 290)
	)
	(arc
		(start 207.1 130.675)
		(mid 207.136612 130.586612)
		(end 207.225 130.55)
		(width 0.1)
		(layer "F.Cu")
		(net 290)
	)
	(arc
		(start 207.225 130.8)
		(mid 207.136612 130.763388)
		(end 207.1 130.675)
		(width 0.1)
		(layer "F.Cu")
		(net 290)
	)
	(arc
		(start 207.875 130.55)
		(mid 207.963388 130.513388)
		(end 208 130.425)
		(width 0.1)
		(layer "F.Cu")
		(net 290)
	)
	(via
		(at 204.999 144.151)
		(size 0.35)
		(drill 0.15)
		(layers "F.Cu" "B.Cu")
		(remove_unused_layers yes)
		(keep_end_layers yes)
		(zone_layer_connections)
		(net 291)
	)
	(via
		(at 194.9 134.7)
		(size 0.35)
		(drill 0.15)
		(layers "F.Cu" "B.Cu")
		(remove_unused_layers yes)
		(keep_end_layers yes)
		(zone_layer_connections)
		(net 291)
	)
	(segment
		(start 202.48 142.153711)
		(end 202.48 142.446802)
		(width 0.09)
		(layer "In7.Cu")
		(net 291)
	)
	(segment
		(start 200.29 142.3)
		(end 199.77 141.78)
		(width 0.09)
		(layer "In7.Cu")
		(net 291)
	)
	(segment
		(start 202.333199 142.593603)
		(end 202.276801 142.593603)
		(width 0.09)
		(layer "In7.Cu")
		(net 291)
	)
	(segment
		(start 196.86 140.12)
		(end 195.22 138.48)
		(width 0.09)
		(layer "In7.Cu")
		(net 291)
	)
	(segment
		(start 201.43 142.446301)
		(end 201.43 142.4463)
		(width 0.09)
		(layer "In7.Cu")
		(net 291)
	)
	(segment
		(start 200.29 142.3)
		(end 201.2837 142.3)
		(width 0.09)
		(layer "In7.Cu")
		(net 291)
	)
	(segment
		(start 199.77 141.78)
		(end 198.326451 141.78)
		(width 0.09)
		(layer "In7.Cu")
		(net 291)
	)
	(segment
		(start 202.13 142.446802)
		(end 202.13 142.153198)
		(width 0.09)
		(layer "In7.Cu")
		(net 291)
	)
	(segment
		(start 195.34 135.14)
		(end 194.9 134.7)
		(width 0.09)
		(layer "In7.Cu")
		(net 291)
	)
	(segment
		(start 195.22 138.48)
		(end 195.22 137.37)
		(width 0.09)
		(layer "In7.Cu")
		(net 291)
	)
	(segment
		(start 204.999 144.151)
		(end 203.148 142.3)
		(width 0.09)
		(layer "In7.Cu")
		(net 291)
	)
	(segment
		(start 201.78 142.153198)
		(end 201.78 142.446301)
		(width 0.09)
		(layer "In7.Cu")
		(net 291)
	)
	(segment
		(start 197.71 140.94)
		(end 197.39 140.62)
		(width 0.09)
		(layer "In7.Cu")
		(net 291)
	)
	(segment
		(start 197.166451 140.62)
		(end 196.86 140.313549)
		(width 0.09)
		(layer "In7.Cu")
		(net 291)
	)
	(segment
		(start 202.687424 142.007423)
		(end 202.626288 142.007423)
		(width 0.09)
		(layer "In7.Cu")
		(net 291)
	)
	(segment
		(start 198.326451 141.78)
		(end 197.71 141.163549)
		(width 0.09)
		(layer "In7.Cu")
		(net 291)
	)
	(segment
		(start 197.71 141.163549)
		(end 197.71 140.94)
		(width 0.09)
		(layer "In7.Cu")
		(net 291)
	)
	(segment
		(start 195.22 137.37)
		(end 195.34 137.25)
		(width 0.09)
		(layer "In7.Cu")
		(net 291)
	)
	(segment
		(start 201.983199 142.006397)
		(end 201.926801 142.006397)
		(width 0.09)
		(layer "In7.Cu")
		(net 291)
	)
	(segment
		(start 196.86 140.313549)
		(end 196.86 140.12)
		(width 0.09)
		(layer "In7.Cu")
		(net 291)
	)
	(segment
		(start 203.148 142.3)
		(end 202.98 142.3)
		(width 0.09)
		(layer "In7.Cu")
		(net 291)
	)
	(segment
		(start 195.34 137.25)
		(end 195.34 135.14)
		(width 0.09)
		(layer "In7.Cu")
		(net 291)
	)
	(segment
		(start 197.39 140.62)
		(end 197.166451 140.62)
		(width 0.09)
		(layer "In7.Cu")
		(net 291)
	)
	(segment
		(start 202.833712 142.153712)
		(end 202.833712 142.153711)
		(width 0.09)
		(layer "In7.Cu")
		(net 291)
	)
	(segment
		(start 201.6337 142.592601)
		(end 201.5763 142.592601)
		(width 0.09)
		(layer "In7.Cu")
		(net 291)
	)
	(arc
		(start 201.5763 142.592601)
		(mid 201.47285 142.549751)
		(end 201.43 142.446301)
		(width 0.09)
		(layer "In7.Cu")
		(net 291)
	)
	(arc
		(start 202.13 142.153198)
		(mid 202.087003 142.049394)
		(end 201.983199 142.006397)
		(width 0.09)
		(layer "In7.Cu")
		(net 291)
	)
	(arc
		(start 202.276801 142.593603)
		(mid 202.172997 142.550606)
		(end 202.13 142.446802)
		(width 0.09)
		(layer "In7.Cu")
		(net 291)
	)
	(arc
		(start 201.78 142.446301)
		(mid 201.73715 142.549751)
		(end 201.6337 142.592601)
		(width 0.09)
		(layer "In7.Cu")
		(net 291)
	)
	(arc
		(start 202.48 142.446802)
		(mid 202.437003 142.550606)
		(end 202.333199 142.593603)
		(width 0.09)
		(layer "In7.Cu")
		(net 291)
	)
	(arc
		(start 201.43 142.4463)
		(mid 201.38715 142.34285)
		(end 201.2837 142.3)
		(width 0.09)
		(layer "In7.Cu")
		(net 291)
	)
	(arc
		(start 202.833712 142.153711)
		(mid 202.790865 142.05027)
		(end 202.687424 142.007423)
		(width 0.09)
		(layer "In7.Cu")
		(net 291)
	)
	(arc
		(start 201.926801 142.006397)
		(mid 201.822997 142.049394)
		(end 201.78 142.153198)
		(width 0.09)
		(layer "In7.Cu")
		(net 291)
	)
	(arc
		(start 202.98 142.3)
		(mid 202.876559 142.257153)
		(end 202.833712 142.153712)
		(width 0.09)
		(layer "In7.Cu")
		(net 291)
	)
	(arc
		(start 202.626288 142.007423)
		(mid 202.522847 142.05027)
		(end 202.48 142.153711)
		(width 0.09)
		(layer "In7.Cu")
		(net 291)
	)
	(via
		(at 204.349 144.151)
		(size 0.35)
		(drill 0.15)
		(layers "F.Cu" "B.Cu")
		(remove_unused_layers yes)
		(keep_end_layers yes)
		(zone_layer_connections)
		(net 292)
	)
	(via
		(at 194.9 135.5)
		(size 0.35)
		(drill 0.15)
		(layers "F.Cu" "B.Cu")
		(remove_unused_layers yes)
		(keep_end_layers yes)
		(zone_layer_connections)
		(net 292)
	)
	(segment
		(start 204.349 141.499)
		(end 204.349 144.151)
		(width 0.09)
		(layer "In11.Cu")
		(net 292)
	)
	(segment
		(start 195.71 134.69)
		(end 198.34 134.69)
		(width 0.09)
		(layer "In11.Cu")
		(net 292)
	)
	(segment
		(start 201.761 136.621)
		(end 202.62 137.48)
		(width 0.09)
		(layer "In11.Cu")
		(net 292)
	)
	(segment
		(start 198.34 134.69)
		(end 200.271 136.621)
		(width 0.09)
		(layer "In11.Cu")
		(net 292)
	)
	(segment
		(start 203.89 138.32)
		(end 204.08 138.51)
		(width 0.09)
		(layer "In11.Cu")
		(net 292)
	)
	(segment
		(start 202.62 137.48)
		(end 203.13 137.48)
		(width 0.09)
		(layer "In11.Cu")
		(net 292)
	)
	(segment
		(start 204.08 138.51)
		(end 204.08 141.23)
		(width 0.09)
		(layer "In11.Cu")
		(net 292)
	)
	(segment
		(start 200.271 136.621)
		(end 201.761 136.621)
		(width 0.09)
		(layer "In11.Cu")
		(net 292)
	)
	(segment
		(start 203.3 137.65)
		(end 203.3 138.13)
		(width 0.09)
		(layer "In11.Cu")
		(net 292)
	)
	(segment
		(start 203.13 137.48)
		(end 203.3 137.65)
		(width 0.09)
		(layer "In11.Cu")
		(net 292)
	)
	(segment
		(start 194.9 135.5)
		(end 195.71 134.69)
		(width 0.09)
		(layer "In11.Cu")
		(net 292)
	)
	(segment
		(start 203.49 138.32)
		(end 203.89 138.32)
		(width 0.09)
		(layer "In11.Cu")
		(net 292)
	)
	(segment
		(start 204.08 141.23)
		(end 204.349 141.499)
		(width 0.09)
		(layer "In11.Cu")
		(net 292)
	)
	(segment
		(start 203.3 138.13)
		(end 203.49 138.32)
		(width 0.09)
		(layer "In11.Cu")
		(net 292)
	)
	(via
		(at 194.9 136.301)
		(size 0.35)
		(drill 0.15)
		(layers "F.Cu" "B.Cu")
		(remove_unused_layers yes)
		(keep_end_layers yes)
		(zone_layer_connections)
		(net 293)
	)
	(via
		(at 203.699 144.151)
		(size 0.35)
		(drill 0.15)
		(layers "F.Cu" "B.Cu")
		(remove_unused_layers yes)
		(keep_end_layers yes)
		(zone_layer_connections)
		(net 293)
	)
	(segment
		(start 201.62 140.167451)
		(end 201.62 140.3)
		(width 0.09)
		(layer "In11.Cu")
		(net 293)
	)
	(segment
		(start 202.85 142.7)
		(end 203.699 143.549)
		(width 0.09)
		(layer "In11.Cu")
		(net 293)
	)
	(segment
		(start 200.118199 138.771748)
		(end 200.446451 139.1)
		(width 0.09)
		(layer "In11.Cu")
		(net 293)
	)
	(segment
		(start 200.157194 138.48527)
		(end 200.1182 138.524261)
		(width 0.09)
		(layer "In11.Cu")
		(net 293)
	)
	(segment
		(start 199.870714 138.276776)
		(end 199.909705 138.237782)
		(width 0.09)
		(layer "In11.Cu")
		(net 293)
	)
	(segment
		(start 199.5 137.452549)
		(end 199.38 137.572549)
		(width 0.09)
		(layer "In11.Cu")
		(net 293)
	)
	(segment
		(start 199.870713 138.276774)
		(end 199.870714 138.276776)
		(width 0.09)
		(layer "In11.Cu")
		(net 293)
	)
	(segment
		(start 202.1 140.62)
		(end 202.42 140.94)
		(width 0.09)
		(layer "In11.Cu")
		(net 293)
	)
	(segment
		(start 196.03 136.55)
		(end 196.03 136.35)
		(width 0.09)
		(layer "In11.Cu")
		(net 293)
	)
	(segment
		(start 197.88 136.5)
		(end 197.88 136.55)
		(width 0.09)
		(layer "In11.Cu")
		(net 293)
	)
	(segment
		(start 200.157192 138.485269)
		(end 200.157194 138.48527)
		(width 0.09)
		(layer "In11.Cu")
		(net 293)
	)
	(segment
		(start 196.93 136.35)
		(end 196.93 136.55)
		(width 0.09)
		(layer "In11.Cu")
		(net 293)
	)
	(segment
		(start 199.38 138.033549)
		(end 199.623226 138.276775)
		(width 0.09)
		(layer "In11.Cu")
		(net 293)
	)
	(segment
		(start 199.5 137.2)
		(end 199.5 137.452549)
		(width 0.09)
		(layer "In11.Cu")
		(net 293)
	)
	(segment
		(start 196.63 136.55)
		(end 196.63 136.35)
		(width 0.09)
		(layer "In11.Cu")
		(net 293)
	)
	(segment
		(start 195.176 136.301)
		(end 195.575 136.7)
		(width 0.09)
		(layer "In11.Cu")
		(net 293)
	)
	(segment
		(start 201.172451 139.83)
		(end 201.282549 139.83)
		(width 0.09)
		(layer "In11.Cu")
		(net 293)
	)
	(segment
		(start 200.9 139.557549)
		(end 201.172451 139.83)
		(width 0.09)
		(layer "In11.Cu")
		(net 293)
	)
	(segment
		(start 198.18 136.55)
		(end 198.18 136.05)
		(width 0.09)
		(layer "In11.Cu")
		(net 293)
	)
	(segment
		(start 198.48 136.05)
		(end 198.48 136.55)
		(width 0.09)
		(layer "In11.Cu")
		(net 293)
	)
	(segment
		(start 194.9 136.301)
		(end 195.176 136.301)
		(width 0.09)
		(layer "In11.Cu")
		(net 293)
	)
	(segment
		(start 200.9 139.448451)
		(end 200.9 139.557549)
		(width 0.09)
		(layer "In11.Cu")
		(net 293)
	)
	(segment
		(start 196.33 136.35)
		(end 196.33 136.55)
		(width 0.09)
		(layer "In11.Cu")
		(net 293)
	)
	(segment
		(start 201.94 140.62)
		(end 202.1 140.62)
		(width 0.09)
		(layer "In11.Cu")
		(net 293)
	)
	(segment
		(start 197.08 136.7)
		(end 197.43 136.7)
		(width 0.09)
		(layer "In11.Cu")
		(net 293)
	)
	(segment
		(start 200.551549 139.1)
		(end 200.9 139.448451)
		(width 0.09)
		(layer "In11.Cu")
		(net 293)
	)
	(segment
		(start 201.282549 139.83)
		(end 201.62 140.167451)
		(width 0.09)
		(layer "In11.Cu")
		(net 293)
	)
	(segment
		(start 201.62 140.3)
		(end 201.94 140.62)
		(width 0.09)
		(layer "In11.Cu")
		(net 293)
	)
	(segment
		(start 199.38 137.572549)
		(end 199.38 138.033549)
		(width 0.09)
		(layer "In11.Cu")
		(net 293)
	)
	(segment
		(start 202.42 141.42)
		(end 202.85 141.85)
		(width 0.09)
		(layer "In11.Cu")
		(net 293)
	)
	(segment
		(start 198.63 136.7)
		(end 199 136.7)
		(width 0.09)
		(layer "In11.Cu")
		(net 293)
	)
	(segment
		(start 197.58 136.55)
		(end 197.58 136.5)
		(width 0.09)
		(layer "In11.Cu")
		(net 293)
	)
	(segment
		(start 203.699 143.549)
		(end 203.699 144.151)
		(width 0.09)
		(layer "In11.Cu")
		(net 293)
	)
	(segment
		(start 199 136.7)
		(end 199.5 137.2)
		(width 0.09)
		(layer "In11.Cu")
		(net 293)
	)
	(segment
		(start 202.85 141.85)
		(end 202.85 142.7)
		(width 0.09)
		(layer "In11.Cu")
		(net 293)
	)
	(segment
		(start 200.446451 139.1)
		(end 200.551549 139.1)
		(width 0.09)
		(layer "In11.Cu")
		(net 293)
	)
	(segment
		(start 200.157192 138.237781)
		(end 200.157193 138.237782)
		(width 0.09)
		(layer "In11.Cu")
		(net 293)
	)
	(segment
		(start 202.42 140.94)
		(end 202.42 141.42)
		(width 0.09)
		(layer "In11.Cu")
		(net 293)
	)
	(segment
		(start 195.575 136.7)
		(end 195.88 136.7)
		(width 0.09)
		(layer "In11.Cu")
		(net 293)
	)
	(arc
		(start 199.623226 138.276775)
		(mid 199.74697 138.328031)
		(end 199.870713 138.276774)
		(width 0.09)
		(layer "In11.Cu")
		(net 293)
	)
	(arc
		(start 195.88 136.7)
		(mid 195.986066 136.656066)
		(end 196.03 136.55)
		(width 0.09)
		(layer "In11.Cu")
		(net 293)
	)
	(arc
		(start 196.18 136.2)
		(mid 196.286066 136.243934)
		(end 196.33 136.35)
		(width 0.09)
		(layer "In11.Cu")
		(net 293)
	)
	(arc
		(start 196.63 136.35)
		(mid 196.673934 136.243934)
		(end 196.78 136.2)
		(width 0.09)
		(layer "In11.Cu")
		(net 293)
	)
	(arc
		(start 200.1182 138.524261)
		(mid 200.066943 138.648004)
		(end 200.118199 138.771748)
		(width 0.09)
		(layer "In11.Cu")
		(net 293)
	)
	(arc
		(start 196.33 136.55)
		(mid 196.373934 136.656066)
		(end 196.48 136.7)
		(width 0.09)
		(layer "In11.Cu")
		(net 293)
	)
	(arc
		(start 199.909705 138.237782)
		(mid 200.033448 138.186525)
		(end 200.157192 138.237781)
		(width 0.09)
		(layer "In11.Cu")
		(net 293)
	)
	(arc
		(start 200.157193 138.237782)
		(mid 200.208449 138.361526)
		(end 200.157192 138.485269)
		(width 0.09)
		(layer "In11.Cu")
		(net 293)
	)
	(arc
		(start 197.58 136.5)
		(mid 197.623934 136.393934)
		(end 197.73 136.35)
		(width 0.09)
		(layer "In11.Cu")
		(net 293)
	)
	(arc
		(start 198.18 136.05)
		(mid 198.223934 135.943934)
		(end 198.33 135.9)
		(width 0.09)
		(layer "In11.Cu")
		(net 293)
	)
	(arc
		(start 196.78 136.2)
		(mid 196.886066 136.243934)
		(end 196.93 136.35)
		(width 0.09)
		(layer "In11.Cu")
		(net 293)
	)
	(arc
		(start 197.88 136.55)
		(mid 197.923934 136.656066)
		(end 198.03 136.7)
		(width 0.09)
		(layer "In11.Cu")
		(net 293)
	)
	(arc
		(start 196.48 136.7)
		(mid 196.586066 136.656066)
		(end 196.63 136.55)
		(width 0.09)
		(layer "In11.Cu")
		(net 293)
	)
	(arc
		(start 198.03 136.7)
		(mid 198.136066 136.656066)
		(end 198.18 136.55)
		(width 0.09)
		(layer "In11.Cu")
		(net 293)
	)
	(arc
		(start 197.73 136.35)
		(mid 197.836066 136.393934)
		(end 197.88 136.5)
		(width 0.09)
		(layer "In11.Cu")
		(net 293)
	)
	(arc
		(start 196.03 136.35)
		(mid 196.073934 136.243934)
		(end 196.18 136.2)
		(width 0.09)
		(layer "In11.Cu")
		(net 293)
	)
	(arc
		(start 197.43 136.7)
		(mid 197.536066 136.656066)
		(end 197.58 136.55)
		(width 0.09)
		(layer "In11.Cu")
		(net 293)
	)
	(arc
		(start 198.33 135.9)
		(mid 198.436066 135.943934)
		(end 198.48 136.05)
		(width 0.09)
		(layer "In11.Cu")
		(net 293)
	)
	(arc
		(start 196.93 136.55)
		(mid 196.973934 136.656066)
		(end 197.08 136.7)
		(width 0.09)
		(layer "In11.Cu")
		(net 293)
	)
	(arc
		(start 198.48 136.55)
		(mid 198.523934 136.656066)
		(end 198.63 136.7)
		(width 0.09)
		(layer "In11.Cu")
		(net 293)
	)
	(via
		(at 194.099 136.301)
		(size 0.35)
		(drill 0.15)
		(layers "F.Cu" "B.Cu")
		(remove_unused_layers yes)
		(keep_end_layers yes)
		(zone_layer_connections)
		(net 294)
	)
	(via
		(at 201.1 144.15)
		(size 0.35)
		(drill 0.15)
		(layers "F.Cu" "B.Cu")
		(remove_unused_layers yes)
		(keep_end_layers yes)
		(zone_layer_connections)
		(net 294)
	)
	(segment
		(start 196.435775 137.704225)
		(end 196.435775 137.384225)
		(width 0.09)
		(layer "In9.Cu")
		(net 294)
	)
	(segment
		(start 200.64 142.64)
		(end 201.34 142.64)
		(width 0.09)
		(layer "In9.Cu")
		(net 294)
	)
	(segment
		(start 200.07 141.19)
		(end 200.07 141.019451)
		(width 0.09)
		(layer "In9.Cu")
		(net 294)
	)
	(segment
		(start 200.879644 142.295329)
		(end 200.879644 142.29533)
		(width 0.09)
		(layer "In9.Cu")
		(net 294)
	)
	(segment
		(start 196.200775 137.149225)
		(end 195.449225 137.149225)
		(width 0.09)
		(layer "In9.Cu")
		(net 294)
	)
	(segment
		(start 201.34 142.94)
		(end 200.64 142.94)
		(width 0.09)
		(layer "In9.Cu")
		(net 294)
	)
	(segment
		(start 201.49 143.76)
		(end 201.49 143.69)
		(width 0.09)
		(layer "In9.Cu")
		(net 294)
	)
	(segment
		(start 195 136.7)
		(end 194.498 136.7)
		(width 0.09)
		(layer "In9.Cu")
		(net 294)
	)
	(segment
		(start 200.07 141.019451)
		(end 199.780549 140.73)
		(width 0.09)
		(layer "In9.Cu")
		(net 294)
	)
	(segment
		(start 194.498 136.7)
		(end 194.099 136.301)
		(width 0.09)
		(layer "In9.Cu")
		(net 294)
	)
	(segment
		(start 197.51 138.38)
		(end 197.1 138.38)
		(width 0.09)
		(layer "In9.Cu")
		(net 294)
	)
	(segment
		(start 200.915 142.012487)
		(end 200.914999 142.012487)
		(width 0.09)
		(layer "In9.Cu")
		(net 294)
	)
	(segment
		(start 199.780549 140.73)
		(end 199.608225 140.73)
		(width 0.09)
		(layer "In9.Cu")
		(net 294)
	)
	(segment
		(start 200.317486 141.684973)
		(end 200.282131 141.720329)
		(width 0.09)
		(layer "In9.Cu")
		(net 294)
	)
	(segment
		(start 200.879644 142.047842)
		(end 200.915 142.012487)
		(width 0.09)
		(layer "In9.Cu")
		(net 294)
	)
	(segment
		(start 197.71 138.58)
		(end 197.51 138.38)
		(width 0.09)
		(layer "In9.Cu")
		(net 294)
	)
	(segment
		(start 198.53 139.4)
		(end 198.23 139.1)
		(width 0.09)
		(layer "In9.Cu")
		(net 294)
	)
	(segment
		(start 200.64 143.24)
		(end 201.34 143.24)
		(width 0.09)
		(layer "In9.Cu")
		(net 294)
	)
	(segment
		(start 197.71 138.88)
		(end 197.71 138.58)
		(width 0.09)
		(layer "In9.Cu")
		(net 294)
	)
	(segment
		(start 201.49 142.49)
		(end 201.49 142.34)
		(width 0.09)
		(layer "In9.Cu")
		(net 294)
	)
	(segment
		(start 200.915 141.765)
		(end 200.875 141.725)
		(width 0.09)
		(layer "In9.Cu")
		(net 294)
	)
	(segment
		(start 196.16 137.98)
		(end 196.435775 137.704225)
		(width 0.09)
		(layer "In9.Cu")
		(net 294)
	)
	(segment
		(start 201.127131 142.295329)
		(end 201.127131 142.295328)
		(width 0.09)
		(layer "In9.Cu")
		(net 294)
	)
	(segment
		(start 200.875 141.725)
		(end 200.605 141.725)
		(width 0.09)
		(layer "In9.Cu")
		(net 294)
	)
	(segment
		(start 195.449225 137.149225)
		(end 195 136.7)
		(width 0.09)
		(layer "In9.Cu")
		(net 294)
	)
	(segment
		(start 196.435775 137.384225)
		(end 196.200775 137.149225)
		(width 0.09)
		(layer "In9.Cu")
		(net 294)
	)
	(segment
		(start 200.034644 141.720329)
		(end 200.034644 141.72033)
		(width 0.09)
		(layer "In9.Cu")
		(net 294)
	)
	(segment
		(start 199.608225 140.73)
		(end 199.3 140.421775)
		(width 0.09)
		(layer "In9.Cu")
		(net 294)
	)
	(segment
		(start 201.34 143.54)
		(end 200.64 143.54)
		(width 0.09)
		(layer "In9.Cu")
		(net 294)
	)
	(segment
		(start 200.07 141.437487)
		(end 200.069999 141.437487)
		(width 0.09)
		(layer "In9.Cu")
		(net 294)
	)
	(segment
		(start 197.1 138.38)
		(end 196.82 138.66)
		(width 0.09)
		(layer "In9.Cu")
		(net 294)
	)
	(segment
		(start 196.82 138.66)
		(end 196.47 138.66)
		(width 0.09)
		(layer "In9.Cu")
		(net 294)
	)
	(segment
		(start 200.034644 141.472842)
		(end 200.07 141.437487)
		(width 0.09)
		(layer "In9.Cu")
		(net 294)
	)
	(segment
		(start 196.16 138.35)
		(end 196.16 137.98)
		(width 0.09)
		(layer "In9.Cu")
		(net 294)
	)
	(segment
		(start 200.282131 141.720329)
		(end 200.282131 141.720328)
		(width 0.09)
		(layer "In9.Cu")
		(net 294)
	)
	(segment
		(start 199.3 140.13)
		(end 199.07 139.9)
		(width 0.09)
		(layer "In9.Cu")
		(net 294)
	)
	(segment
		(start 198.53 139.65)
		(end 198.53 139.4)
		(width 0.09)
		(layer "In9.Cu")
		(net 294)
	)
	(segment
		(start 200.605 141.725)
		(end 200.564974 141.684973)
		(width 0.09)
		(layer "In9.Cu")
		(net 294)
	)
	(segment
		(start 199.07 139.9)
		(end 198.78 139.9)
		(width 0.09)
		(layer "In9.Cu")
		(net 294)
	)
	(segment
		(start 199.3 140.421775)
		(end 199.3 140.13)
		(width 0.09)
		(layer "In9.Cu")
		(net 294)
	)
	(segment
		(start 197.93 139.1)
		(end 197.71 138.88)
		(width 0.09)
		(layer "In9.Cu")
		(net 294)
	)
	(segment
		(start 196.47 138.66)
		(end 196.16 138.35)
		(width 0.09)
		(layer "In9.Cu")
		(net 294)
	)
	(segment
		(start 198.78 139.9)
		(end 198.53 139.65)
		(width 0.09)
		(layer "In9.Cu")
		(net 294)
	)
	(segment
		(start 201.1 144.15)
		(end 201.49 143.76)
		(width 0.09)
		(layer "In9.Cu")
		(net 294)
	)
	(segment
		(start 201.49 142.34)
		(end 201.409974 142.259973)
		(width 0.09)
		(layer "In9.Cu")
		(net 294)
	)
	(segment
		(start 201.162486 142.259973)
		(end 201.127131 142.295329)
		(width 0.09)
		(layer "In9.Cu")
		(net 294)
	)
	(segment
		(start 198.23 139.1)
		(end 197.93 139.1)
		(width 0.09)
		(layer "In9.Cu")
		(net 294)
	)
	(arc
		(start 200.914999 142.012487)
		(mid 200.966256 141.888744)
		(end 200.915 141.765)
		(width 0.09)
		(layer "In9.Cu")
		(net 294)
	)
	(arc
		(start 201.34 143.24)
		(mid 201.446066 143.196066)
		(end 201.49 143.09)
		(width 0.09)
		(layer "In9.Cu")
		(net 294)
	)
	(arc
		(start 201.127131 142.295328)
		(mid 201.003388 142.346585)
		(end 200.879644 142.295329)
		(width 0.09)
		(layer "In9.Cu")
		(net 294)
	)
	(arc
		(start 200.034644 141.72033)
		(mid 199.983388 141.596586)
		(end 200.034644 141.472842)
		(width 0.09)
		(layer "In9.Cu")
		(net 294)
	)
	(arc
		(start 201.49 143.69)
		(mid 201.446066 143.583934)
		(end 201.34 143.54)
		(width 0.09)
		(layer "In9.Cu")
		(net 294)
	)
	(arc
		(start 200.49 142.79)
		(mid 200.533934 142.683934)
		(end 200.64 142.64)
		(width 0.09)
		(layer "In9.Cu")
		(net 294)
	)
	(arc
		(start 200.64 143.54)
		(mid 200.533934 143.496066)
		(end 200.49 143.39)
		(width 0.09)
		(layer "In9.Cu")
		(net 294)
	)
	(arc
		(start 201.49 143.09)
		(mid 201.446066 142.983934)
		(end 201.34 142.94)
		(width 0.09)
		(layer "In9.Cu")
		(net 294)
	)
	(arc
		(start 200.64 142.94)
		(mid 200.533934 142.896066)
		(end 200.49 142.79)
		(width 0.09)
		(layer "In9.Cu")
		(net 294)
	)
	(arc
		(start 200.879644 142.29533)
		(mid 200.828388 142.171586)
		(end 200.879644 142.047842)
		(width 0.09)
		(layer "In9.Cu")
		(net 294)
	)
	(arc
		(start 200.069999 141.437487)
		(mid 200.121256 141.313744)
		(end 200.07 141.19)
		(width 0.09)
		(layer "In9.Cu")
		(net 294)
	)
	(arc
		(start 200.282131 141.720328)
		(mid 200.158388 141.771585)
		(end 200.034644 141.720329)
		(width 0.09)
		(layer "In9.Cu")
		(net 294)
	)
	(arc
		(start 200.49 143.39)
		(mid 200.533934 143.283934)
		(end 200.64 143.24)
		(width 0.09)
		(layer "In9.Cu")
		(net 294)
	)
	(arc
		(start 201.34 142.64)
		(mid 201.446066 142.596066)
		(end 201.49 142.49)
		(width 0.09)
		(layer "In9.Cu")
		(net 294)
	)
	(arc
		(start 201.409974 142.259973)
		(mid 201.28623 142.208717)
		(end 201.162486 142.259973)
		(width 0.09)
		(layer "In9.Cu")
		(net 294)
	)
	(arc
		(start 200.564974 141.684973)
		(mid 200.44123 141.633717)
		(end 200.317486 141.684973)
		(width 0.09)
		(layer "In9.Cu")
		(net 294)
	)
	(segment
		(start 206.945 126.645)
		(end 210.535 126.645)
		(width 0.1)
		(layer "F.Cu")
		(net 295)
	)
	(segment
		(start 210.535 126.645)
		(end 211.09 127.2)
		(width 0.1)
		(layer "F.Cu")
		(net 295)
	)
	(segment
		(start 220.1 127.2)
		(end 211.09 127.2)
		(width 0.1)
		(layer "F.Cu")
		(net 295)
	)
	(segment
		(start 203.299 126.3)
		(end 202.9 125.901)
		(width 0.1)
		(layer "F.Cu")
		(net 295)
	)
	(segment
		(start 221.025 126.125)
		(end 221.025 126.275)
		(width 0.1)
		(layer "F.Cu")
		(net 295)
	)
	(segment
		(start 206.945 126.645)
		(end 206.6 126.3)
		(width 0.1)
		(layer "F.Cu")
		(net 295)
	)
	(segment
		(start 206.6 126.3)
		(end 203.299 126.3)
		(width 0.1)
		(layer "F.Cu")
		(net 295)
	)
	(segment
		(start 221.025 126.275)
		(end 220.1 127.2)
		(width 0.1)
		(layer "F.Cu")
		(net 295)
	)
	(via
		(at 222.36 151.13)
		(size 0.35)
		(drill 0.15)
		(layers "F.Cu" "B.Cu")
		(remove_unused_layers yes)
		(keep_end_layers yes)
		(zone_layer_connections)
		(net 295)
	)
	(via
		(at 221.025 126.125)
		(size 0.35)
		(drill 0.15)
		(layers "F.Cu" "B.Cu")
		(remove_unused_layers yes)
		(keep_end_layers yes)
		(zone_layer_connections)
		(net 295)
	)
	(segment
		(start 224.925 149.45)
		(end 226.075 148.3)
		(width 0.1)
		(layer "B.Cu")
		(net 295)
	)
	(segment
		(start 223.43 149.45)
		(end 224.925 149.45)
		(width 0.1)
		(layer "B.Cu")
		(net 295)
	)
	(segment
		(start 222.36 150.52)
		(end 223.43 149.45)
		(width 0.1)
		(layer "B.Cu")
		(net 295)
	)
	(segment
		(start 222.36 151.13)
		(end 222.36 150.52)
		(width 0.1)
		(layer "B.Cu")
		(net 295)
	)
	(segment
		(start 222.36 149.68)
		(end 224.05 147.99)
		(width 0.1)
		(layer "In9.Cu")
		(net 295)
	)
	(segment
		(start 223.7 143.1)
		(end 223.7 140.85)
		(width 0.1)
		(layer "In9.Cu")
		(net 295)
	)
	(segment
		(start 224.05 147.99)
		(end 224.05 145.2)
		(width 0.1)
		(layer "In9.Cu")
		(net 295)
	)
	(segment
		(start 223.7 140.85)
		(end 221.025 138.175)
		(width 0.1)
		(layer "In9.Cu")
		(net 295)
	)
	(segment
		(start 223.4 143.4)
		(end 223.7 143.1)
		(width 0.1)
		(layer "In9.Cu")
		(net 295)
	)
	(segment
		(start 223.4 144.55)
		(end 223.4 143.4)
		(width 0.1)
		(layer "In9.Cu")
		(net 295)
	)
	(segment
		(start 221.025 138.175)
		(end 221.025 126.125)
		(width 0.1)
		(layer "In9.Cu")
		(net 295)
	)
	(segment
		(start 222.36 151.13)
		(end 222.36 149.68)
		(width 0.1)
		(layer "In9.Cu")
		(net 295)
	)
	(segment
		(start 224.05 145.2)
		(end 223.4 144.55)
		(width 0.1)
		(layer "In9.Cu")
		(net 295)
	)
	(segment
		(start 219.1 134.42)
		(end 219.455 134.775)
		(width 0.256)
		(layer "B.Cu")
		(net 296)
	)
	(segment
		(start 219.1 132.25)
		(end 219.1 133.729)
		(width 0.256)
		(layer "B.Cu")
		(net 296)
	)
	(segment
		(start 219.1 133.729)
		(end 219.1 134.42)
		(width 0.256)
		(layer "B.Cu")
		(net 296)
	)
	(segment
		(start 219.455 134.775)
		(end 219.455 135.775)
		(width 0.256)
		(layer "B.Cu")
		(net 296)
	)
	(segment
		(start 227.2 148.45)
		(end 225.05 148.45)
		(width 0.1)
		(layer "F.Cu")
		(net 297)
	)
	(segment
		(start 224.8015 148.2015)
		(end 224.8015 147.817)
		(width 0.1)
		(layer "F.Cu")
		(net 297)
	)
	(segment
		(start 225.05 148.45)
		(end 224.8015 148.2015)
		(width 0.1)
		(layer "F.Cu")
		(net 297)
	)
	(via
		(at 194.099 137.101)
		(size 0.35)
		(drill 0.15)
		(layers "F.Cu" "B.Cu")
		(remove_unused_layers yes)
		(keep_end_layers yes)
		(zone_layer_connections)
		(net 298)
	)
	(via
		(at 204.349 144.801)
		(size 0.35)
		(drill 0.15)
		(layers "F.Cu" "B.Cu")
		(remove_unused_layers yes)
		(keep_end_layers yes)
		(zone_layer_connections)
		(net 298)
	)
	(segment
		(start 203.300775 142.431775)
		(end 204.019 143.15)
		(width 0.09)
		(layer "In11.Cu")
		(net 298)
	)
	(segment
		(start 194.75 135.9)
		(end 194.5 136.15)
		(width 0.09)
		(layer "In11.Cu")
		(net 298)
	)
	(segment
		(start 204.349 144.801)
		(end 204.019 144.471)
		(width 0.09)
		(layer "In11.Cu")
		(net 298)
	)
	(segment
		(start 197.1 135.9)
		(end 194.75 135.9)
		(width 0.09)
		(layer "In11.Cu")
		(net 298)
	)
	(segment
		(start 194.320001 136.879999)
		(end 194.099 137.101)
		(width 0.09)
		(layer "In11.Cu")
		(net 298)
	)
	(segment
		(start 201.625 137.744977)
		(end 200.757524 136.877501)
		(width 0.09)
		(layer "In11.Cu")
		(net 298)
	)
	(segment
		(start 194.320001 136.875441)
		(end 194.320001 136.879999)
		(width 0.09)
		(layer "In11.Cu")
		(net 298)
	)
	(segment
		(start 194.5 136.15)
		(end 194.5 136.695442)
		(width 0.09)
		(layer "In11.Cu")
		(net 298)
	)
	(segment
		(start 197.436001 135.563999)
		(end 197.1 135.9)
		(width 0.09)
		(layer "In11.Cu")
		(net 298)
	)
	(segment
		(start 200.127501 136.877501)
		(end 198.813999 135.563999)
		(width 0.09)
		(layer "In11.Cu")
		(net 298)
	)
	(segment
		(start 203.300775 141.049225)
		(end 203.300775 142.431775)
		(width 0.09)
		(layer "In11.Cu")
		(net 298)
	)
	(segment
		(start 202.75 140.75)
		(end 202.42 140.42)
		(width 0.09)
		(layer "In11.Cu")
		(net 298)
	)
	(segment
		(start 200.757524 136.877501)
		(end 200.127501 136.877501)
		(width 0.09)
		(layer "In11.Cu")
		(net 298)
	)
	(segment
		(start 203.300775 141.049225)
		(end 203.001549 140.75)
		(width 0.09)
		(layer "In11.Cu")
		(net 298)
	)
	(segment
		(start 201.625 139.477549)
		(end 201.625 137.744977)
		(width 0.09)
		(layer "In11.Cu")
		(net 298)
	)
	(segment
		(start 202.42 140.42)
		(end 202.42 140.14)
		(width 0.09)
		(layer "In11.Cu")
		(net 298)
	)
	(segment
		(start 202.1 139.82)
		(end 201.967451 139.82)
		(width 0.09)
		(layer "In11.Cu")
		(net 298)
	)
	(segment
		(start 203.001549 140.75)
		(end 202.75 140.75)
		(width 0.09)
		(layer "In11.Cu")
		(net 298)
	)
	(segment
		(start 194.5 136.695442)
		(end 194.320001 136.875441)
		(width 0.09)
		(layer "In11.Cu")
		(net 298)
	)
	(segment
		(start 204.019 144.471)
		(end 204.019 143.15)
		(width 0.09)
		(layer "In11.Cu")
		(net 298)
	)
	(segment
		(start 201.967451 139.82)
		(end 201.625 139.477549)
		(width 0.09)
		(layer "In11.Cu")
		(net 298)
	)
	(segment
		(start 198.813999 135.563999)
		(end 197.436001 135.563999)
		(width 0.09)
		(layer "In11.Cu")
		(net 298)
	)
	(segment
		(start 202.42 140.14)
		(end 202.1 139.82)
		(width 0.09)
		(layer "In11.Cu")
		(net 298)
	)
	(via
		(at 193.299 137.101)
		(size 0.35)
		(drill 0.15)
		(layers "F.Cu" "B.Cu")
		(remove_unused_layers yes)
		(keep_end_layers yes)
		(zone_layer_connections)
		(net 299)
	)
	(via
		(at 204.999 144.801)
		(size 0.35)
		(drill 0.15)
		(layers "F.Cu" "B.Cu")
		(remove_unused_layers yes)
		(keep_end_layers yes)
		(zone_layer_connections)
		(net 299)
	)
	(segment
		(start 199.24 144.05)
		(end 199.79 144.05)
		(width 0.09)
		(layer "In7.Cu")
		(net 299)
	)
	(segment
		(start 196.94 141.088451)
		(end 196.94 141.194549)
		(width 0.09)
		(layer "In7.Cu")
		(net 299)
	)
	(segment
		(start 194.090549 137.44)
		(end 194.419 137.768451)
		(width 0.09)
		(layer "In7.Cu")
		(net 299)
	)
	(segment
		(start 193.299 137.101)
		(end 193.638 137.44)
		(width 0.09)
		(layer "In7.Cu")
		(net 299)
	)
	(segment
		(start 202.310712 143.38)
		(end 203.380549 143.38)
		(width 0.09)
		(layer "In7.Cu")
		(net 299)
	)
	(segment
		(start 197.68 141.7)
		(end 198.28 142.3)
		(width 0.09)
		(layer "In7.Cu")
		(net 299)
	)
	(segment
		(start 198.28 142.3)
		(end 198.28 143.09)
		(width 0.09)
		(layer "In7.Cu")
		(net 299)
	)
	(segment
		(start 201.13 143.249274)
		(end 201.13 143.513361)
		(width 0.09)
		(layer "In7.Cu")
		(net 299)
	)
	(segment
		(start 194.419 139.471549)
		(end 194.767451 139.82)
		(width 0.09)
		(layer "In7.Cu")
		(net 299)
	)
	(segment
		(start 196.397451 140.65)
		(end 196.501549 140.65)
		(width 0.09)
		(layer "In7.Cu")
		(net 299)
	)
	(segment
		(start 201.613361 143.113278)
		(end 201.696639 143.113278)
		(width 0.09)
		(layer "In7.Cu")
		(net 299)
	)
	(segment
		(start 196.94 141.194549)
		(end 197.445451 141.7)
		(width 0.09)
		(layer "In7.Cu")
		(net 299)
	)
	(segment
		(start 200.89145 143.118549)
		(end 200.999275 143.118549)
		(width 0.09)
		(layer "In7.Cu")
		(net 299)
	)
	(segment
		(start 200.46 143.38)
		(end 200.63 143.38)
		(width 0.09)
		(layer "In7.Cu")
		(net 299)
	)
	(segment
		(start 201.48 143.513361)
		(end 201.48 143.246639)
		(width 0.09)
		(layer "In7.Cu")
		(net 299)
	)
	(segment
		(start 196.16 140.412549)
		(end 196.397451 140.65)
		(width 0.09)
		(layer "In7.Cu")
		(net 299)
	)
	(segment
		(start 193.638 137.44)
		(end 194.090549 137.44)
		(width 0.09)
		(layer "In7.Cu")
		(net 299)
	)
	(segment
		(start 194.419 137.768451)
		(end 194.419 139.471549)
		(width 0.09)
		(layer "In7.Cu")
		(net 299)
	)
	(segment
		(start 204.216451 144.471)
		(end 204.669 144.471)
		(width 0.09)
		(layer "In7.Cu")
		(net 299)
	)
	(segment
		(start 201.83 143.246639)
		(end 201.83 143.510712)
		(width 0.09)
		(layer "In7.Cu")
		(net 299)
	)
	(segment
		(start 201.263361 143.646722)
		(end 201.346639 143.646722)
		(width 0.09)
		(layer "In7.Cu")
		(net 299)
	)
	(segment
		(start 198.28 143.09)
		(end 199.24 144.05)
		(width 0.09)
		(layer "In7.Cu")
		(net 299)
	)
	(segment
		(start 199.79 144.05)
		(end 200.46 143.38)
		(width 0.09)
		(layer "In7.Cu")
		(net 299)
	)
	(segment
		(start 195.672549 139.82)
		(end 196.16 140.307451)
		(width 0.09)
		(layer "In7.Cu")
		(net 299)
	)
	(segment
		(start 197.445451 141.7)
		(end 197.68 141.7)
		(width 0.09)
		(layer "In7.Cu")
		(net 299)
	)
	(segment
		(start 204.029 144.283549)
		(end 204.216451 144.471)
		(width 0.09)
		(layer "In7.Cu")
		(net 299)
	)
	(segment
		(start 194.767451 139.82)
		(end 195.672549 139.82)
		(width 0.09)
		(layer "In7.Cu")
		(net 299)
	)
	(segment
		(start 196.501549 140.65)
		(end 196.94 141.088451)
		(width 0.09)
		(layer "In7.Cu")
		(net 299)
	)
	(segment
		(start 204.029 144.028451)
		(end 204.029 144.283549)
		(width 0.09)
		(layer "In7.Cu")
		(net 299)
	)
	(segment
		(start 201.960712 143.641424)
		(end 202.049288 143.641424)
		(width 0.09)
		(layer "In7.Cu")
		(net 299)
	)
	(segment
		(start 200.760725 143.249275)
		(end 200.760725 143.249274)
		(width 0.09)
		(layer "In7.Cu")
		(net 299)
	)
	(segment
		(start 203.380549 143.38)
		(end 204.029 144.028451)
		(width 0.09)
		(layer "In7.Cu")
		(net 299)
	)
	(segment
		(start 204.669 144.471)
		(end 204.999 144.801)
		(width 0.09)
		(layer "In7.Cu")
		(net 299)
	)
	(segment
		(start 196.16 140.307451)
		(end 196.16 140.412549)
		(width 0.09)
		(layer "In7.Cu")
		(net 299)
	)
	(arc
		(start 200.760725 143.249274)
		(mid 200.799013 143.156837)
		(end 200.89145 143.118549)
		(width 0.09)
		(layer "In7.Cu")
		(net 299)
	)
	(arc
		(start 201.13 143.513361)
		(mid 201.169061 143.607661)
		(end 201.263361 143.646722)
		(width 0.09)
		(layer "In7.Cu")
		(net 299)
	)
	(arc
		(start 201.346639 143.646722)
		(mid 201.440939 143.607661)
		(end 201.48 143.513361)
		(width 0.09)
		(layer "In7.Cu")
		(net 299)
	)
	(arc
		(start 202.049288 143.641424)
		(mid 202.141715 143.603139)
		(end 202.18 143.510712)
		(width 0.09)
		(layer "In7.Cu")
		(net 299)
	)
	(arc
		(start 201.696639 143.113278)
		(mid 201.790939 143.152339)
		(end 201.83 143.246639)
		(width 0.09)
		(layer "In7.Cu")
		(net 299)
	)
	(arc
		(start 202.18 143.510712)
		(mid 202.218285 143.418285)
		(end 202.310712 143.38)
		(width 0.09)
		(layer "In7.Cu")
		(net 299)
	)
	(arc
		(start 200.999275 143.118549)
		(mid 201.091712 143.156837)
		(end 201.13 143.249274)
		(width 0.09)
		(layer "In7.Cu")
		(net 299)
	)
	(arc
		(start 200.63 143.38)
		(mid 200.722437 143.341712)
		(end 200.760725 143.249275)
		(width 0.09)
		(layer "In7.Cu")
		(net 299)
	)
	(arc
		(start 201.83 143.510712)
		(mid 201.868285 143.603139)
		(end 201.960712 143.641424)
		(width 0.09)
		(layer "In7.Cu")
		(net 299)
	)
	(arc
		(start 201.48 143.246639)
		(mid 201.519061 143.152339)
		(end 201.613361 143.113278)
		(width 0.09)
		(layer "In7.Cu")
		(net 299)
	)
	(via
		(at 203.699 144.801)
		(size 0.35)
		(drill 0.15)
		(layers "F.Cu" "B.Cu")
		(remove_unused_layers yes)
		(keep_end_layers yes)
		(zone_layer_connections)
		(net 300)
	)
	(via
		(at 193.299 137.901)
		(size 0.35)
		(drill 0.15)
		(layers "F.Cu" "B.Cu")
		(remove_unused_layers yes)
		(keep_end_layers yes)
		(zone_layer_connections)
		(net 300)
	)
	(segment
		(start 203.379 144.481)
		(end 203.379 143.879)
		(width 0.09)
		(layer "In11.Cu")
		(net 300)
	)
	(segment
		(start 200.819 140.167451)
		(end 200.501549 139.85)
		(width 0.09)
		(layer "In11.Cu")
		(net 300)
	)
	(segment
		(start 200.819 140.3)
		(end 200.819 140.167451)
		(width 0.09)
		(layer "In11.Cu")
		(net 300)
	)
	(segment
		(start 195.47 137.35103)
		(end 195.47 137.15)
		(width 0.09)
		(layer "In11.Cu")
		(net 300)
	)
	(segment
		(start 198.0245 137.372951)
		(end 197.651549 137)
		(width 0.09)
		(layer "In11.Cu")
		(net 300)
	)
	(segment
		(start 202.2 141.8)
		(end 201.62 141.22)
		(width 0.09)
		(layer "In11.Cu")
		(net 300)
	)
	(segment
		(start 195.77 137.15)
		(end 195.77 137.35103)
		(width 0.09)
		(layer "In11.Cu")
		(net 300)
	)
	(segment
		(start 200.501549 139.85)
		(end 200.35 139.85)
		(width 0.09)
		(layer "In11.Cu")
		(net 300)
	)
	(segment
		(start 201.62 141.22)
		(end 201.62 140.968451)
		(width 0.09)
		(layer "In11.Cu")
		(net 300)
	)
	(segment
		(start 194.79 136.71)
		(end 194.5 137)
		(width 0.09)
		(layer "In11.Cu")
		(net 300)
	)
	(segment
		(start 198.0245 137.638049)
		(end 198.0245 137.372951)
		(width 0.09)
		(layer "In11.Cu")
		(net 300)
	)
	(segment
		(start 199 138.25)
		(end 198.636451 138.25)
		(width 0.09)
		(layer "In11.Cu")
		(net 300)
	)
	(segment
		(start 195.01 136.71)
		(end 194.79 136.71)
		(width 0.09)
		(layer "In11.Cu")
		(net 300)
	)
	(segment
		(start 196.83 137)
		(end 196.73 137)
		(width 0.09)
		(layer "In11.Cu")
		(net 300)
	)
	(segment
		(start 199.219 138.719)
		(end 199.219 138.469)
		(width 0.09)
		(layer "In11.Cu")
		(net 300)
	)
	(segment
		(start 199.219 138.469)
		(end 199 138.25)
		(width 0.09)
		(layer "In11.Cu")
		(net 300)
	)
	(segment
		(start 197.18 137.25)
		(end 197.08 137.25)
		(width 0.09)
		(layer "In11.Cu")
		(net 300)
	)
	(segment
		(start 194.35 137.5)
		(end 193.7 137.5)
		(width 0.09)
		(layer "In11.Cu")
		(net 300)
	)
	(segment
		(start 194.5 137)
		(end 194.5 137.35)
		(width 0.09)
		(layer "In11.Cu")
		(net 300)
	)
	(segment
		(start 203.379 143.879)
		(end 202.2 142.7)
		(width 0.09)
		(layer "In11.Cu")
		(net 300)
	)
	(segment
		(start 198.636451 138.25)
		(end 198.0245 137.638049)
		(width 0.09)
		(layer "In11.Cu")
		(net 300)
	)
	(segment
		(start 197.651549 137)
		(end 197.43 137)
		(width 0.09)
		(layer "In11.Cu")
		(net 300)
	)
	(segment
		(start 195.3 137)
		(end 195.01 136.71)
		(width 0.09)
		(layer "In11.Cu")
		(net 300)
	)
	(segment
		(start 196.48 137.25)
		(end 196.38 137.25)
		(width 0.09)
		(layer "In11.Cu")
		(net 300)
	)
	(segment
		(start 201.62 140.968451)
		(end 201.271549 140.62)
		(width 0.09)
		(layer "In11.Cu")
		(net 300)
	)
	(segment
		(start 201.271549 140.62)
		(end 201.139 140.62)
		(width 0.09)
		(layer "In11.Cu")
		(net 300)
	)
	(segment
		(start 202.2 142.7)
		(end 202.2 141.8)
		(width 0.09)
		(layer "In11.Cu")
		(net 300)
	)
	(segment
		(start 194.5 137.35)
		(end 194.35 137.5)
		(width 0.09)
		(layer "In11.Cu")
		(net 300)
	)
	(segment
		(start 200.35 139.85)
		(end 199.219 138.719)
		(width 0.09)
		(layer "In11.Cu")
		(net 300)
	)
	(segment
		(start 203.699 144.801)
		(end 203.379 144.481)
		(width 0.09)
		(layer "In11.Cu")
		(net 300)
	)
	(segment
		(start 196.13 137)
		(end 195.92 137)
		(width 0.09)
		(layer "In11.Cu")
		(net 300)
	)
	(segment
		(start 201.139 140.62)
		(end 200.819 140.3)
		(width 0.09)
		(layer "In11.Cu")
		(net 300)
	)
	(segment
		(start 195.32 137)
		(end 195.3 137)
		(width 0.09)
		(layer "In11.Cu")
		(net 300)
	)
	(segment
		(start 193.7 137.5)
		(end 193.299 137.901)
		(width 0.09)
		(layer "In11.Cu")
		(net 300)
	)
	(arc
		(start 196.605 137.125)
		(mid 196.568388 137.213388)
		(end 196.48 137.25)
		(width 0.09)
		(layer "In11.Cu")
		(net 300)
	)
	(arc
		(start 195.77 137.35103)
		(mid 195.726066 137.457096)
		(end 195.62 137.50103)
		(width 0.09)
		(layer "In11.Cu")
		(net 300)
	)
	(arc
		(start 196.38 137.25)
		(mid 196.291612 137.213388)
		(end 196.255 137.125)
		(width 0.09)
		(layer "In11.Cu")
		(net 300)
	)
	(arc
		(start 195.62 137.50103)
		(mid 195.513934 137.457096)
		(end 195.47 137.35103)
		(width 0.09)
		(layer "In11.Cu")
		(net 300)
	)
	(arc
		(start 197.305 137.125)
		(mid 197.268388 137.213388)
		(end 197.18 137.25)
		(width 0.09)
		(layer "In11.Cu")
		(net 300)
	)
	(arc
		(start 197.08 137.25)
		(mid 196.991612 137.213388)
		(end 196.955 137.125)
		(width 0.09)
		(layer "In11.Cu")
		(net 300)
	)
	(arc
		(start 196.955 137.125)
		(mid 196.918388 137.036612)
		(end 196.83 137)
		(width 0.09)
		(layer "In11.Cu")
		(net 300)
	)
	(arc
		(start 196.255 137.125)
		(mid 196.218388 137.036612)
		(end 196.13 137)
		(width 0.09)
		(layer "In11.Cu")
		(net 300)
	)
	(arc
		(start 197.43 137)
		(mid 197.341612 137.036612)
		(end 197.305 137.125)
		(width 0.09)
		(layer "In11.Cu")
		(net 300)
	)
	(arc
		(start 195.47 137.15)
		(mid 195.426066 137.043934)
		(end 195.32 137)
		(width 0.09)
		(layer "In11.Cu")
		(net 300)
	)
	(arc
		(start 196.73 137)
		(mid 196.641612 137.036612)
		(end 196.605 137.125)
		(width 0.09)
		(layer "In11.Cu")
		(net 300)
	)
	(arc
		(start 195.92 137)
		(mid 195.813934 137.043934)
		(end 195.77 137.15)
		(width 0.09)
		(layer "In11.Cu")
		(net 300)
	)
	(segment
		(start 211.295 121.74)
		(end 210.905 121.35)
		(width 0.1)
		(layer "F.Cu")
		(net 301)
	)
	(segment
		(start 211.71 121.479908)
		(end 211.71 121.655)
		(width 0.1)
		(layer "F.Cu")
		(net 301)
	)
	(segment
		(start 211.621486 121.391394)
		(end 211.71 121.479908)
		(width 0.1)
		(layer "F.Cu")
		(net 301)
	)
	(segment
		(start 211.625 121.74)
		(end 211.295 121.74)
		(width 0.1)
		(layer "F.Cu")
		(net 301)
	)
	(segment
		(start 211.71 121.655)
		(end 211.625 121.74)
		(width 0.1)
		(layer "F.Cu")
		(net 301)
	)
	(via
		(at 222.075 122.3)
		(size 0.35)
		(drill 0.15)
		(layers "F.Cu" "B.Cu")
		(remove_unused_layers yes)
		(keep_end_layers yes)
		(zone_layer_connections)
		(net 301)
	)
	(via
		(at 211.621486 121.391394)
		(size 0.35)
		(drill 0.15)
		(layers "F.Cu" "B.Cu")
		(remove_unused_layers yes)
		(keep_end_layers yes)
		(zone_layer_connections)
		(net 301)
	)
	(segment
		(start 214.350294 124.43)
		(end 216.280294 126.36)
		(width 0.09)
		(layer "In4.Cu")
		(net 301)
	)
	(segment
		(start 211.85 121.55)
		(end 211.85 121.64)
		(width 0.09)
		(layer "In4.Cu")
		(net 301)
	)
	(segment
		(start 216.280294 126.36)
		(end 219.299706 126.36)
		(width 0.09)
		(layer "In4.Cu")
		(net 301)
	)
	(segment
		(start 211.329411 121.730883)
		(end 210.94 122.120294)
		(width 0.09)
		(layer "In4.Cu")
		(net 301)
	)
	(segment
		(start 210.94 122.919706)
		(end 212.450294 124.43)
		(width 0.09)
		(layer "In4.Cu")
		(net 301)
	)
	(segment
		(start 211.621486 121.391394)
		(end 211.691394 121.391394)
		(width 0.09)
		(layer "In4.Cu")
		(net 301)
	)
	(segment
		(start 223.06 124.069706)
		(end 223.06 122.880294)
		(width 0.09)
		(layer "In4.Cu")
		(net 301)
	)
	(segment
		(start 211.85 121.64)
		(end 211.759117 121.730883)
		(width 0.09)
		(layer "In4.Cu")
		(net 301)
	)
	(segment
		(start 222.255 122.48)
		(end 222.075 122.3)
		(width 0.09)
		(layer "In4.Cu")
		(net 301)
	)
	(segment
		(start 211.759117 121.730883)
		(end 211.329411 121.730883)
		(width 0.09)
		(layer "In4.Cu")
		(net 301)
	)
	(segment
		(start 223.06 122.880294)
		(end 222.659706 122.48)
		(width 0.09)
		(layer "In4.Cu")
		(net 301)
	)
	(segment
		(start 220.949706 124.71)
		(end 222.419706 124.71)
		(width 0.09)
		(layer "In4.Cu")
		(net 301)
	)
	(segment
		(start 222.659706 122.48)
		(end 222.255 122.48)
		(width 0.09)
		(layer "In4.Cu")
		(net 301)
	)
	(segment
		(start 212.450294 124.43)
		(end 214.350294 124.43)
		(width 0.09)
		(layer "In4.Cu")
		(net 301)
	)
	(segment
		(start 222.419706 124.71)
		(end 223.06 124.069706)
		(width 0.09)
		(layer "In4.Cu")
		(net 301)
	)
	(segment
		(start 210.94 122.120294)
		(end 210.94 122.919706)
		(width 0.09)
		(layer "In4.Cu")
		(net 301)
	)
	(segment
		(start 219.299706 126.36)
		(end 220.949706 124.71)
		(width 0.09)
		(layer "In4.Cu")
		(net 301)
	)
	(segment
		(start 211.691394 121.391394)
		(end 211.85 121.55)
		(width 0.09)
		(layer "In4.Cu")
		(net 301)
	)
	(segment
		(start 210.905 122.3406)
		(end 211.2903 121.9553)
		(width 0.1)
		(layer "F.Cu")
		(net 302)
	)
	(segment
		(start 211.8 122.2)
		(end 211.8 122.35)
		(width 0.1)
		(layer "F.Cu")
		(net 302)
	)
	(segment
		(start 211.2903 121.9553)
		(end 211.5553 121.9553)
		(width 0.1)
		(layer "F.Cu")
		(net 302)
	)
	(segment
		(start 211.5553 121.9553)
		(end 211.8 122.2)
		(width 0.1)
		(layer "F.Cu")
		(net 302)
	)
	(via
		(at 222.075 122.9)
		(size 0.35)
		(drill 0.15)
		(layers "F.Cu" "B.Cu")
		(remove_unused_layers yes)
		(keep_end_layers yes)
		(zone_layer_connections)
		(net 302)
	)
	(via
		(at 211.8 122.35)
		(size 0.35)
		(drill 0.15)
		(layers "F.Cu" "B.Cu")
		(remove_unused_layers yes)
		(keep_end_layers yes)
		(zone_layer_connections)
		(net 302)
	)
	(segment
		(start 222.560294 122.72)
		(end 222.255 122.72)
		(width 0.09)
		(layer "In4.Cu")
		(net 302)
	)
	(segment
		(start 216.379706 126.12)
		(end 219.200294 126.12)
		(width 0.09)
		(layer "In4.Cu")
		(net 302)
	)
	(segment
		(start 212.549706 124.19)
		(end 214.449706 124.19)
		(width 0.09)
		(layer "In4.Cu")
		(net 302)
	)
	(segment
		(start 211.719116 123.35941)
		(end 212.549706 124.19)
		(width 0.09)
		(layer "In4.Cu")
		(net 302)
	)
	(segment
		(start 221.69 124.32)
		(end 221.69 124.283499)
		(width 0.09)
		(layer "In4.Cu")
		(net 302)
	)
	(segment
		(start 222.82 123.970294)
		(end 222.82 122.979706)
		(width 0.09)
		(layer "In4.Cu")
		(net 302)
	)
	(segment
		(start 222.14 124.47)
		(end 222.320294 124.47)
		(width 0.09)
		(layer "In4.Cu")
		(net 302)
	)
	(segment
		(start 211.506985 122.935147)
		(end 211.648407 122.793726)
		(width 0.09)
		(layer "In4.Cu")
		(net 302)
	)
	(segment
		(start 221.39 124.183517)
		(end 221.39 124.32)
		(width 0.09)
		(layer "In4.Cu")
		(net 302)
	)
	(segment
		(start 211.18 122.820294)
		(end 211.294853 122.935147)
		(width 0.09)
		(layer "In4.Cu")
		(net 302)
	)
	(segment
		(start 211.428823 121.970883)
		(end 211.18 122.219706)
		(width 0.09)
		(layer "In4.Cu")
		(net 302)
	)
	(segment
		(start 222.255 122.72)
		(end 222.075 122.9)
		(width 0.09)
		(layer "In4.Cu")
		(net 302)
	)
	(segment
		(start 221.09 124.32)
		(end 221.09 124.183517)
		(width 0.09)
		(layer "In4.Cu")
		(net 302)
	)
	(segment
		(start 214.449706 124.19)
		(end 216.379706 126.12)
		(width 0.09)
		(layer "In4.Cu")
		(net 302)
	)
	(segment
		(start 211.641477 121.970883)
		(end 211.428823 121.970883)
		(width 0.09)
		(layer "In4.Cu")
		(net 302)
	)
	(segment
		(start 211.18 122.219706)
		(end 211.18 122.820294)
		(width 0.09)
		(layer "In4.Cu")
		(net 302)
	)
	(segment
		(start 211.860539 123.005858)
		(end 211.719116 123.147278)
		(width 0.09)
		(layer "In4.Cu")
		(net 302)
	)
	(segment
		(start 221.99 124.283499)
		(end 221.99 124.32)
		(width 0.09)
		(layer "In4.Cu")
		(net 302)
	)
	(segment
		(start 211.8 122.129406)
		(end 211.641477 121.970883)
		(width 0.09)
		(layer "In4.Cu")
		(net 302)
	)
	(segment
		(start 220.850294 124.47)
		(end 220.94 124.47)
		(width 0.09)
		(layer "In4.Cu")
		(net 302)
	)
	(segment
		(start 211.506986 122.935146)
		(end 211.506985 122.935147)
		(width 0.09)
		(layer "In4.Cu")
		(net 302)
	)
	(segment
		(start 222.82 122.979706)
		(end 222.560294 122.72)
		(width 0.09)
		(layer "In4.Cu")
		(net 302)
	)
	(segment
		(start 211.8 122.35)
		(end 211.8 122.129406)
		(width 0.09)
		(layer "In4.Cu")
		(net 302)
	)
	(segment
		(start 222.320294 124.47)
		(end 222.82 123.970294)
		(width 0.09)
		(layer "In4.Cu")
		(net 302)
	)
	(segment
		(start 211.860538 123.005859)
		(end 211.860539 123.005858)
		(width 0.09)
		(layer "In4.Cu")
		(net 302)
	)
	(segment
		(start 219.200294 126.12)
		(end 220.850294 124.47)
		(width 0.09)
		(layer "In4.Cu")
		(net 302)
	)
	(arc
		(start 211.648407 122.793726)
		(mid 211.754473 122.749792)
		(end 211.860539 122.793726)
		(width 0.09)
		(layer "In4.Cu")
		(net 302)
	)
	(arc
		(start 211.294853 122.935147)
		(mid 211.400921 122.979082)
		(end 211.506986 122.935146)
		(width 0.09)
		(layer "In4.Cu")
		(net 302)
	)
	(arc
		(start 211.719116 123.147278)
		(mid 211.675182 123.253344)
		(end 211.719116 123.35941)
		(width 0.09)
		(layer "In4.Cu")
		(net 302)
	)
	(arc
		(start 221.84 124.133499)
		(mid 221.946066 124.177433)
		(end 221.99 124.283499)
		(width 0.09)
		(layer "In4.Cu")
		(net 302)
	)
	(arc
		(start 221.24 124.033517)
		(mid 221.346066 124.077451)
		(end 221.39 124.183517)
		(width 0.09)
		(layer "In4.Cu")
		(net 302)
	)
	(arc
		(start 221.54 124.47)
		(mid 221.646066 124.426066)
		(end 221.69 124.32)
		(width 0.09)
		(layer "In4.Cu")
		(net 302)
	)
	(arc
		(start 221.39 124.32)
		(mid 221.433934 124.426066)
		(end 221.54 124.47)
		(width 0.09)
		(layer "In4.Cu")
		(net 302)
	)
	(arc
		(start 221.09 124.183517)
		(mid 221.133934 124.077451)
		(end 221.24 124.033517)
		(width 0.09)
		(layer "In4.Cu")
		(net 302)
	)
	(arc
		(start 221.99 124.32)
		(mid 222.033934 124.426066)
		(end 222.14 124.47)
		(width 0.09)
		(layer "In4.Cu")
		(net 302)
	)
	(arc
		(start 220.94 124.47)
		(mid 221.046066 124.426066)
		(end 221.09 124.32)
		(width 0.09)
		(layer "In4.Cu")
		(net 302)
	)
	(arc
		(start 211.860539 122.793726)
		(mid 211.904472 122.899792)
		(end 211.860538 123.005859)
		(width 0.09)
		(layer "In4.Cu")
		(net 302)
	)
	(arc
		(start 221.69 124.283499)
		(mid 221.733934 124.177433)
		(end 221.84 124.133499)
		(width 0.09)
		(layer "In4.Cu")
		(net 302)
	)
	(via
		(at 203.049 144.801)
		(size 0.35)
		(drill 0.15)
		(layers "F.Cu" "B.Cu")
		(remove_unused_layers yes)
		(keep_end_layers yes)
		(zone_layer_connections)
		(net 303)
	)
	(via
		(at 193.299 138.65)
		(size 0.35)
		(drill 0.15)
		(layers "F.Cu" "B.Cu")
		(remove_unused_layers yes)
		(keep_end_layers yes)
		(zone_layer_connections)
		(net 303)
	)
	(segment
		(start 198.42 139.632549)
		(end 198.42 139.367451)
		(width 0.09)
		(layer "In11.Cu")
		(net 303)
	)
	(segment
		(start 195.23 138.38)
		(end 194.606451 138.38)
		(width 0.09)
		(layer "In11.Cu")
		(net 303)
	)
	(segment
		(start 198.607451 139.82)
		(end 198.42 139.632549)
		(width 0.09)
		(layer "In11.Cu")
		(net 303)
	)
	(segment
		(start 193.699 139.05)
		(end 193.299 138.65)
		(width 0.09)
		(layer "In11.Cu")
		(net 303)
	)
	(segment
		(start 203.5675 145.26)
		(end 203.66 145.3525)
		(width 0.09)
		(layer "In11.Cu")
		(net 303)
	)
	(segment
		(start 199.219 140.119)
		(end 198.92 139.82)
		(width 0.09)
		(layer "In11.Cu")
		(net 303)
	)
	(segment
		(start 201.125 142.8)
		(end 201.125 142.179549)
		(width 0.09)
		(layer "In11.Cu")
		(net 303)
	)
	(segment
		(start 199.726451 140.781)
		(end 199.219 140.273549)
		(width 0.09)
		(layer "In11.Cu")
		(net 303)
	)
	(segment
		(start 203.66 145.3525)
		(end 203.66 145.64)
		(width 0.09)
		(layer "In11.Cu")
		(net 303)
	)
	(segment
		(start 194.5 138.486451)
		(end 194.5 138.8)
		(width 0.09)
		(layer "In11.Cu")
		(net 303)
	)
	(segment
		(start 203.56 145.74)
		(end 202.69 145.74)
		(width 0.09)
		(layer "In11.Cu")
		(net 303)
	)
	(segment
		(start 202.150549 143.45)
		(end 201.775 143.45)
		(width 0.09)
		(layer "In11.Cu")
		(net 303)
	)
	(segment
		(start 198.152549 139.1)
		(end 195.95 139.1)
		(width 0.09)
		(layer "In11.Cu")
		(net 303)
	)
	(segment
		(start 198.42 139.367451)
		(end 198.152549 139.1)
		(width 0.09)
		(layer "In11.Cu")
		(net 303)
	)
	(segment
		(start 201.125 142.179549)
		(end 200.179 141.233549)
		(width 0.09)
		(layer "In11.Cu")
		(net 303)
	)
	(segment
		(start 202.719 144.018451)
		(end 202.150549 143.45)
		(width 0.09)
		(layer "In11.Cu")
		(net 303)
	)
	(segment
		(start 200.179 141.233549)
		(end 200.179 141.128451)
		(width 0.09)
		(layer "In11.Cu")
		(net 303)
	)
	(segment
		(start 194.25 139.05)
		(end 193.699 139.05)
		(width 0.09)
		(layer "In11.Cu")
		(net 303)
	)
	(segment
		(start 194.606451 138.38)
		(end 194.5 138.486451)
		(width 0.09)
		(layer "In11.Cu")
		(net 303)
	)
	(segment
		(start 203.22 145.26)
		(end 203.5675 145.26)
		(width 0.09)
		(layer "In11.Cu")
		(net 303)
	)
	(segment
		(start 201.775 143.45)
		(end 201.125 142.8)
		(width 0.09)
		(layer "In11.Cu")
		(net 303)
	)
	(segment
		(start 203.049 144.801)
		(end 203.049 145.089)
		(width 0.09)
		(layer "In11.Cu")
		(net 303)
	)
	(segment
		(start 199.219 140.273549)
		(end 199.219 140.119)
		(width 0.09)
		(layer "In11.Cu")
		(net 303)
	)
	(segment
		(start 202.69 145.74)
		(end 202.58 145.63)
		(width 0.09)
		(layer "In11.Cu")
		(net 303)
	)
	(segment
		(start 195.95 139.1)
		(end 195.23 138.38)
		(width 0.09)
		(layer "In11.Cu")
		(net 303)
	)
	(segment
		(start 202.719 145.261)
		(end 202.719 144.018451)
		(width 0.09)
		(layer "In11.Cu")
		(net 303)
	)
	(segment
		(start 203.66 145.64)
		(end 203.56 145.74)
		(width 0.09)
		(layer "In11.Cu")
		(net 303)
	)
	(segment
		(start 199.831549 140.781)
		(end 199.726451 140.781)
		(width 0.09)
		(layer "In11.Cu")
		(net 303)
	)
	(segment
		(start 194.5 138.8)
		(end 194.25 139.05)
		(width 0.09)
		(layer "In11.Cu")
		(net 303)
	)
	(segment
		(start 203.049 145.089)
		(end 203.22 145.26)
		(width 0.09)
		(layer "In11.Cu")
		(net 303)
	)
	(segment
		(start 198.92 139.82)
		(end 198.607451 139.82)
		(width 0.09)
		(layer "In11.Cu")
		(net 303)
	)
	(segment
		(start 202.58 145.63)
		(end 202.58 145.4)
		(width 0.09)
		(layer "In11.Cu")
		(net 303)
	)
	(segment
		(start 200.179 141.128451)
		(end 199.831549 140.781)
		(width 0.09)
		(layer "In11.Cu")
		(net 303)
	)
	(segment
		(start 202.58 145.4)
		(end 202.719 145.261)
		(width 0.09)
		(layer "In11.Cu")
		(net 303)
	)
	(via
		(at 201.749 144.151)
		(size 0.35)
		(drill 0.15)
		(layers "F.Cu" "B.Cu")
		(remove_unused_layers yes)
		(keep_end_layers yes)
		(zone_layer_connections)
		(net 304)
	)
	(via
		(at 192.499 136.301)
		(size 0.35)
		(drill 0.15)
		(layers "F.Cu" "B.Cu")
		(remove_unused_layers yes)
		(keep_end_layers yes)
		(zone_layer_connections)
		(net 304)
	)
	(segment
		(start 195.3 136.04)
		(end 195.3 136.52)
		(width 0.09)
		(layer "In9.Cu")
		(net 304)
	)
	(segment
		(start 198.78 139.08)
		(end 199.04 139.08)
		(width 0.09)
		(layer "In9.Cu")
		(net 304)
	)
	(segment
		(start 200.12 140.45)
		(end 200.38 140.71)
		(width 0.09)
		(layer "In9.Cu")
		(net 304)
	)
	(segment
		(start 199.04 139.08)
		(end 200.12 140.16)
		(width 0.09)
		(layer "In9.Cu")
		(net 304)
	)
	(segment
		(start 196.719226 137.079226)
		(end 197.730774 137.079226)
		(width 0.09)
		(layer "In9.Cu")
		(net 304)
	)
	(segment
		(start 195.14 135.88)
		(end 195.3 136.04)
		(width 0.09)
		(layer "In9.Cu")
		(net 304)
	)
	(segment
		(start 200.38 140.71)
		(end 200.68 140.71)
		(width 0.09)
		(layer "In9.Cu")
		(net 304)
	)
	(segment
		(start 201.924 142.495)
		(end 202.55079 142.495)
		(width 0.09)
		(layer "In9.Cu")
		(net 304)
	)
	(segment
		(start 192.57 135.88)
		(end 195.14 135.88)
		(width 0.09)
		(layer "In9.Cu")
		(net 304)
	)
	(segment
		(start 192.499 136.301)
		(end 192.499 135.951)
		(width 0.09)
		(layer "In9.Cu")
		(net 304)
	)
	(segment
		(start 200.68 140.71)
		(end 200.94 140.97)
		(width 0.09)
		(layer "In9.Cu")
		(net 304)
	)
	(segment
		(start 200.12 140.16)
		(end 200.12 140.45)
		(width 0.09)
		(layer "In9.Cu")
		(net 304)
	)
	(segment
		(start 201.924 143.195)
		(end 202.55079 143.195)
		(width 0.09)
		(layer "In9.Cu")
		(net 304)
	)
	(segment
		(start 200.94 140.97)
		(end 200.94 141.32)
		(width 0.09)
		(layer "In9.Cu")
		(net 304)
	)
	(segment
		(start 197.730774 137.079226)
		(end 198.080774 137.429226)
		(width 0.09)
		(layer "In9.Cu")
		(net 304)
	)
	(segment
		(start 198.080774 138.030774)
		(end 198.53 138.48)
		(width 0.09)
		(layer "In9.Cu")
		(net 304)
	)
	(segment
		(start 192.499 135.951)
		(end 192.57 135.88)
		(width 0.09)
		(layer "In9.Cu")
		(net 304)
	)
	(segment
		(start 201.749 142.129)
		(end 201.749 142.32)
		(width 0.09)
		(layer "In9.Cu")
		(net 304)
	)
	(segment
		(start 196.4 136.76)
		(end 196.719226 137.079226)
		(width 0.09)
		(layer "In9.Cu")
		(net 304)
	)
	(segment
		(start 202.55079 142.845)
		(end 201.924 142.845)
		(width 0.09)
		(layer "In9.Cu")
		(net 304)
	)
	(segment
		(start 202.55079 143.545)
		(end 201.924 143.545)
		(width 0.09)
		(layer "In9.Cu")
		(net 304)
	)
	(segment
		(start 198.080774 137.429226)
		(end 198.080774 138.030774)
		(width 0.09)
		(layer "In9.Cu")
		(net 304)
	)
	(segment
		(start 195.3 136.52)
		(end 195.54 136.76)
		(width 0.09)
		(layer "In9.Cu")
		(net 304)
	)
	(segment
		(start 200.94 141.32)
		(end 201.749 142.129)
		(width 0.09)
		(layer "In9.Cu")
		(net 304)
	)
	(segment
		(start 198.53 138.83)
		(end 198.78 139.08)
		(width 0.09)
		(layer "In9.Cu")
		(net 304)
	)
	(segment
		(start 198.53 138.48)
		(end 198.53 138.83)
		(width 0.09)
		(layer "In9.Cu")
		(net 304)
	)
	(segment
		(start 201.749 144.089999)
		(end 201.749 144.151)
		(width 0.09)
		(layer "In9.Cu")
		(net 304)
	)
	(segment
		(start 195.54 136.76)
		(end 196.4 136.76)
		(width 0.09)
		(layer "In9.Cu")
		(net 304)
	)
	(segment
		(start 201.749 143.72)
		(end 201.749 144.089999)
		(width 0.09)
		(layer "In9.Cu")
		(net 304)
	)
	(arc
		(start 202.72579 143.37)
		(mid 202.674534 143.493744)
		(end 202.55079 143.545)
		(width 0.09)
		(layer "In9.Cu")
		(net 304)
	)
	(arc
		(start 202.55079 143.195)
		(mid 202.674534 143.246256)
		(end 202.72579 143.37)
		(width 0.09)
		(layer "In9.Cu")
		(net 304)
	)
	(arc
		(start 201.749 142.32)
		(mid 201.800256 142.443744)
		(end 201.924 142.495)
		(width 0.09)
		(layer "In9.Cu")
		(net 304)
	)
	(arc
		(start 201.749 143.02)
		(mid 201.800256 143.143744)
		(end 201.924 143.195)
		(width 0.09)
		(layer "In9.Cu")
		(net 304)
	)
	(arc
		(start 201.924 143.545)
		(mid 201.800256 143.596256)
		(end 201.749 143.72)
		(width 0.09)
		(layer "In9.Cu")
		(net 304)
	)
	(arc
		(start 202.55079 142.495)
		(mid 202.674534 142.546256)
		(end 202.72579 142.67)
		(width 0.09)
		(layer "In9.Cu")
		(net 304)
	)
	(arc
		(start 202.72579 142.67)
		(mid 202.674534 142.793744)
		(end 202.55079 142.845)
		(width 0.09)
		(layer "In9.Cu")
		(net 304)
	)
	(arc
		(start 201.924 142.845)
		(mid 201.800256 142.896256)
		(end 201.749 143.02)
		(width 0.09)
		(layer "In9.Cu")
		(net 304)
	)
	(segment
		(start 176.404 126.016)
		(end 176.0045 126.3405)
		(width 0.174)
		(layer "F.Cu")
		(net 305)
	)
	(via
		(at 176.0045 126.3405)
		(size 0.35)
		(drill 0.15)
		(layers "F.Cu" "B.Cu")
		(remove_unused_layers yes)
		(keep_end_layers yes)
		(zone_layer_connections)
		(net 305)
	)
	(via
		(at 190.1 124.3)
		(size 0.35)
		(drill 0.15)
		(layers "F.Cu" "B.Cu")
		(remove_unused_layers yes)
		(keep_end_layers yes)
		(zone_layer_connections)
		(net 305)
	)
	(segment
		(start 177.55 127.859451)
		(end 177.55 128.7)
		(width 0.09)
		(layer "In2.Cu")
		(net 305)
	)
	(segment
		(start 190.5 129.25)
		(end 190.5 128.9)
		(width 0.09)
		(layer "In2.Cu")
		(net 305)
	)
	(segment
		(start 176.031049 126.3405)
		(end 177.55 127.859451)
		(width 0.09)
		(layer "In2.Cu")
		(net 305)
	)
	(segment
		(start 190.7 126.3)
		(end 190.5 126.1)
		(width 0.09)
		(layer "In2.Cu")
		(net 305)
	)
	(segment
		(start 191.05 126.3)
		(end 190.7 126.3)
		(width 0.09)
		(layer "In2.Cu")
		(net 305)
	)
	(segment
		(start 176.0045 126.3405)
		(end 176.031049 126.3405)
		(width 0.09)
		(layer "In2.Cu")
		(net 305)
	)
	(segment
		(start 190.25 129.5)
		(end 190.5 129.25)
		(width 0.09)
		(layer "In2.Cu")
		(net 305)
	)
	(segment
		(start 191.1 128.7)
		(end 191.3 128.5)
		(width 0.09)
		(layer "In2.Cu")
		(net 305)
	)
	(segment
		(start 190.5 128.9)
		(end 190.7 128.7)
		(width 0.09)
		(layer "In2.Cu")
		(net 305)
	)
	(segment
		(start 177.55 128.7)
		(end 178.35 129.5)
		(width 0.09)
		(layer "In2.Cu")
		(net 305)
	)
	(segment
		(start 190.5 126.1)
		(end 190.5 124.7)
		(width 0.09)
		(layer "In2.Cu")
		(net 305)
	)
	(segment
		(start 191.3 128.5)
		(end 191.3 126.55)
		(width 0.09)
		(layer "In2.Cu")
		(net 305)
	)
	(segment
		(start 190.7 128.7)
		(end 191.1 128.7)
		(width 0.09)
		(layer "In2.Cu")
		(net 305)
	)
	(segment
		(start 191.3 126.55)
		(end 191.05 126.3)
		(width 0.09)
		(layer "In2.Cu")
		(net 305)
	)
	(segment
		(start 178.35 129.5)
		(end 190.25 129.5)
		(width 0.09)
		(layer "In2.Cu")
		(net 305)
	)
	(segment
		(start 190.5 124.7)
		(end 190.1 124.3)
		(width 0.09)
		(layer "In2.Cu")
		(net 305)
	)
	(segment
		(start 177.205 124.717)
		(end 176.8055 124.3925)
		(width 0.174)
		(layer "F.Cu")
		(net 306)
	)
	(via
		(at 190.1 125.101)
		(size 0.35)
		(drill 0.15)
		(layers "F.Cu" "B.Cu")
		(remove_unused_layers yes)
		(keep_end_layers yes)
		(zone_layer_connections)
		(net 306)
	)
	(via
		(at 176.8055 124.3925)
		(size 0.35)
		(drill 0.15)
		(layers "F.Cu" "B.Cu")
		(remove_unused_layers yes)
		(keep_end_layers yes)
		(zone_layer_connections)
		(net 306)
	)
	(segment
		(start 189.596438 123.832309)
		(end 189.596438 123.83231)
		(width 0.09)
		(layer "In2.Cu")
		(net 306)
	)
	(segment
		(start 176.8175 124.3925)
		(end 176.8055 124.3925)
		(width 0.09)
		(layer "In2.Cu")
		(net 306)
	)
	(segment
		(start 188.155 124.225)
		(end 188.155 124.545)
		(width 0.09)
		(layer "In2.Cu")
		(net 306)
	)
	(segment
		(start 186.520878 123.801174)
		(end 186.52088 123.801175)
		(width 0.09)
		(layer "In2.Cu")
		(net 306)
	)
	(segment
		(start 177.0225 124.5975)
		(end 176.8175 124.3925)
		(width 0.09)
		(layer "In2.Cu")
		(net 306)
	)
	(segment
		(start 177.357794 124.5975)
		(end 177.0225 124.5975)
		(width 0.09)
		(layer "In2.Cu")
		(net 306)
	)
	(segment
		(start 190.1 125.101)
		(end 190.1 124.85)
		(width 0.09)
		(layer "In2.Cu")
		(net 306)
	)
	(segment
		(start 184.509706 121.79)
		(end 177.888556 121.79)
		(width 0.09)
		(layer "In2.Cu")
		(net 306)
	)
	(segment
		(start 185.672351 122.952646)
		(end 184.509706 121.79)
		(width 0.09)
		(layer "In2.Cu")
		(net 306)
	)
	(segment
		(start 189.724999 124.057303)
		(end 189.725 124.057303)
		(width 0.09)
		(layer "In2.Cu")
		(net 306)
	)
	(segment
		(start 177.888556 121.79)
		(end 177.53 122.148556)
		(width 0.09)
		(layer "In2.Cu")
		(net 306)
	)
	(segment
		(start 187.412805 123.163812)
		(end 186.775418 123.801198)
		(width 0.09)
		(layer "In2.Cu")
		(net 306)
	)
	(segment
		(start 177.53 124.425294)
		(end 177.357794 124.5975)
		(width 0.09)
		(layer "In2.Cu")
		(net 306)
	)
	(segment
		(start 189.725 124.475)
		(end 189.725 124.23408)
		(width 0.09)
		(layer "In2.Cu")
		(net 306)
	)
	(segment
		(start 189.371446 123.880525)
		(end 189.371445 123.880525)
		(width 0.09)
		(layer "In2.Cu")
		(net 306)
	)
	(segment
		(start 188.975 123.755)
		(end 188.625 123.755)
		(width 0.09)
		(layer "In2.Cu")
		(net 306)
	)
	(segment
		(start 187.494706 124.775)
		(end 187.36941 124.649705)
		(width 0.09)
		(layer "In2.Cu")
		(net 306)
	)
	(segment
		(start 189.095 123.875)
		(end 188.975 123.755)
		(width 0.09)
		(layer "In2.Cu")
		(net 306)
	)
	(segment
		(start 189.773215 123.832311)
		(end 189.773215 123.83231)
		(width 0.09)
		(layer "In2.Cu")
		(net 306)
	)
	(segment
		(start 177.53 122.148556)
		(end 177.53 124.425294)
		(width 0.09)
		(layer "In2.Cu")
		(net 306)
	)
	(segment
		(start 189.371445 123.880525)
		(end 189.36592 123.875)
		(width 0.09)
		(layer "In2.Cu")
		(net 306)
	)
	(segment
		(start 187.369409 124.395146)
		(end 188.006773 123.757781)
		(width 0.09)
		(layer "In2.Cu")
		(net 306)
	)
	(segment
		(start 189.596438 123.83231)
		(end 189.548222 123.880525)
		(width 0.09)
		(layer "In2.Cu")
		(net 306)
	)
	(segment
		(start 189.725 124.057303)
		(end 189.773215 124.009087)
		(width 0.09)
		(layer "In2.Cu")
		(net 306)
	)
	(segment
		(start 186.663316 122.81021)
		(end 186.663317 122.810212)
		(width 0.09)
		(layer "In2.Cu")
		(net 306)
	)
	(segment
		(start 186.069348 122.810211)
		(end 185.926911 122.952647)
		(width 0.09)
		(layer "In2.Cu")
		(net 306)
	)
	(segment
		(start 185.926911 122.952647)
		(end 185.926913 122.952648)
		(width 0.09)
		(layer "In2.Cu")
		(net 306)
	)
	(segment
		(start 189.36592 123.875)
		(end 189.095 123.875)
		(width 0.09)
		(layer "In2.Cu")
		(net 306)
	)
	(segment
		(start 190.1 124.85)
		(end 189.725 124.475)
		(width 0.09)
		(layer "In2.Cu")
		(net 306)
	)
	(segment
		(start 186.520879 123.546617)
		(end 186.663316 123.40418)
		(width 0.09)
		(layer "In2.Cu")
		(net 306)
	)
	(segment
		(start 188.006773 123.163811)
		(end 188.006774 123.163813)
		(width 0.09)
		(layer "In2.Cu")
		(net 306)
	)
	(segment
		(start 187.925 124.775)
		(end 187.494706 124.775)
		(width 0.09)
		(layer "In2.Cu")
		(net 306)
	)
	(arc
		(start 186.775418 123.801198)
		(mid 186.648143 123.85391)
		(end 186.520878 123.801174)
		(width 0.09)
		(layer "In2.Cu")
		(net 306)
	)
	(arc
		(start 186.663317 122.810212)
		(mid 186.366333 122.687196)
		(end 186.069348 122.810211)
		(width 0.09)
		(layer "In2.Cu")
		(net 306)
	)
	(arc
		(start 189.773215 123.83231)
		(mid 189.684827 123.795698)
		(end 189.596438 123.832309)
		(width 0.09)
		(layer "In2.Cu")
		(net 306)
	)
	(arc
		(start 188.155 124.545)
		(mid 188.087635 124.707635)
		(end 187.925 124.775)
		(width 0.09)
		(layer "In2.Cu")
		(net 306)
	)
	(arc
		(start 188.006773 123.757781)
		(mid 188.129788 123.460796)
		(end 188.006773 123.163811)
		(width 0.09)
		(layer "In2.Cu")
		(net 306)
	)
	(arc
		(start 187.36941 124.649705)
		(mid 187.316689 124.522426)
		(end 187.369409 124.395146)
		(width 0.09)
		(layer "In2.Cu")
		(net 306)
	)
	(arc
		(start 189.725 124.23408)
		(mid 189.688388 124.145692)
		(end 189.724999 124.057303)
		(width 0.09)
		(layer "In2.Cu")
		(net 306)
	)
	(arc
		(start 186.663316 123.40418)
		(mid 186.786331 123.107195)
		(end 186.663316 122.81021)
		(width 0.09)
		(layer "In2.Cu")
		(net 306)
	)
	(arc
		(start 189.548222 123.880525)
		(mid 189.459834 123.917137)
		(end 189.371446 123.880525)
		(width 0.09)
		(layer "In2.Cu")
		(net 306)
	)
	(arc
		(start 189.773215 124.009087)
		(mid 189.809827 123.920699)
		(end 189.773215 123.832311)
		(width 0.09)
		(layer "In2.Cu")
		(net 306)
	)
	(arc
		(start 188.006774 123.163813)
		(mid 187.70979 123.040797)
		(end 187.412805 123.163812)
		(width 0.09)
		(layer "In2.Cu")
		(net 306)
	)
	(arc
		(start 186.52088 123.801175)
		(mid 186.468158 123.673896)
		(end 186.520879 123.546617)
		(width 0.09)
		(layer "In2.Cu")
		(net 306)
	)
	(arc
		(start 185.926913 122.952648)
		(mid 185.799632 123.005368)
		(end 185.672351 122.952646)
		(width 0.09)
		(layer "In2.Cu")
		(net 306)
	)
	(arc
		(start 188.625 123.755)
		(mid 188.29266 123.89266)
		(end 188.155 124.225)
		(width 0.09)
		(layer "In2.Cu")
		(net 306)
	)
	(segment
		(start 177.205 125.367)
		(end 176.8055 125.0425)
		(width 0.174)
		(layer "F.Cu")
		(net 307)
	)
	(via
		(at 190.1 125.901)
		(size 0.35)
		(drill 0.15)
		(layers "F.Cu" "B.Cu")
		(remove_unused_layers yes)
		(keep_end_layers yes)
		(zone_layer_connections)
		(net 307)
	)
	(via
		(at 176.8055 125.0425)
		(size 0.35)
		(drill 0.15)
		(layers "F.Cu" "B.Cu")
		(remove_unused_layers yes)
		(keep_end_layers yes)
		(zone_layer_connections)
		(net 307)
	)
	(segment
		(start 186.351174 123.970881)
		(end 186.351173 123.970879)
		(width 0.09)
		(layer "In2.Cu")
		(net 307)
	)
	(segment
		(start 186.493612 122.979917)
		(end 186.493611 122.979916)
		(width 0.09)
		(layer "In2.Cu")
		(net 307)
	)
	(segment
		(start 177.77 122.247968)
		(end 177.987968 122.03)
		(width 0.09)
		(layer "In2.Cu")
		(net 307)
	)
	(segment
		(start 177.0105 124.8375)
		(end 177.457206 124.8375)
		(width 0.09)
		(layer "In2.Cu")
		(net 307)
	)
	(segment
		(start 187.199702 124.819408)
		(end 187.395294 125.015)
		(width 0.09)
		(layer "In2.Cu")
		(net 307)
	)
	(segment
		(start 187.199704 124.819409)
		(end 187.199702 124.819408)
		(width 0.09)
		(layer "In2.Cu")
		(net 307)
	)
	(segment
		(start 189.5 124.725)
		(end 189.7 124.925)
		(width 0.09)
		(layer "In2.Cu")
		(net 307)
	)
	(segment
		(start 186.945123 123.970903)
		(end 187.58251 123.333517)
		(width 0.09)
		(layer "In2.Cu")
		(net 307)
	)
	(segment
		(start 187.199703 124.22544)
		(end 187.837068 123.588075)
		(width 0.09)
		(layer "In2.Cu")
		(net 307)
	)
	(segment
		(start 186.351174 123.376911)
		(end 186.493611 123.234474)
		(width 0.09)
		(layer "In2.Cu")
		(net 307)
	)
	(segment
		(start 189.7 124.925)
		(end 189.7 125.501)
		(width 0.09)
		(layer "In2.Cu")
		(net 307)
	)
	(segment
		(start 177.987968 122.03)
		(end 184.410294 122.03)
		(width 0.09)
		(layer "In2.Cu")
		(net 307)
	)
	(segment
		(start 177.457206 124.8375)
		(end 177.77 124.524706)
		(width 0.09)
		(layer "In2.Cu")
		(net 307)
	)
	(segment
		(start 188.625 123.995)
		(end 188.769998 123.995)
		(width 0.09)
		(layer "In2.Cu")
		(net 307)
	)
	(segment
		(start 184.410294 122.03)
		(end 185.502646 123.122351)
		(width 0.09)
		(layer "In2.Cu")
		(net 307)
	)
	(segment
		(start 189.271451 124.725)
		(end 189.5 124.725)
		(width 0.09)
		(layer "In2.Cu")
		(net 307)
	)
	(segment
		(start 187.837069 123.333518)
		(end 187.837068 123.333517)
		(width 0.09)
		(layer "In2.Cu")
		(net 307)
	)
	(segment
		(start 188.395 124.545)
		(end 188.395 124.225)
		(width 0.09)
		(layer "In2.Cu")
		(net 307)
	)
	(segment
		(start 186.096616 123.122352)
		(end 186.239053 122.979916)
		(width 0.09)
		(layer "In2.Cu")
		(net 307)
	)
	(segment
		(start 188.9 124.353549)
		(end 189.271451 124.725)
		(width 0.09)
		(layer "In2.Cu")
		(net 307)
	)
	(segment
		(start 188.769998 123.995)
		(end 188.9 124.125002)
		(width 0.09)
		(layer "In2.Cu")
		(net 307)
	)
	(segment
		(start 189.7 125.501)
		(end 190.1 125.901)
		(width 0.09)
		(layer "In2.Cu")
		(net 307)
	)
	(segment
		(start 187.395294 125.015)
		(end 187.925 125.015)
		(width 0.09)
		(layer "In2.Cu")
		(net 307)
	)
	(segment
		(start 188.9 124.125002)
		(end 188.9 124.353549)
		(width 0.09)
		(layer "In2.Cu")
		(net 307)
	)
	(segment
		(start 176.8055 125.0425)
		(end 177.0105 124.8375)
		(width 0.09)
		(layer "In2.Cu")
		(net 307)
	)
	(segment
		(start 186.096618 123.122353)
		(end 186.096616 123.122352)
		(width 0.09)
		(layer "In2.Cu")
		(net 307)
	)
	(segment
		(start 177.77 124.524706)
		(end 177.77 122.247968)
		(width 0.09)
		(layer "In2.Cu")
		(net 307)
	)
	(arc
		(start 187.925 125.015)
		(mid 188.25734 124.87734)
		(end 188.395 124.545)
		(width 0.09)
		(layer "In2.Cu")
		(net 307)
	)
	(arc
		(start 186.493611 122.979916)
		(mid 186.546332 123.107195)
		(end 186.493611 123.234474)
		(width 0.09)
		(layer "In2.Cu")
		(net 307)
	)
	(arc
		(start 186.351174 123.376911)
		(mid 186.228159 123.673896)
		(end 186.351174 123.970881)
		(width 0.09)
		(layer "In2.Cu")
		(net 307)
	)
	(arc
		(start 187.199703 124.22544)
		(mid 187.076688 124.522425)
		(end 187.199704 124.819409)
		(width 0.09)
		(layer "In2.Cu")
		(net 307)
	)
	(arc
		(start 186.239053 122.979916)
		(mid 186.366333 122.927196)
		(end 186.493612 122.979917)
		(width 0.09)
		(layer "In2.Cu")
		(net 307)
	)
	(arc
		(start 188.395 124.225)
		(mid 188.462365 124.062365)
		(end 188.625 123.995)
		(width 0.09)
		(layer "In2.Cu")
		(net 307)
	)
	(arc
		(start 186.351173 123.970879)
		(mid 186.648143 124.093909)
		(end 186.945123 123.970903)
		(width 0.09)
		(layer "In2.Cu")
		(net 307)
	)
	(arc
		(start 187.837068 123.333517)
		(mid 187.889789 123.460796)
		(end 187.837068 123.588075)
		(width 0.09)
		(layer "In2.Cu")
		(net 307)
	)
	(arc
		(start 187.58251 123.333517)
		(mid 187.70979 123.280797)
		(end 187.837069 123.333518)
		(width 0.09)
		(layer "In2.Cu")
		(net 307)
	)
	(arc
		(start 185.502646 123.122351)
		(mid 185.799633 123.245368)
		(end 186.096618 123.122353)
		(width 0.09)
		(layer "In2.Cu")
		(net 307)
	)
	(segment
		(start 178.005 125.367)
		(end 178.4045 125.0425)
		(width 0.174)
		(layer "F.Cu")
		(net 308)
	)
	(via
		(at 190.1 127.5)
		(size 0.35)
		(drill 0.15)
		(layers "F.Cu" "B.Cu")
		(remove_unused_layers yes)
		(keep_end_layers yes)
		(zone_layer_connections)
		(net 308)
	)
	(via
		(at 178.4045 125.0425)
		(size 0.35)
		(drill 0.15)
		(layers "F.Cu" "B.Cu")
		(remove_unused_layers yes)
		(keep_end_layers yes)
		(zone_layer_connections)
		(net 308)
	)
	(segment
		(start 180 126.15)
		(end 180 126.25)
		(width 0.09)
		(layer "In2.Cu")
		(net 308)
	)
	(segment
		(start 185.898527 128.160027)
		(end 186.0385 128.3)
		(width 0.09)
		(layer "In2.Cu")
		(net 308)
	)
	(segment
		(start 178.4045 125.4045)
		(end 178.975 125.975)
		(width 0.09)
		(layer "In2.Cu")
		(net 308)
	)
	(segment
		(start 185.262132 127.3115)
		(end 185.474265 127.099368)
		(width 0.09)
		(layer "In2.Cu")
		(net 308)
	)
	(segment
		(start 185.686396 127.735764)
		(end 185.898529 127.523632)
		(width 0.09)
		(layer "In2.Cu")
		(net 308)
	)
	(segment
		(start 187.8625 128.3)
		(end 189.0625 127.1)
		(width 0.09)
		(layer "In2.Cu")
		(net 308)
	)
	(segment
		(start 182.2115 127.3115)
		(end 182.675 127.3115)
		(width 0.09)
		(layer "In2.Cu")
		(net 308)
	)
	(segment
		(start 186.110661 127.735764)
		(end 185.898527 127.947895)
		(width 0.09)
		(layer "In2.Cu")
		(net 308)
	)
	(segment
		(start 186.0385 128.3)
		(end 186.325 128.3)
		(width 0.09)
		(layer "In2.Cu")
		(net 308)
	)
	(segment
		(start 189.0625 127.1)
		(end 189.7 127.1)
		(width 0.09)
		(layer "In2.Cu")
		(net 308)
	)
	(segment
		(start 186.475 128.15)
		(end 186.475 127.373072)
		(width 0.09)
		(layer "In2.Cu")
		(net 308)
	)
	(segment
		(start 185.686397 127.735763)
		(end 185.686396 127.735764)
		(width 0.09)
		(layer "In2.Cu")
		(net 308)
	)
	(segment
		(start 180.525 125.975)
		(end 181.8 125.975)
		(width 0.09)
		(layer "In2.Cu")
		(net 308)
	)
	(segment
		(start 182.05 127.15)
		(end 182.2115 127.3115)
		(width 0.09)
		(layer "In2.Cu")
		(net 308)
	)
	(segment
		(start 185.686396 127.311501)
		(end 185.686397 127.3115)
		(width 0.09)
		(layer "In2.Cu")
		(net 308)
	)
	(segment
		(start 185.686397 127.3115)
		(end 185.474263 127.523631)
		(width 0.09)
		(layer "In2.Cu")
		(net 308)
	)
	(segment
		(start 183.725 126.9115)
		(end 183.725 127.1615)
		(width 0.09)
		(layer "In2.Cu")
		(net 308)
	)
	(segment
		(start 187.075 128.15)
		(end 187.075 127.373088)
		(width 0.09)
		(layer "In2.Cu")
		(net 308)
	)
	(segment
		(start 183.125 126.9115)
		(end 183.125 127.1615)
		(width 0.09)
		(layer "In2.Cu")
		(net 308)
	)
	(segment
		(start 178.975 125.975)
		(end 179.825 125.975)
		(width 0.09)
		(layer "In2.Cu")
		(net 308)
	)
	(segment
		(start 182.825 127.1615)
		(end 182.825 126.9115)
		(width 0.09)
		(layer "In2.Cu")
		(net 308)
	)
	(segment
		(start 182.05 126.225)
		(end 182.05 127.15)
		(width 0.09)
		(layer "In2.Cu")
		(net 308)
	)
	(segment
		(start 178.4045 125.0425)
		(end 178.4045 125.4045)
		(width 0.09)
		(layer "In2.Cu")
		(net 308)
	)
	(segment
		(start 184.475 127.3115)
		(end 185.05 127.3115)
		(width 0.09)
		(layer "In2.Cu")
		(net 308)
	)
	(segment
		(start 184.025 127.1615)
		(end 184.025 126.9115)
		(width 0.09)
		(layer "In2.Cu")
		(net 308)
	)
	(segment
		(start 180.35 126.25)
		(end 180.35 126.15)
		(width 0.09)
		(layer "In2.Cu")
		(net 308)
	)
	(segment
		(start 185.262133 127.311499)
		(end 185.262132 127.3115)
		(width 0.09)
		(layer "In2.Cu")
		(net 308)
	)
	(segment
		(start 185.474263 127.735763)
		(end 185.474264 127.735764)
		(width 0.09)
		(layer "In2.Cu")
		(net 308)
	)
	(segment
		(start 186.11066 127.735765)
		(end 186.110661 127.735764)
		(width 0.09)
		(layer "In2.Cu")
		(net 308)
	)
	(segment
		(start 186.775 127.373072)
		(end 186.775 128.15)
		(width 0.09)
		(layer "In2.Cu")
		(net 308)
	)
	(segment
		(start 187.525 128.3)
		(end 187.8625 128.3)
		(width 0.09)
		(layer "In2.Cu")
		(net 308)
	)
	(segment
		(start 189.7 127.1)
		(end 190.1 127.5)
		(width 0.09)
		(layer "In2.Cu")
		(net 308)
	)
	(segment
		(start 187.375 127.373088)
		(end 187.375 128.15)
		(width 0.09)
		(layer "In2.Cu")
		(net 308)
	)
	(segment
		(start 181.8 125.975)
		(end 182.05 126.225)
		(width 0.09)
		(layer "In2.Cu")
		(net 308)
	)
	(segment
		(start 183.425 127.1615)
		(end 183.425 126.9115)
		(width 0.09)
		(layer "In2.Cu")
		(net 308)
	)
	(segment
		(start 184.325 126.9115)
		(end 184.325 127.1615)
		(width 0.09)
		(layer "In2.Cu")
		(net 308)
	)
	(arc
		(start 185.898527 127.947895)
		(mid 185.854593 128.053961)
		(end 185.898527 128.160027)
		(width 0.09)
		(layer "In2.Cu")
		(net 308)
	)
	(arc
		(start 185.474264 127.735764)
		(mid 185.580332 127.779699)
		(end 185.686397 127.735763)
		(width 0.09)
		(layer "In2.Cu")
		(net 308)
	)
	(arc
		(start 179.825 125.975)
		(mid 179.948744 126.026256)
		(end 180 126.15)
		(width 0.09)
		(layer "In2.Cu")
		(net 308)
	)
	(arc
		(start 182.975 126.7615)
		(mid 183.081066 126.805434)
		(end 183.125 126.9115)
		(width 0.09)
		(layer "In2.Cu")
		(net 308)
	)
	(arc
		(start 184.325 127.1615)
		(mid 184.368934 127.267566)
		(end 184.475 127.3115)
		(width 0.09)
		(layer "In2.Cu")
		(net 308)
	)
	(arc
		(start 186.475 127.373072)
		(mid 186.518934 127.267006)
		(end 186.625 127.223072)
		(width 0.09)
		(layer "In2.Cu")
		(net 308)
	)
	(arc
		(start 187.225 127.223088)
		(mid 187.331066 127.267022)
		(end 187.375 127.373088)
		(width 0.09)
		(layer "In2.Cu")
		(net 308)
	)
	(arc
		(start 185.898529 127.523632)
		(mid 186.004595 127.479698)
		(end 186.110661 127.523632)
		(width 0.09)
		(layer "In2.Cu")
		(net 308)
	)
	(arc
		(start 182.675 127.3115)
		(mid 182.781066 127.267566)
		(end 182.825 127.1615)
		(width 0.09)
		(layer "In2.Cu")
		(net 308)
	)
	(arc
		(start 180 126.25)
		(mid 180.051256 126.373744)
		(end 180.175 126.425)
		(width 0.09)
		(layer "In2.Cu")
		(net 308)
	)
	(arc
		(start 186.325 128.3)
		(mid 186.431066 128.256066)
		(end 186.475 128.15)
		(width 0.09)
		(layer "In2.Cu")
		(net 308)
	)
	(arc
		(start 180.35 126.15)
		(mid 180.401256 126.026256)
		(end 180.525 125.975)
		(width 0.09)
		(layer "In2.Cu")
		(net 308)
	)
	(arc
		(start 186.625 127.223072)
		(mid 186.731066 127.267006)
		(end 186.775 127.373072)
		(width 0.09)
		(layer "In2.Cu")
		(net 308)
	)
	(arc
		(start 185.05 127.3115)
		(mid 185.156068 127.355435)
		(end 185.262133 127.311499)
		(width 0.09)
		(layer "In2.Cu")
		(net 308)
	)
	(arc
		(start 187.375 128.15)
		(mid 187.418934 128.256066)
		(end 187.525 128.3)
		(width 0.09)
		(layer "In2.Cu")
		(net 308)
	)
	(arc
		(start 185.474263 127.523631)
		(mid 185.430329 127.629697)
		(end 185.474263 127.735763)
		(width 0.09)
		(layer "In2.Cu")
		(net 308)
	)
	(arc
		(start 183.425 126.9115)
		(mid 183.468934 126.805434)
		(end 183.575 126.7615)
		(width 0.09)
		(layer "In2.Cu")
		(net 308)
	)
	(arc
		(start 185.686397 127.099368)
		(mid 185.73033 127.205434)
		(end 185.686396 127.311501)
		(width 0.09)
		(layer "In2.Cu")
		(net 308)
	)
	(arc
		(start 184.175 126.7615)
		(mid 184.281066 126.805434)
		(end 184.325 126.9115)
		(width 0.09)
		(layer "In2.Cu")
		(net 308)
	)
	(arc
		(start 186.925 128.3)
		(mid 187.031066 128.256066)
		(end 187.075 128.15)
		(width 0.09)
		(layer "In2.Cu")
		(net 308)
	)
	(arc
		(start 180.175 126.425)
		(mid 180.298744 126.373744)
		(end 180.35 126.25)
		(width 0.09)
		(layer "In2.Cu")
		(net 308)
	)
	(arc
		(start 183.275 127.3115)
		(mid 183.381066 127.267566)
		(end 183.425 127.1615)
		(width 0.09)
		(layer "In2.Cu")
		(net 308)
	)
	(arc
		(start 182.825 126.9115)
		(mid 182.868934 126.805434)
		(end 182.975 126.7615)
		(width 0.09)
		(layer "In2.Cu")
		(net 308)
	)
	(arc
		(start 183.725 127.1615)
		(mid 183.768934 127.267566)
		(end 183.875 127.3115)
		(width 0.09)
		(layer "In2.Cu")
		(net 308)
	)
	(arc
		(start 185.474265 127.099368)
		(mid 185.580331 127.055434)
		(end 185.686397 127.099368)
		(width 0.09)
		(layer "In2.Cu")
		(net 308)
	)
	(arc
		(start 183.125 127.1615)
		(mid 183.168934 127.267566)
		(end 183.275 127.3115)
		(width 0.09)
		(layer "In2.Cu")
		(net 308)
	)
	(arc
		(start 183.575 126.7615)
		(mid 183.681066 126.805434)
		(end 183.725 126.9115)
		(width 0.09)
		(layer "In2.Cu")
		(net 308)
	)
	(arc
		(start 184.025 126.9115)
		(mid 184.068934 126.805434)
		(end 184.175 126.7615)
		(width 0.09)
		(layer "In2.Cu")
		(net 308)
	)
	(arc
		(start 186.110661 127.523632)
		(mid 186.154594 127.629698)
		(end 186.11066 127.735765)
		(width 0.09)
		(layer "In2.Cu")
		(net 308)
	)
	(arc
		(start 183.875 127.3115)
		(mid 183.981066 127.267566)
		(end 184.025 127.1615)
		(width 0.09)
		(layer "In2.Cu")
		(net 308)
	)
	(arc
		(start 186.775 128.15)
		(mid 186.818934 128.256066)
		(end 186.925 128.3)
		(width 0.09)
		(layer "In2.Cu")
		(net 308)
	)
	(arc
		(start 187.075 127.373088)
		(mid 187.118934 127.267022)
		(end 187.225 127.223088)
		(width 0.09)
		(layer "In2.Cu")
		(net 308)
	)
	(segment
		(start 183.604 126.016)
		(end 184.0035 126.3405)
		(width 0.174)
		(layer "F.Cu")
		(net 309)
	)
	(via
		(at 184.0035 126.3405)
		(size 0.35)
		(drill 0.15)
		(layers "F.Cu" "B.Cu")
		(remove_unused_layers yes)
		(keep_end_layers yes)
		(zone_layer_connections)
		(net 309)
	)
	(via
		(at 190.1 128.3)
		(size 0.35)
		(drill 0.15)
		(layers "F.Cu" "B.Cu")
		(remove_unused_layers yes)
		(keep_end_layers yes)
		(zone_layer_connections)
		(net 309)
	)
	(segment
		(start 188.93 127.66)
		(end 189.11 127.84)
		(width 0.09)
		(layer "In4.Cu")
		(net 309)
	)
	(segment
		(start 183.89 126.89)
		(end 184.22 126.89)
		(width 0.09)
		(layer "In4.Cu")
		(net 309)
	)
	(segment
		(start 185.96 127.700033)
		(end 185.96 126.99)
		(width 0.09)
		(layer "In4.Cu")
		(net 309)
	)
	(segment
		(start 189.11 127.84)
		(end 189.64 127.84)
		(width 0.09)
		(layer "In4.Cu")
		(net 309)
	)
	(segment
		(start 183.53 126.53)
		(end 183.89 126.89)
		(width 0.09)
		(layer "In4.Cu")
		(net 309)
	)
	(segment
		(start 188.93 126.99)
		(end 188.93 127.66)
		(width 0.09)
		(layer "In4.Cu")
		(net 309)
	)
	(segment
		(start 188.51 126.84)
		(end 188.78 126.84)
		(width 0.09)
		(layer "In4.Cu")
		(net 309)
	)
	(segment
		(start 187.16 127.700033)
		(end 187.16 126.99)
		(width 0.09)
		(layer "In4.Cu")
		(net 309)
	)
	(segment
		(start 185.14 126.62)
		(end 185.36 126.84)
		(width 0.09)
		(layer "In4.Cu")
		(net 309)
	)
	(segment
		(start 184.0035 126.3405)
		(end 183.763 126.1)
		(width 0.09)
		(layer "In4.Cu")
		(net 309)
	)
	(segment
		(start 184.43 126.17)
		(end 184.5795 126.0205)
		(width 0.09)
		(layer "In4.Cu")
		(net 309)
	)
	(segment
		(start 186.26 126.99)
		(end 186.26 127.700033)
		(width 0.09)
		(layer "In4.Cu")
		(net 309)
	)
	(segment
		(start 183.763 126.1)
		(end 183.62 126.1)
		(width 0.09)
		(layer "In4.Cu")
		(net 309)
	)
	(segment
		(start 185.14 126.223451)
		(end 185.14 126.62)
		(width 0.09)
		(layer "In4.Cu")
		(net 309)
	)
	(segment
		(start 187.46 126.99)
		(end 187.46 127.700033)
		(width 0.09)
		(layer "In4.Cu")
		(net 309)
	)
	(segment
		(start 188.78 126.84)
		(end 188.93 126.99)
		(width 0.09)
		(layer "In4.Cu")
		(net 309)
	)
	(segment
		(start 184.22 126.89)
		(end 184.43 126.68)
		(width 0.09)
		(layer "In4.Cu")
		(net 309)
	)
	(segment
		(start 184.5795 126.0205)
		(end 184.937049 126.0205)
		(width 0.09)
		(layer "In4.Cu")
		(net 309)
	)
	(segment
		(start 187.76 127.700033)
		(end 187.76 126.99)
		(width 0.09)
		(layer "In4.Cu")
		(net 309)
	)
	(segment
		(start 188.06 126.99)
		(end 188.06 127.700033)
		(width 0.09)
		(layer "In4.Cu")
		(net 309)
	)
	(segment
		(start 184.43 126.68)
		(end 184.43 126.17)
		(width 0.09)
		(layer "In4.Cu")
		(net 309)
	)
	(segment
		(start 186.86 126.99)
		(end 186.86 127.700033)
		(width 0.09)
		(layer "In4.Cu")
		(net 309)
	)
	(segment
		(start 183.62 126.1)
		(end 183.53 126.19)
		(width 0.09)
		(layer "In4.Cu")
		(net 309)
	)
	(segment
		(start 185.66 126.99)
		(end 185.66 127.700033)
		(width 0.09)
		(layer "In4.Cu")
		(net 309)
	)
	(segment
		(start 189.64 127.84)
		(end 190.1 128.3)
		(width 0.09)
		(layer "In4.Cu")
		(net 309)
	)
	(segment
		(start 186.56 127.700033)
		(end 186.56 126.99)
		(width 0.09)
		(layer "In4.Cu")
		(net 309)
	)
	(segment
		(start 183.53 126.19)
		(end 183.53 126.53)
		(width 0.09)
		(layer "In4.Cu")
		(net 309)
	)
	(segment
		(start 184.937049 126.0205)
		(end 185.14 126.223451)
		(width 0.09)
		(layer "In4.Cu")
		(net 309)
	)
	(segment
		(start 188.36 127.700033)
		(end 188.36 126.99)
		(width 0.09)
		(layer "In4.Cu")
		(net 309)
	)
	(segment
		(start 185.36 126.84)
		(end 185.51 126.84)
		(width 0.09)
		(layer "In4.Cu")
		(net 309)
	)
	(arc
		(start 188.06 127.700033)
		(mid 188.103934 127.806099)
		(end 188.21 127.850033)
		(width 0.09)
		(layer "In4.Cu")
		(net 309)
	)
	(arc
		(start 188.21 127.850033)
		(mid 188.316066 127.806099)
		(end 188.36 127.700033)
		(width 0.09)
		(layer "In4.Cu")
		(net 309)
	)
	(arc
		(start 186.86 127.700033)
		(mid 186.903934 127.806099)
		(end 187.01 127.850033)
		(width 0.09)
		(layer "In4.Cu")
		(net 309)
	)
	(arc
		(start 187.46 127.700033)
		(mid 187.503934 127.806099)
		(end 187.61 127.850033)
		(width 0.09)
		(layer "In4.Cu")
		(net 309)
	)
	(arc
		(start 187.31 126.84)
		(mid 187.416066 126.883934)
		(end 187.46 126.99)
		(width 0.09)
		(layer "In4.Cu")
		(net 309)
	)
	(arc
		(start 185.96 126.99)
		(mid 186.003934 126.883934)
		(end 186.11 126.84)
		(width 0.09)
		(layer "In4.Cu")
		(net 309)
	)
	(arc
		(start 185.81 127.850033)
		(mid 185.916066 127.806099)
		(end 185.96 127.700033)
		(width 0.09)
		(layer "In4.Cu")
		(net 309)
	)
	(arc
		(start 186.41 127.850033)
		(mid 186.516066 127.806099)
		(end 186.56 127.700033)
		(width 0.09)
		(layer "In4.Cu")
		(net 309)
	)
	(arc
		(start 186.56 126.99)
		(mid 186.603934 126.883934)
		(end 186.71 126.84)
		(width 0.09)
		(layer "In4.Cu")
		(net 309)
	)
	(arc
		(start 187.91 126.84)
		(mid 188.016066 126.883934)
		(end 188.06 126.99)
		(width 0.09)
		(layer "In4.Cu")
		(net 309)
	)
	(arc
		(start 188.36 126.99)
		(mid 188.403934 126.883934)
		(end 188.51 126.84)
		(width 0.09)
		(layer "In4.Cu")
		(net 309)
	)
	(arc
		(start 186.26 127.700033)
		(mid 186.303934 127.806099)
		(end 186.41 127.850033)
		(width 0.09)
		(layer "In4.Cu")
		(net 309)
	)
	(arc
		(start 185.51 126.84)
		(mid 185.616066 126.883934)
		(end 185.66 126.99)
		(width 0.09)
		(layer "In4.Cu")
		(net 309)
	)
	(arc
		(start 187.01 127.850033)
		(mid 187.116066 127.806099)
		(end 187.16 127.700033)
		(width 0.09)
		(layer "In4.Cu")
		(net 309)
	)
	(arc
		(start 185.66 127.700033)
		(mid 185.703934 127.806099)
		(end 185.81 127.850033)
		(width 0.09)
		(layer "In4.Cu")
		(net 309)
	)
	(arc
		(start 187.16 126.99)
		(mid 187.203934 126.883934)
		(end 187.31 126.84)
		(width 0.09)
		(layer "In4.Cu")
		(net 309)
	)
	(arc
		(start 186.11 126.84)
		(mid 186.216066 126.883934)
		(end 186.26 126.99)
		(width 0.09)
		(layer "In4.Cu")
		(net 309)
	)
	(arc
		(start 187.61 127.850033)
		(mid 187.716066 127.806099)
		(end 187.76 127.700033)
		(width 0.09)
		(layer "In4.Cu")
		(net 309)
	)
	(arc
		(start 187.76 126.99)
		(mid 187.803934 126.883934)
		(end 187.91 126.84)
		(width 0.09)
		(layer "In4.Cu")
		(net 309)
	)
	(arc
		(start 186.71 126.84)
		(mid 186.816066 126.883934)
		(end 186.86 126.99)
		(width 0.09)
		(layer "In4.Cu")
		(net 309)
	)
	(segment
		(start 182.805 124.066)
		(end 183.2045 123.7415)
		(width 0.174)
		(layer "F.Cu")
		(net 310)
	)
	(via
		(at 183.2045 123.7415)
		(size 0.35)
		(drill 0.15)
		(layers "F.Cu" "B.Cu")
		(remove_unused_layers yes)
		(keep_end_layers yes)
		(zone_layer_connections)
		(net 310)
	)
	(via
		(at 190.1 129.1)
		(size 0.35)
		(drill 0.15)
		(layers "F.Cu" "B.Cu")
		(remove_unused_layers yes)
		(keep_end_layers yes)
		(zone_layer_connections)
		(net 310)
	)
	(segment
		(start 182.84 123.61)
		(end 182.84 121.653553)
		(width 0.09)
		(layer "In4.Cu")
		(net 310)
	)
	(segment
		(start 182.766777 121.476777)
		(end 182.743224 121.453224)
		(width 0.09)
		(layer "In4.Cu")
		(net 310)
	)
	(segment
		(start 189.62 128.62)
		(end 190.1 129.1)
		(width 0.09)
		(layer "In4.Cu")
		(net 310)
	)
	(segment
		(start 185.1245 127.4345)
		(end 185.1245 128.1945)
		(width 0.09)
		(layer "In4.Cu")
		(net 310)
	)
	(segment
		(start 182.28 122.92)
		(end 182.28 124.37)
		(width 0.09)
		(layer "In4.Cu")
		(net 310)
	)
	(segment
		(start 181.87 125.353451)
		(end 182.79 126.273451)
		(width 0.09)
		(layer "In4.Cu")
		(net 310)
	)
	(segment
		(start 185.01 127.32)
		(end 185.1245 127.4345)
		(width 0.09)
		(layer "In4.Cu")
		(net 310)
	)
	(segment
		(start 182.13 121.87)
		(end 181.88 121.87)
		(width 0.09)
		(layer "In4.Cu")
		(net 310)
	)
	(segment
		(start 182.9715 123.7415)
		(end 182.84 123.61)
		(width 0.09)
		(layer "In4.Cu")
		(net 310)
	)
	(segment
		(start 182.79 126.54)
		(end 183.57 127.32)
		(width 0.09)
		(layer "In4.Cu")
		(net 310)
	)
	(segment
		(start 182.566447 121.38)
		(end 182.543553 121.38)
		(width 0.09)
		(layer "In4.Cu")
		(net 310)
	)
	(segment
		(start 183.57 127.32)
		(end 185.01 127.32)
		(width 0.09)
		(layer "In4.Cu")
		(net 310)
	)
	(segment
		(start 187.27 128.62)
		(end 189.62 128.62)
		(width 0.09)
		(layer "In4.Cu")
		(net 310)
	)
	(segment
		(start 182.79 126.273451)
		(end 182.79 126.54)
		(width 0.09)
		(layer "In4.Cu")
		(net 310)
	)
	(segment
		(start 183.2045 123.7415)
		(end 182.9715 123.7415)
		(width 0.09)
		(layer "In4.Cu")
		(net 310)
	)
	(segment
		(start 182.08 122.77)
		(end 182.13 122.77)
		(width 0.09)
		(layer "In4.Cu")
		(net 310)
	)
	(segment
		(start 185.1245 128.1945)
		(end 185.32 128.39)
		(width 0.09)
		(layer "In4.Cu")
		(net 310)
	)
	(segment
		(start 182.366777 121.453223)
		(end 182.353224 121.466776)
		(width 0.09)
		(layer "In4.Cu")
		(net 310)
	)
	(segment
		(start 181.87 124.78)
		(end 181.87 125.353451)
		(width 0.09)
		(layer "In4.Cu")
		(net 310)
	)
	(segment
		(start 185.32 128.39)
		(end 187.04 128.39)
		(width 0.09)
		(layer "In4.Cu")
		(net 310)
	)
	(segment
		(start 187.04 128.39)
		(end 187.27 128.62)
		(width 0.09)
		(layer "In4.Cu")
		(net 310)
	)
	(segment
		(start 182.28 124.37)
		(end 181.87 124.78)
		(width 0.09)
		(layer "In4.Cu")
		(net 310)
	)
	(segment
		(start 181.88 122.17)
		(end 182.13 122.17)
		(width 0.09)
		(layer "In4.Cu")
		(net 310)
	)
	(segment
		(start 182.28 121.643553)
		(end 182.28 121.72)
		(width 0.09)
		(layer "In4.Cu")
		(net 310)
	)
	(segment
		(start 182.13 122.47)
		(end 182.08 122.47)
		(width 0.09)
		(layer "In4.Cu")
		(net 310)
	)
	(arc
		(start 182.13 122.77)
		(mid 182.236066 122.813934)
		(end 182.28 122.92)
		(width 0.09)
		(layer "In4.Cu")
		(net 310)
	)
	(arc
		(start 182.13 122.17)
		(mid 182.236066 122.213934)
		(end 182.28 122.32)
		(width 0.09)
		(layer "In4.Cu")
		(net 310)
	)
	(arc
		(start 181.88 121.87)
		(mid 181.773934 121.913934)
		(end 181.73 122.02)
		(width 0.09)
		(layer "In4.Cu")
		(net 310)
	)
	(arc
		(start 182.28 122.32)
		(mid 182.236066 122.426066)
		(end 182.13 122.47)
		(width 0.09)
		(layer "In4.Cu")
		(net 310)
	)
	(arc
		(start 181.73 122.02)
		(mid 181.773934 122.126066)
		(end 181.88 122.17)
		(width 0.09)
		(layer "In4.Cu")
		(net 310)
	)
	(arc
		(start 182.84 121.653553)
		(mid 182.82097 121.557883)
		(end 182.766777 121.476777)
		(width 0.09)
		(layer "In4.Cu")
		(net 310)
	)
	(arc
		(start 182.353224 121.466776)
		(mid 182.299031 121.547882)
		(end 182.28 121.643553)
		(width 0.09)
		(layer "In4.Cu")
		(net 310)
	)
	(arc
		(start 182.743224 121.453224)
		(mid 182.662118 121.39903)
		(end 182.566447 121.38)
		(width 0.09)
		(layer "In4.Cu")
		(net 310)
	)
	(arc
		(start 182.28 121.72)
		(mid 182.236066 121.826066)
		(end 182.13 121.87)
		(width 0.09)
		(layer "In4.Cu")
		(net 310)
	)
	(arc
		(start 181.93 122.62)
		(mid 181.973934 122.726066)
		(end 182.08 122.77)
		(width 0.09)
		(layer "In4.Cu")
		(net 310)
	)
	(arc
		(start 182.543553 121.38)
		(mid 182.447882 121.39903)
		(end 182.366777 121.453223)
		(width 0.09)
		(layer "In4.Cu")
		(net 310)
	)
	(arc
		(start 182.08 122.47)
		(mid 181.973934 122.513934)
		(end 181.93 122.62)
		(width 0.09)
		(layer "In4.Cu")
		(net 310)
	)
	(segment
		(start 182.004 123.417)
		(end 181.6045 123.0925)
		(width 0.174)
		(layer "F.Cu")
		(net 311)
	)
	(via
		(at 190.1 129.85)
		(size 0.35)
		(drill 0.15)
		(layers "F.Cu" "B.Cu")
		(remove_unused_layers yes)
		(keep_end_layers yes)
		(zone_layer_connections)
		(net 311)
	)
	(via
		(at 181.6045 123.0925)
		(size 0.35)
		(drill 0.15)
		(layers "F.Cu" "B.Cu")
		(remove_unused_layers yes)
		(keep_end_layers yes)
		(zone_layer_connections)
		(net 311)
	)
	(segment
		(start 185.511 130.381)
		(end 189.569 130.381)
		(width 0.09)
		(layer "In4.Cu")
		(net 311)
	)
	(segment
		(start 182.7 129.84)
		(end 184.97 129.84)
		(width 0.09)
		(layer "In4.Cu")
		(net 311)
	)
	(segment
		(start 180.6275 124.7125)
		(end 180.27 125.07)
		(width 0.09)
		(layer "In4.Cu")
		(net 311)
	)
	(segment
		(start 182.02 123.508)
		(end 182.02 123.79)
		(width 0.09)
		(layer "In4.Cu")
		(net 311)
	)
	(segment
		(start 189.569 130.381)
		(end 190.1 129.85)
		(width 0.09)
		(layer "In4.Cu")
		(net 311)
	)
	(segment
		(start 181.65 129.69)
		(end 181.65 129.44)
		(width 0.09)
		(layer "In4.Cu")
		(net 311)
	)
	(segment
		(start 181.2845 124.37)
		(end 180.942 124.7125)
		(width 0.09)
		(layer "In4.Cu")
		(net 311)
	)
	(segment
		(start 180.942 124.7125)
		(end 180.6275 124.7125)
		(width 0.09)
		(layer "In4.Cu")
		(net 311)
	)
	(segment
		(start 181.6045 123.0925)
		(end 182.02 123.508)
		(width 0.09)
		(layer "In4.Cu")
		(net 311)
	)
	(segment
		(start 182.02 123.79)
		(end 181.737275 124.072725)
		(width 0.09)
		(layer "In4.Cu")
		(net 311)
	)
	(segment
		(start 181.471726 124.072725)
		(end 181.2845 124.259951)
		(width 0.09)
		(layer "In4.Cu")
		(net 311)
	)
	(segment
		(start 180.27 125.07)
		(end 180.27 128.74)
		(width 0.09)
		(layer "In4.Cu")
		(net 311)
	)
	(segment
		(start 182.25 129.69)
		(end 182.25 129.59)
		(width 0.09)
		(layer "In4.Cu")
		(net 311)
	)
	(segment
		(start 181.37 129.84)
		(end 181.5 129.84)
		(width 0.09)
		(layer "In4.Cu")
		(net 311)
	)
	(segment
		(start 182.55 129.59)
		(end 182.55 129.69)
		(width 0.09)
		(layer "In4.Cu")
		(net 311)
	)
	(segment
		(start 184.97 129.84)
		(end 185.511 130.381)
		(width 0.09)
		(layer "In4.Cu")
		(net 311)
	)
	(segment
		(start 181.2845 124.259951)
		(end 181.2845 124.37)
		(width 0.09)
		(layer "In4.Cu")
		(net 311)
	)
	(segment
		(start 181.95 129.44)
		(end 181.95 129.69)
		(width 0.09)
		(layer "In4.Cu")
		(net 311)
	)
	(segment
		(start 181.737275 124.072725)
		(end 181.471726 124.072725)
		(width 0.09)
		(layer "In4.Cu")
		(net 311)
	)
	(segment
		(start 180.27 128.74)
		(end 181.37 129.84)
		(width 0.09)
		(layer "In4.Cu")
		(net 311)
	)
	(arc
		(start 181.8 129.29)
		(mid 181.906066 129.333934)
		(end 181.95 129.44)
		(width 0.09)
		(layer "In4.Cu")
		(net 311)
	)
	(arc
		(start 181.95 129.69)
		(mid 181.993934 129.796066)
		(end 182.1 129.84)
		(width 0.09)
		(layer "In4.Cu")
		(net 311)
	)
	(arc
		(start 181.5 129.84)
		(mid 181.606066 129.796066)
		(end 181.65 129.69)
		(width 0.09)
		(layer "In4.Cu")
		(net 311)
	)
	(arc
		(start 181.65 129.44)
		(mid 181.693934 129.333934)
		(end 181.8 129.29)
		(width 0.09)
		(layer "In4.Cu")
		(net 311)
	)
	(arc
		(start 182.25 129.59)
		(mid 182.293934 129.483934)
		(end 182.4 129.44)
		(width 0.09)
		(layer "In4.Cu")
		(net 311)
	)
	(arc
		(start 182.55 129.69)
		(mid 182.593934 129.796066)
		(end 182.7 129.84)
		(width 0.09)
		(layer "In4.Cu")
		(net 311)
	)
	(arc
		(start 182.4 129.44)
		(mid 182.506066 129.483934)
		(end 182.55 129.59)
		(width 0.09)
		(layer "In4.Cu")
		(net 311)
	)
	(arc
		(start 182.1 129.84)
		(mid 182.206066 129.796066)
		(end 182.25 129.69)
		(width 0.09)
		(layer "In4.Cu")
		(net 311)
	)
	(segment
		(start 177.205 133.817)
		(end 176.8055 134.1415)
		(width 0.174)
		(layer "F.Cu")
		(net 312)
	)
	(via
		(at 176.8055 134.1415)
		(size 0.35)
		(drill 0.15)
		(layers "F.Cu" "B.Cu")
		(remove_unused_layers yes)
		(keep_end_layers yes)
		(zone_layer_connections)
		(net 312)
	)
	(via
		(at 190.1 131.501)
		(size 0.35)
		(drill 0.15)
		(layers "F.Cu" "B.Cu")
		(remove_unused_layers yes)
		(keep_end_layers yes)
		(zone_layer_connections)
		(net 312)
	)
	(segment
		(start 177.154294 134.346)
		(end 178.100294 133.4)
		(width 0.09)
		(layer "In2.Cu")
		(net 312)
	)
	(segment
		(start 187.38 134.034752)
		(end 187.38 133.4)
		(width 0.09)
		(layer "In2.Cu")
		(net 312)
	)
	(segment
		(start 189.619 132.301)
		(end 190.1 131.82)
		(width 0.09)
		(layer "In2.Cu")
		(net 312)
	)
	(segment
		(start 177.01 134.346)
		(end 177.154294 134.346)
		(width 0.09)
		(layer "In2.Cu")
		(net 312)
	)
	(segment
		(start 189.071549 132.98)
		(end 189.619 132.432549)
		(width 0.09)
		(layer "In2.Cu")
		(net 312)
	)
	(segment
		(start 188.58 134.034749)
		(end 188.58 133.4)
		(width 0.09)
		(layer "In2.Cu")
		(net 312)
	)
	(segment
		(start 176.8055 134.1415)
		(end 177.01 134.346)
		(width 0.09)
		(layer "In2.Cu")
		(net 312)
	)
	(segment
		(start 184.780294 133.4)
		(end 185.200294 132.98)
		(width 0.09)
		(layer "In2.Cu")
		(net 312)
	)
	(segment
		(start 185.82 133.4)
		(end 185.82 134.034752)
		(width 0.09)
		(layer "In2.Cu")
		(net 312)
	)
	(segment
		(start 185.200294 132.98)
		(end 185.4 132.98)
		(width 0.09)
		(layer "In2.Cu")
		(net 312)
	)
	(segment
		(start 190.1 131.82)
		(end 190.1 131.501)
		(width 0.09)
		(layer "In2.Cu")
		(net 312)
	)
	(segment
		(start 188.22 133.4)
		(end 188.22 134.034749)
		(width 0.09)
		(layer "In2.Cu")
		(net 312)
	)
	(segment
		(start 178.100294 133.4)
		(end 184.780294 133.4)
		(width 0.09)
		(layer "In2.Cu")
		(net 312)
	)
	(segment
		(start 189 132.98)
		(end 189.071549 132.98)
		(width 0.09)
		(layer "In2.Cu")
		(net 312)
	)
	(segment
		(start 187.02 133.4)
		(end 187.02 134.034752)
		(width 0.09)
		(layer "In2.Cu")
		(net 312)
	)
	(segment
		(start 189.619 132.432549)
		(end 189.619 132.301)
		(width 0.09)
		(layer "In2.Cu")
		(net 312)
	)
	(segment
		(start 186.18 134.034752)
		(end 186.18 133.4)
		(width 0.09)
		(layer "In2.Cu")
		(net 312)
	)
	(arc
		(start 188.58 133.4)
		(mid 188.703015 133.103015)
		(end 189 132.98)
		(width 0.09)
		(layer "In2.Cu")
		(net 312)
	)
	(arc
		(start 188.22 134.034749)
		(mid 188.272721 134.162028)
		(end 188.4 134.214749)
		(width 0.09)
		(layer "In2.Cu")
		(net 312)
	)
	(arc
		(start 187.8 132.98)
		(mid 188.096985 133.103015)
		(end 188.22 133.4)
		(width 0.09)
		(layer "In2.Cu")
		(net 312)
	)
	(arc
		(start 186.6 132.98)
		(mid 186.896985 133.103015)
		(end 187.02 133.4)
		(width 0.09)
		(layer "In2.Cu")
		(net 312)
	)
	(arc
		(start 186.18 133.4)
		(mid 186.303015 133.103015)
		(end 186.6 132.98)
		(width 0.09)
		(layer "In2.Cu")
		(net 312)
	)
	(arc
		(start 188.4 134.214749)
		(mid 188.527279 134.162028)
		(end 188.58 134.034749)
		(width 0.09)
		(layer "In2.Cu")
		(net 312)
	)
	(arc
		(start 187.2 134.214752)
		(mid 187.327279 134.162031)
		(end 187.38 134.034752)
		(width 0.09)
		(layer "In2.Cu")
		(net 312)
	)
	(arc
		(start 187.38 133.4)
		(mid 187.503015 133.103015)
		(end 187.8 132.98)
		(width 0.09)
		(layer "In2.Cu")
		(net 312)
	)
	(arc
		(start 185.4 132.98)
		(mid 185.696985 133.103015)
		(end 185.82 133.4)
		(width 0.09)
		(layer "In2.Cu")
		(net 312)
	)
	(arc
		(start 187.02 134.034752)
		(mid 187.072721 134.162031)
		(end 187.2 134.214752)
		(width 0.09)
		(layer "In2.Cu")
		(net 312)
	)
	(arc
		(start 186 134.214752)
		(mid 186.127279 134.162031)
		(end 186.18 134.034752)
		(width 0.09)
		(layer "In2.Cu")
		(net 312)
	)
	(arc
		(start 185.82 134.034752)
		(mid 185.872721 134.162031)
		(end 186 134.214752)
		(width 0.09)
		(layer "In2.Cu")
		(net 312)
	)
	(segment
		(start 177.205 134.466)
		(end 176.8055 134.7905)
		(width 0.174)
		(layer "F.Cu")
		(net 313)
	)
	(via
		(at 190.1 132.3)
		(size 0.35)
		(drill 0.15)
		(layers "F.Cu" "B.Cu")
		(remove_unused_layers yes)
		(keep_end_layers yes)
		(zone_layer_connections)
		(net 313)
	)
	(via
		(at 176.8055 134.7905)
		(size 0.35)
		(drill 0.15)
		(layers "F.Cu" "B.Cu")
		(remove_unused_layers yes)
		(keep_end_layers yes)
		(zone_layer_connections)
		(net 313)
	)
	(segment
		(start 189.170931 133.22)
		(end 189.229782 133.161153)
		(width 0.09)
		(layer "In2.Cu")
		(net 313)
	)
	(segment
		(start 185.4 133.22)
		(end 185.299706 133.22)
		(width 0.09)
		(layer "In2.Cu")
		(net 313)
	)
	(segment
		(start 189.795466 132.878309)
		(end 189.795465 132.878309)
		(width 0.09)
		(layer "In2.Cu")
		(net 313)
	)
	(segment
		(start 189.805046 133.170732)
		(end 189.805047 133.170732)
		(width 0.09)
		(layer "In2.Cu")
		(net 313)
	)
	(segment
		(start 187.98 134.034749)
		(end 187.98 133.4)
		(width 0.09)
		(layer "In2.Cu")
		(net 313)
	)
	(segment
		(start 186.78 134.034752)
		(end 186.78 133.4)
		(width 0.09)
		(layer "In2.Cu")
		(net 313)
	)
	(segment
		(start 185.299706 133.22)
		(end 184.879706 133.64)
		(width 0.09)
		(layer "In2.Cu")
		(net 313)
	)
	(segment
		(start 184.879706 133.64)
		(end 178.199706 133.64)
		(width 0.09)
		(layer "In2.Cu")
		(net 313)
	)
	(segment
		(start 185.58 134.034752)
		(end 185.58 133.4)
		(width 0.09)
		(layer "In2.Cu")
		(net 313)
	)
	(segment
		(start 190.090931 132.3)
		(end 189.795466 132.595465)
		(width 0.09)
		(layer "In2.Cu")
		(net 313)
	)
	(segment
		(start 188.82 133.4)
		(end 188.82 134.034749)
		(width 0.09)
		(layer "In2.Cu")
		(net 313)
	)
	(segment
		(start 189.522203 133.170735)
		(end 189.522204 133.170733)
		(width 0.09)
		(layer "In2.Cu")
		(net 313)
	)
	(segment
		(start 177.253706 134.586)
		(end 177.01 134.586)
		(width 0.09)
		(layer "In2.Cu")
		(net 313)
	)
	(segment
		(start 189.170931 133.22)
		(end 189 133.22)
		(width 0.09)
		(layer "In2.Cu")
		(net 313)
	)
	(segment
		(start 189.795465 132.878309)
		(end 189.805046 132.88789)
		(width 0.09)
		(layer "In2.Cu")
		(net 313)
	)
	(segment
		(start 178.199706 133.64)
		(end 177.253706 134.586)
		(width 0.09)
		(layer "In2.Cu")
		(net 313)
	)
	(segment
		(start 189.522204 133.170733)
		(end 189.512624 133.161153)
		(width 0.09)
		(layer "In2.Cu")
		(net 313)
	)
	(segment
		(start 190.1 132.3)
		(end 190.090931 132.3)
		(width 0.09)
		(layer "In2.Cu")
		(net 313)
	)
	(segment
		(start 186.42 133.4)
		(end 186.42 134.034752)
		(width 0.09)
		(layer "In2.Cu")
		(net 313)
	)
	(segment
		(start 177.01 134.586)
		(end 176.8055 134.7905)
		(width 0.09)
		(layer "In2.Cu")
		(net 313)
	)
	(segment
		(start 189.805047 133.170732)
		(end 189.805046 133.170734)
		(width 0.09)
		(layer "In2.Cu")
		(net 313)
	)
	(segment
		(start 187.62 133.4)
		(end 187.62 134.034752)
		(width 0.09)
		(layer "In2.Cu")
		(net 313)
	)
	(arc
		(start 186.42 134.034752)
		(mid 186.296985 134.331737)
		(end 186 134.454752)
		(width 0.09)
		(layer "In2.Cu")
		(net 313)
	)
	(arc
		(start 186.78 133.4)
		(mid 186.727279 133.272721)
		(end 186.6 133.22)
		(width 0.09)
		(layer "In2.Cu")
		(net 313)
	)
	(arc
		(start 186 134.454752)
		(mid 185.703015 134.331737)
		(end 185.58 134.034752)
		(width 0.09)
		(layer "In2.Cu")
		(net 313)
	)
	(arc
		(start 185.58 133.4)
		(mid 185.527279 133.272721)
		(end 185.4 133.22)
		(width 0.09)
		(layer "In2.Cu")
		(net 313)
	)
	(arc
		(start 189 133.22)
		(mid 188.872721 133.272721)
		(end 188.82 133.4)
		(width 0.09)
		(layer "In2.Cu")
		(net 313)
	)
	(arc
		(start 187.98 133.4)
		(mid 187.927279 133.272721)
		(end 187.8 133.22)
		(width 0.09)
		(layer "In2.Cu")
		(net 313)
	)
	(arc
		(start 189.805046 133.170734)
		(mid 189.663625 133.229313)
		(end 189.522203 133.170735)
		(width 0.09)
		(layer "In2.Cu")
		(net 313)
	)
	(arc
		(start 186.6 133.22)
		(mid 186.472721 133.272721)
		(end 186.42 133.4)
		(width 0.09)
		(layer "In2.Cu")
		(net 313)
	)
	(arc
		(start 189.805046 132.88789)
		(mid 189.863625 133.02931)
		(end 189.805046 133.170732)
		(width 0.09)
		(layer "In2.Cu")
		(net 313)
	)
	(arc
		(start 187.62 134.034752)
		(mid 187.496985 134.331737)
		(end 187.2 134.454752)
		(width 0.09)
		(layer "In2.Cu")
		(net 313)
	)
	(arc
		(start 187.2 134.454752)
		(mid 186.903015 134.331737)
		(end 186.78 134.034752)
		(width 0.09)
		(layer "In2.Cu")
		(net 313)
	)
	(arc
		(start 187.8 133.22)
		(mid 187.672721 133.272721)
		(end 187.62 133.4)
		(width 0.09)
		(layer "In2.Cu")
		(net 313)
	)
	(arc
		(start 189.512624 133.161153)
		(mid 189.371202 133.102576)
		(end 189.229782 133.161153)
		(width 0.09)
		(layer "In2.Cu")
		(net 313)
	)
	(arc
		(start 189.795466 132.595465)
		(mid 189.736886 132.736888)
		(end 189.795466 132.878309)
		(width 0.09)
		(layer "In2.Cu")
		(net 313)
	)
	(arc
		(start 188.82 134.034749)
		(mid 188.696985 134.331734)
		(end 188.4 134.454749)
		(width 0.09)
		(layer "In2.Cu")
		(net 313)
	)
	(arc
		(start 188.4 134.454749)
		(mid 188.103015 134.331734)
		(end 187.98 134.034749)
		(width 0.09)
		(layer "In2.Cu")
		(net 313)
	)
	(segment
		(start 219.07 154.74)
		(end 219.7609 154.74)
		(width 0.125)
		(layer "F.Cu")
		(net 314)
	)
	(segment
		(start 219.7609 154.74)
		(end 220.1709 155.15)
		(width 0.125)
		(layer "F.Cu")
		(net 314)
	)
	(segment
		(start 220.616 155.15)
		(end 220.8335 154.9325)
		(width 0.125)
		(layer "F.Cu")
		(net 314)
	)
	(segment
		(start 218.695 155.115)
		(end 219.07 154.74)
		(width 0.125)
		(layer "F.Cu")
		(net 314)
	)
	(segment
		(start 220.1709 155.15)
		(end 220.616 155.15)
		(width 0.125)
		(layer "F.Cu")
		(net 314)
	)
	(segment
		(start 218.69 155.115)
		(end 218.695 155.115)
		(width 0.125)
		(layer "F.Cu")
		(net 314)
	)
	(segment
		(start 220.976 154.6)
		(end 220.976 154.4)
		(width 0.125)
		(layer "F.Cu")
		(net 314)
	)
	(segment
		(start 220.8335 154.7425)
		(end 220.976 154.6)
		(width 0.125)
		(layer "F.Cu")
		(net 314)
	)
	(segment
		(start 220.8335 154.9325)
		(end 220.8335 154.7425)
		(width 0.125)
		(layer "F.Cu")
		(net 314)
	)
	(via
		(at 218.83 154.97)
		(size 0.35)
		(drill 0.15)
		(layers "F.Cu" "B.Cu")
		(remove_unused_layers yes)
		(keep_end_layers yes)
		(zone_layer_connections)
		(net 314)
	)
	(segment
		(start 220.2591 154.92)
		(end 220.526 154.92)
		(width 0.125)
		(layer "F.Cu")
		(net 315)
	)
	(segment
		(start 218.69 154.14)
		(end 219.065 154.515)
		(width 0.125)
		(layer "F.Cu")
		(net 315)
	)
	(segment
		(start 220.526 154.92)
		(end 220.6185 154.8275)
		(width 0.125)
		(layer "F.Cu")
		(net 315)
	)
	(segment
		(start 219.8541 154.515)
		(end 220.2591 154.92)
		(width 0.125)
		(layer "F.Cu")
		(net 315)
	)
	(segment
		(start 220.6185 154.8275)
		(end 220.6185 154.7425)
		(width 0.125)
		(layer "F.Cu")
		(net 315)
	)
	(segment
		(start 220.6185 154.7425)
		(end 220.476 154.6)
		(width 0.125)
		(layer "F.Cu")
		(net 315)
	)
	(segment
		(start 219.065 154.515)
		(end 219.8541 154.515)
		(width 0.125)
		(layer "F.Cu")
		(net 315)
	)
	(segment
		(start 220.49 154.6)
		(end 220.49 154.4)
		(width 0.125)
		(layer "F.Cu")
		(net 315)
	)
	(via
		(at 218.83 154.28)
		(size 0.35)
		(drill 0.15)
		(layers "F.Cu" "B.Cu")
		(remove_unused_layers yes)
		(keep_end_layers yes)
		(zone_layer_connections)
		(net 315)
	)
	(segment
		(start 178.004 124.066)
		(end 178.4035 123.7415)
		(width 0.174)
		(layer "F.Cu")
		(net 316)
	)
	(via
		(at 178.4035 123.7415)
		(size 0.35)
		(drill 0.15)
		(layers "F.Cu" "B.Cu")
		(remove_unused_layers yes)
		(keep_end_layers yes)
		(zone_layer_connections)
		(net 316)
	)
	(via
		(at 189.299 125.101)
		(size 0.35)
		(drill 0.15)
		(layers "F.Cu" "B.Cu")
		(remove_unused_layers yes)
		(keep_end_layers yes)
		(zone_layer_connections)
		(net 316)
	)
	(segment
		(start 178.7275 123.4175)
		(end 179.375 123.4175)
		(width 0.09)
		(layer "In2.Cu")
		(net 316)
	)
	(segment
		(start 185.923529 126.248528)
		(end 185.923528 126.248528)
		(width 0.09)
		(layer "In2.Cu")
		(net 316)
	)
	(segment
		(start 180.125 123.5675)
		(end 180.125 124.1675)
		(width 0.09)
		(layer "In2.Cu")
		(net 316)
	)
	(segment
		(start 182.05 125.075)
		(end 182.05 125.225)
		(width 0.09)
		(layer "In2.Cu")
		(net 316)
	)
	(segment
		(start 180.575 123.4175)
		(end 181.75 123.4175)
		(width 0.09)
		(layer "In2.Cu")
		(net 316)
	)
	(segment
		(start 178.4035 123.7415)
		(end 178.7275 123.4175)
		(width 0.09)
		(layer "In2.Cu")
		(net 316)
	)
	(segment
		(start 186.028853 125.71894)
		(end 186.028853 125.718939)
		(width 0.09)
		(layer "In2.Cu")
		(net 316)
	)
	(segment
		(start 188.5 126.65)
		(end 188.85 126.3)
		(width 0.09)
		(layer "In2.Cu")
		(net 316)
	)
	(segment
		(start 179.525 123.5675)
		(end 179.525 124.1675)
		(width 0.09)
		(layer "In2.Cu")
		(net 316)
	)
	(segment
		(start 186.028852 125.931072)
		(end 186.028853 125.931071)
		(width 0.09)
		(layer "In2.Cu")
		(net 316)
	)
	(segment
		(start 179.825 124.1675)
		(end 179.825 123.5675)
		(width 0.09)
		(layer "In2.Cu")
		(net 316)
	)
	(segment
		(start 182.05 123.7175)
		(end 182.05 123.875)
		(width 0.09)
		(layer "In2.Cu")
		(net 316)
	)
	(segment
		(start 185.499263 125.824263)
		(end 185.499264 125.824264)
		(width 0.09)
		(layer "In2.Cu")
		(net 316)
	)
	(segment
		(start 189.299 125.399)
		(end 189.299 125.101)
		(width 0.09)
		(layer "In2.Cu")
		(net 316)
	)
	(segment
		(start 182.8 124.925)
		(end 182.2 124.925)
		(width 0.09)
		(layer "In2.Cu")
		(net 316)
	)
	(segment
		(start 185.287133 125.399999)
		(end 185.287132 125.4)
		(width 0.09)
		(layer "In2.Cu")
		(net 316)
	)
	(segment
		(start 189.675 126.125)
		(end 189.675 125.775)
		(width 0.09)
		(layer "In2.Cu")
		(net 316)
	)
	(segment
		(start 185.604611 125.506786)
		(end 185.604612 125.506785)
		(width 0.09)
		(layer "In2.Cu")
		(net 316)
	)
	(segment
		(start 185.711397 125.824263)
		(end 185.711396 125.824264)
		(width 0.09)
		(layer "In2.Cu")
		(net 316)
	)
	(segment
		(start 185.604612 125.506785)
		(end 185.499263 125.612131)
		(width 0.09)
		(layer "In2.Cu")
		(net 316)
	)
	(segment
		(start 182.2 124.025)
		(end 182.75 124.025)
		(width 0.09)
		(layer "In2.Cu")
		(net 316)
	)
	(segment
		(start 182.05 125.225)
		(end 182.225 125.4)
		(width 0.09)
		(layer "In2.Cu")
		(net 316)
	)
	(segment
		(start 180.425 124.1675)
		(end 180.425 123.5675)
		(width 0.09)
		(layer "In2.Cu")
		(net 316)
	)
	(segment
		(start 188.85 126.3)
		(end 189.5 126.3)
		(width 0.09)
		(layer "In2.Cu")
		(net 316)
	)
	(segment
		(start 189.675 125.775)
		(end 189.299 125.399)
		(width 0.09)
		(layer "In2.Cu")
		(net 316)
	)
	(segment
		(start 185.923528 126.248528)
		(end 186.325 126.65)
		(width 0.09)
		(layer "In2.Cu")
		(net 316)
	)
	(segment
		(start 182.2 124.625)
		(end 182.8 124.625)
		(width 0.09)
		(layer "In2.Cu")
		(net 316)
	)
	(segment
		(start 186.028853 125.931071)
		(end 185.923529 126.036396)
		(width 0.09)
		(layer "In2.Cu")
		(net 316)
	)
	(segment
		(start 185.287132 125.4)
		(end 185.39248 125.294653)
		(width 0.09)
		(layer "In2.Cu")
		(net 316)
	)
	(segment
		(start 189.5 126.3)
		(end 189.675 126.125)
		(width 0.09)
		(layer "In2.Cu")
		(net 316)
	)
	(segment
		(start 182.225 125.4)
		(end 185.075 125.4)
		(width 0.09)
		(layer "In2.Cu")
		(net 316)
	)
	(segment
		(start 182.75 124.325)
		(end 182.2 124.325)
		(width 0.09)
		(layer "In2.Cu")
		(net 316)
	)
	(segment
		(start 185.711396 125.824264)
		(end 185.816721 125.71894)
		(width 0.09)
		(layer "In2.Cu")
		(net 316)
	)
	(segment
		(start 181.75 123.4175)
		(end 182.05 123.7175)
		(width 0.09)
		(layer "In2.Cu")
		(net 316)
	)
	(segment
		(start 186.325 126.65)
		(end 188.5 126.65)
		(width 0.09)
		(layer "In2.Cu")
		(net 316)
	)
	(arc
		(start 182.2 124.925)
		(mid 182.093934 124.968934)
		(end 182.05 125.075)
		(width 0.09)
		(layer "In2.Cu")
		(net 316)
	)
	(arc
		(start 182.75 124.025)
		(mid 182.856066 124.068934)
		(end 182.9 124.175)
		(width 0.09)
		(layer "In2.Cu")
		(net 316)
	)
	(arc
		(start 182.9 124.175)
		(mid 182.856066 124.281066)
		(end 182.75 124.325)
		(width 0.09)
		(layer "In2.Cu")
		(net 316)
	)
	(arc
		(start 179.525 124.1675)
		(mid 179.568934 124.273566)
		(end 179.675 124.3175)
		(width 0.09)
		(layer "In2.Cu")
		(net 316)
	)
	(arc
		(start 180.275 124.3175)
		(mid 180.381066 124.273566)
		(end 180.425 124.1675)
		(width 0.09)
		(layer "In2.Cu")
		(net 316)
	)
	(arc
		(start 185.923529 126.036396)
		(mid 185.879595 126.142462)
		(end 185.923529 126.248528)
		(width 0.09)
		(layer "In2.Cu")
		(net 316)
	)
	(arc
		(start 179.675 124.3175)
		(mid 179.781066 124.273566)
		(end 179.825 124.1675)
		(width 0.09)
		(layer "In2.Cu")
		(net 316)
	)
	(arc
		(start 185.816721 125.71894)
		(mid 185.922787 125.675006)
		(end 186.028853 125.71894)
		(width 0.09)
		(layer "In2.Cu")
		(net 316)
	)
	(arc
		(start 185.075 125.4)
		(mid 185.181068 125.443935)
		(end 185.287133 125.399999)
		(width 0.09)
		(layer "In2.Cu")
		(net 316)
	)
	(arc
		(start 185.499263 125.612131)
		(mid 185.455329 125.718197)
		(end 185.499263 125.824263)
		(width 0.09)
		(layer "In2.Cu")
		(net 316)
	)
	(arc
		(start 182.8 124.625)
		(mid 182.906066 124.668934)
		(end 182.95 124.775)
		(width 0.09)
		(layer "In2.Cu")
		(net 316)
	)
	(arc
		(start 185.39248 125.294653)
		(mid 185.498546 125.250719)
		(end 185.604612 125.294653)
		(width 0.09)
		(layer "In2.Cu")
		(net 316)
	)
	(arc
		(start 182.05 123.875)
		(mid 182.093934 123.981066)
		(end 182.2 124.025)
		(width 0.09)
		(layer "In2.Cu")
		(net 316)
	)
	(arc
		(start 185.499264 125.824264)
		(mid 185.605332 125.868199)
		(end 185.711397 125.824263)
		(width 0.09)
		(layer "In2.Cu")
		(net 316)
	)
	(arc
		(start 179.975 123.4175)
		(mid 180.081066 123.461434)
		(end 180.125 123.5675)
		(width 0.09)
		(layer "In2.Cu")
		(net 316)
	)
	(arc
		(start 180.125 124.1675)
		(mid 180.168934 124.273566)
		(end 180.275 124.3175)
		(width 0.09)
		(layer "In2.Cu")
		(net 316)
	)
	(arc
		(start 182.2 124.325)
		(mid 182.093934 124.368934)
		(end 182.05 124.475)
		(width 0.09)
		(layer "In2.Cu")
		(net 316)
	)
	(arc
		(start 179.375 123.4175)
		(mid 179.481066 123.461434)
		(end 179.525 123.5675)
		(width 0.09)
		(layer "In2.Cu")
		(net 316)
	)
	(arc
		(start 186.028853 125.718939)
		(mid 186.072788 125.825007)
		(end 186.028852 125.931072)
		(width 0.09)
		(layer "In2.Cu")
		(net 316)
	)
	(arc
		(start 179.825 123.5675)
		(mid 179.868934 123.461434)
		(end 179.975 123.4175)
		(width 0.09)
		(layer "In2.Cu")
		(net 316)
	)
	(arc
		(start 182.05 124.475)
		(mid 182.093934 124.581066)
		(end 182.2 124.625)
		(width 0.09)
		(layer "In2.Cu")
		(net 316)
	)
	(arc
		(start 180.425 123.5675)
		(mid 180.468934 123.461434)
		(end 180.575 123.4175)
		(width 0.09)
		(layer "In2.Cu")
		(net 316)
	)
	(arc
		(start 182.95 124.775)
		(mid 182.906066 124.881066)
		(end 182.8 124.925)
		(width 0.09)
		(layer "In2.Cu")
		(net 316)
	)
	(arc
		(start 185.604612 125.294653)
		(mid 185.648545 125.400719)
		(end 185.604611 125.506786)
		(width 0.09)
		(layer "In2.Cu")
		(net 316)
	)
	(segment
		(start 217.415 148.3)
		(end 216.804 148.3)
		(width 0.174)
		(layer "F.Cu")
		(net 317)
	)
	(segment
		(start 216.804 148.3)
		(end 216.802 148.298)
		(width 0.174)
		(layer "F.Cu")
		(net 317)
	)
	(via
		(at 217.415 148.3)
		(size 0.35)
		(drill 0.15)
		(layers "F.Cu" "B.Cu")
		(remove_unused_layers yes)
		(keep_end_layers yes)
		(zone_layer_connections)
		(net 317)
	)
	(segment
		(start 217.415 148.3)
		(end 217.13 148.3)
		(width 0.15)
		(layer "B.Cu")
		(net 317)
	)
	(segment
		(start 217.13 148.3)
		(end 216.85 148.58)
		(width 0.15)
		(layer "B.Cu")
		(net 317)
	)
	(segment
		(start 217.415 147.3)
		(end 216.802 147.3)
		(width 0.174)
		(layer "F.Cu")
		(net 318)
	)
	(via
		(at 217.415 147.3)
		(size 0.35)
		(drill 0.15)
		(layers "F.Cu" "B.Cu")
		(remove_unused_layers yes)
		(keep_end_layers yes)
		(zone_layer_connections)
		(net 318)
	)
	(segment
		(start 217.13 147.3)
		(end 217.415 147.3)
		(width 0.15)
		(layer "B.Cu")
		(net 318)
	)
	(segment
		(start 216.85 147.58)
		(end 217.13 147.3)
		(width 0.15)
		(layer "B.Cu")
		(net 318)
	)
	(segment
		(start 178.004 123.416)
		(end 178.4035 123.0915)
		(width 0.174)
		(layer "F.Cu")
		(net 319)
	)
	(via
		(at 178.4035 123.0915)
		(size 0.35)
		(drill 0.15)
		(layers "F.Cu" "B.Cu")
		(remove_unused_layers yes)
		(keep_end_layers yes)
		(zone_layer_connections)
		(net 319)
	)
	(via
		(at 189.299 125.901)
		(size 0.35)
		(drill 0.15)
		(layers "F.Cu" "B.Cu")
		(remove_unused_layers yes)
		(keep_end_layers yes)
		(zone_layer_connections)
		(net 319)
	)
	(segment
		(start 181.325 122.7665)
		(end 181.825 122.7665)
		(width 0.09)
		(layer "In2.Cu")
		(net 319)
	)
	(segment
		(start 187.425 125.35)
		(end 188.35 125.35)
		(width 0.09)
		(layer "In2.Cu")
		(net 319)
	)
	(segment
		(start 182.275 122.4165)
		(end 182.275 122.6165)
		(width 0.09)
		(layer "In2.Cu")
		(net 319)
	)
	(segment
		(start 188.375 126.15)
		(end 188.375 125.95)
		(width 0.09)
		(layer "In2.Cu")
		(net 319)
	)
	(segment
		(start 186.709923 125.984922)
		(end 186.975001 126.25)
		(width 0.09)
		(layer "In2.Cu")
		(net 319)
	)
	(segment
		(start 187.45 125.8)
		(end 187.325 125.675)
		(width 0.09)
		(layer "In2.Cu")
		(net 319)
	)
	(segment
		(start 186.975001 126.25)
		(end 188.275 126.25)
		(width 0.09)
		(layer "In2.Cu")
		(net 319)
	)
	(segment
		(start 178.4035 123.0915)
		(end 178.7285 122.7665)
		(width 0.09)
		(layer "In2.Cu")
		(net 319)
	)
	(segment
		(start 181.975 122.6165)
		(end 181.975 122.4165)
		(width 0.09)
		(layer "In2.Cu")
		(net 319)
	)
	(segment
		(start 185.719975 124.994974)
		(end 185.719974 124.994974)
		(width 0.09)
		(layer "In2.Cu")
		(net 319)
	)
	(segment
		(start 183.647724 122.593776)
		(end 183.647724 122.593775)
		(width 0.09)
		(layer "In2.Cu")
		(net 319)
	)
	(segment
		(start 183.820448 122.421051)
		(end 183.825 122.421051)
		(width 0.09)
		(layer "In2.Cu")
		(net 319)
	)
	(segment
		(start 187.325 125.45)
		(end 187.425 125.35)
		(width 0.09)
		(layer "In2.Cu")
		(net 319)
	)
	(segment
		(start 186.462435 125.489947)
		(end 186.462436 125.489949)
		(width 0.09)
		(layer "In2.Cu")
		(net 319)
	)
	(segment
		(start 185.932106 124.535354)
		(end 185.719974 124.747487)
		(width 0.09)
		(layer "In2.Cu")
		(net 319)
	)
	(segment
		(start 188.375 125.95)
		(end 188.225 125.8)
		(width 0.09)
		(layer "In2.Cu")
		(net 319)
	)
	(segment
		(start 185.932106 124.535355)
		(end 185.932106 124.535354)
		(width 0.09)
		(layer "In2.Cu")
		(net 319)
	)
	(segment
		(start 185.967461 124.994973)
		(end 185.967462 124.994975)
		(width 0.09)
		(layer "In2.Cu")
		(net 319)
	)
	(segment
		(start 188.9 125.9)
		(end 189.298 125.9)
		(width 0.09)
		(layer "In2.Cu")
		(net 319)
	)
	(segment
		(start 183.997724 122.593775)
		(end 183.997724 122.593776)
		(width 0.09)
		(layer "In2.Cu")
		(net 319)
	)
	(segment
		(start 180.575 122.4165)
		(end 180.575 122.6165)
		(width 0.09)
		(layer "In2.Cu")
		(net 319)
	)
	(segment
		(start 184.5165 122.7665)
		(end 185.225 123.475)
		(width 0.09)
		(layer "In2.Cu")
		(net 319)
	)
	(segment
		(start 183.025 122.7665)
		(end 183.475 122.7665)
		(width 0.09)
		(layer "In2.Cu")
		(net 319)
	)
	(segment
		(start 181.175 122.4165)
		(end 181.175 122.6165)
		(width 0.09)
		(layer "In2.Cu")
		(net 319)
	)
	(segment
		(start 186.922054 125.525302)
		(end 186.709922 125.737435)
		(width 0.09)
		(layer "In2.Cu")
		(net 319)
	)
	(segment
		(start 187.325 125.675)
		(end 187.325 125.45)
		(width 0.09)
		(layer "In2.Cu")
		(net 319)
	)
	(segment
		(start 186.922054 125.277816)
		(end 186.922055 125.277816)
		(width 0.09)
		(layer "In2.Cu")
		(net 319)
	)
	(segment
		(start 179.975 122.4165)
		(end 179.975 122.6165)
		(width 0.09)
		(layer "In2.Cu")
		(net 319)
	)
	(segment
		(start 184.170448 122.7665)
		(end 184.5165 122.7665)
		(width 0.09)
		(layer "In2.Cu")
		(net 319)
	)
	(segment
		(start 185.967462 124.994975)
		(end 186.179593 124.782841)
		(width 0.09)
		(layer "In2.Cu")
		(net 319)
	)
	(segment
		(start 186.214949 125.489948)
		(end 186.214948 125.489948)
		(width 0.09)
		(layer "In2.Cu")
		(net 319)
	)
	(segment
		(start 182.875 122.4165)
		(end 182.875 122.6165)
		(width 0.09)
		(layer "In2.Cu")
		(net 319)
	)
	(segment
		(start 178.7285 122.7665)
		(end 179.525 122.7665)
		(width 0.09)
		(layer "In2.Cu")
		(net 319)
	)
	(segment
		(start 180.275 122.6165)
		(end 180.275 122.4165)
		(width 0.09)
		(layer "In2.Cu")
		(net 319)
	)
	(segment
		(start 186.42708 125.030328)
		(end 186.214948 125.242461)
		(width 0.09)
		(layer "In2.Cu")
		(net 319)
	)
	(segment
		(start 186.462436 125.489949)
		(end 186.674567 125.277815)
		(width 0.09)
		(layer "In2.Cu")
		(net 319)
	)
	(segment
		(start 188.35 125.35)
		(end 188.9 125.9)
		(width 0.09)
		(layer "In2.Cu")
		(net 319)
	)
	(segment
		(start 188.225 125.8)
		(end 187.45 125.8)
		(width 0.09)
		(layer "In2.Cu")
		(net 319)
	)
	(segment
		(start 188.275 126.25)
		(end 188.375 126.15)
		(width 0.09)
		(layer "In2.Cu")
		(net 319)
	)
	(segment
		(start 186.922054 125.525303)
		(end 186.922054 125.525302)
		(width 0.09)
		(layer "In2.Cu")
		(net 319)
	)
	(segment
		(start 185.472487 124.499999)
		(end 185.472488 124.500001)
		(width 0.09)
		(layer "In2.Cu")
		(net 319)
	)
	(segment
		(start 182.575 122.6165)
		(end 182.575 122.4165)
		(width 0.09)
		(layer "In2.Cu")
		(net 319)
	)
	(segment
		(start 189.298 125.9)
		(end 189.299 125.901)
		(width 0.09)
		(layer "In2.Cu")
		(net 319)
	)
	(segment
		(start 185.225 123.475)
		(end 185.225 124.5)
		(width 0.09)
		(layer "In2.Cu")
		(net 319)
	)
	(segment
		(start 186.42708 125.030329)
		(end 186.42708 125.030328)
		(width 0.09)
		(layer "In2.Cu")
		(net 319)
	)
	(segment
		(start 179.675 122.6165)
		(end 179.675 122.4165)
		(width 0.09)
		(layer "In2.Cu")
		(net 319)
	)
	(segment
		(start 180.875 122.6165)
		(end 180.875 122.4165)
		(width 0.09)
		(layer "In2.Cu")
		(net 319)
	)
	(segment
		(start 186.42708 124.782842)
		(end 186.427081 124.782842)
		(width 0.09)
		(layer "In2.Cu")
		(net 319)
	)
	(segment
		(start 185.472488 124.500001)
		(end 185.684619 124.287867)
		(width 0.09)
		(layer "In2.Cu")
		(net 319)
	)
	(arc
		(start 186.179593 124.782841)
		(mid 186.303337 124.731585)
		(end 186.42708 124.782842)
		(width 0.09)
		(layer "In2.Cu")
		(net 319)
	)
	(arc
		(start 182.125 122.2665)
		(mid 182.231066 122.310434)
		(end 182.275 122.4165)
		(width 0.09)
		(layer "In2.Cu")
		(net 319)
	)
	(arc
		(start 186.674567 125.277815)
		(mid 186.798311 125.226559)
		(end 186.922054 125.277816)
		(width 0.09)
		(layer "In2.Cu")
		(net 319)
	)
	(arc
		(start 183.825 122.421051)
		(mid 183.947134 122.471641)
		(end 183.997724 122.593775)
		(width 0.09)
		(layer "In2.Cu")
		(net 319)
	)
	(arc
		(start 181.975 122.4165)
		(mid 182.018934 122.310434)
		(end 182.125 122.2665)
		(width 0.09)
		(layer "In2.Cu")
		(net 319)
	)
	(arc
		(start 180.275 122.4165)
		(mid 180.318934 122.310434)
		(end 180.425 122.2665)
		(width 0.09)
		(layer "In2.Cu")
		(net 319)
	)
	(arc
		(start 183.647724 122.593775)
		(mid 183.698314 122.471641)
		(end 183.820448 122.421051)
		(width 0.09)
		(layer "In2.Cu")
		(net 319)
	)
	(arc
		(start 185.719974 124.747487)
		(mid 185.668718 124.871231)
		(end 185.719975 124.994974)
		(width 0.09)
		(layer "In2.Cu")
		(net 319)
	)
	(arc
		(start 186.214948 125.489948)
		(mid 186.338692 125.541204)
		(end 186.462435 125.489947)
		(width 0.09)
		(layer "In2.Cu")
		(net 319)
	)
	(arc
		(start 179.525 122.7665)
		(mid 179.631066 122.722566)
		(end 179.675 122.6165)
		(width 0.09)
		(layer "In2.Cu")
		(net 319)
	)
	(arc
		(start 180.575 122.6165)
		(mid 180.618934 122.722566)
		(end 180.725 122.7665)
		(width 0.09)
		(layer "In2.Cu")
		(net 319)
	)
	(arc
		(start 186.214948 125.242461)
		(mid 186.163692 125.366205)
		(end 186.214949 125.489948)
		(width 0.09)
		(layer "In2.Cu")
		(net 319)
	)
	(arc
		(start 186.922055 125.277816)
		(mid 186.973311 125.40156)
		(end 186.922054 125.525303)
		(width 0.09)
		(layer "In2.Cu")
		(net 319)
	)
	(arc
		(start 180.875 122.4165)
		(mid 180.918934 122.310434)
		(end 181.025 122.2665)
		(width 0.09)
		(layer "In2.Cu")
		(net 319)
	)
	(arc
		(start 186.709922 125.737435)
		(mid 186.658666 125.861179)
		(end 186.709923 125.984922)
		(width 0.09)
		(layer "In2.Cu")
		(net 319)
	)
	(arc
		(start 179.825 122.2665)
		(mid 179.931066 122.310434)
		(end 179.975 122.4165)
		(width 0.09)
		(layer "In2.Cu")
		(net 319)
	)
	(arc
		(start 183.997724 122.593776)
		(mid 184.048314 122.71591)
		(end 184.170448 122.7665)
		(width 0.09)
		(layer "In2.Cu")
		(net 319)
	)
	(arc
		(start 182.875 122.6165)
		(mid 182.918934 122.722566)
		(end 183.025 122.7665)
		(width 0.09)
		(layer "In2.Cu")
		(net 319)
	)
	(arc
		(start 180.725 122.7665)
		(mid 180.831066 122.722566)
		(end 180.875 122.6165)
		(width 0.09)
		(layer "In2.Cu")
		(net 319)
	)
	(arc
		(start 182.575 122.4165)
		(mid 182.618934 122.310434)
		(end 182.725 122.2665)
		(width 0.09)
		(layer "In2.Cu")
		(net 319)
	)
	(arc
		(start 180.425 122.2665)
		(mid 180.531066 122.310434)
		(end 180.575 122.4165)
		(width 0.09)
		(layer "In2.Cu")
		(net 319)
	)
	(arc
		(start 181.175 122.6165)
		(mid 181.218934 122.722566)
		(end 181.325 122.7665)
		(width 0.09)
		(layer "In2.Cu")
		(net 319)
	)
	(arc
		(start 180.125 122.7665)
		(mid 180.231066 122.722566)
		(end 180.275 122.6165)
		(width 0.09)
		(layer "In2.Cu")
		(net 319)
	)
	(arc
		(start 181.025 122.2665)
		(mid 181.131066 122.310434)
		(end 181.175 122.4165)
		(width 0.09)
		(layer "In2.Cu")
		(net 319)
	)
	(arc
		(start 185.932107 124.287868)
		(mid 185.983363 124.411612)
		(end 185.932106 124.535355)
		(width 0.09)
		(layer "In2.Cu")
		(net 319)
	)
	(arc
		(start 182.425 122.7665)
		(mid 182.531066 122.722566)
		(end 182.575 122.6165)
		(width 0.09)
		(layer "In2.Cu")
		(net 319)
	)
	(arc
		(start 182.275 122.6165)
		(mid 182.318934 122.722566)
		(end 182.425 122.7665)
		(width 0.09)
		(layer "In2.Cu")
		(net 319)
	)
	(arc
		(start 181.825 122.7665)
		(mid 181.931066 122.722566)
		(end 181.975 122.6165)
		(width 0.09)
		(layer "In2.Cu")
		(net 319)
	)
	(arc
		(start 185.225 124.5)
		(mid 185.348744 124.551256)
		(end 185.472487 124.499999)
		(width 0.09)
		(layer "In2.Cu")
		(net 319)
	)
	(arc
		(start 183.475 122.7665)
		(mid 183.597134 122.71591)
		(end 183.647724 122.593776)
		(width 0.09)
		(layer "In2.Cu")
		(net 319)
	)
	(arc
		(start 185.719974 124.994974)
		(mid 185.843718 125.04623)
		(end 185.967461 124.994973)
		(width 0.09)
		(layer "In2.Cu")
		(net 319)
	)
	(arc
		(start 179.675 122.4165)
		(mid 179.718934 122.310434)
		(end 179.825 122.2665)
		(width 0.09)
		(layer "In2.Cu")
		(net 319)
	)
	(arc
		(start 185.684619 124.287867)
		(mid 185.808363 124.236611)
		(end 185.932106 124.287868)
		(width 0.09)
		(layer "In2.Cu")
		(net 319)
	)
	(arc
		(start 186.427081 124.782842)
		(mid 186.478337 124.906586)
		(end 186.42708 125.030329)
		(width 0.09)
		(layer "In2.Cu")
		(net 319)
	)
	(arc
		(start 179.975 122.6165)
		(mid 180.018934 122.722566)
		(end 180.125 122.7665)
		(width 0.09)
		(layer "In2.Cu")
		(net 319)
	)
	(arc
		(start 182.725 122.2665)
		(mid 182.831066 122.310434)
		(end 182.875 122.4165)
		(width 0.09)
		(layer "In2.Cu")
		(net 319)
	)
	(segment
		(start 177.205 124.066)
		(end 176.8055 123.7415)
		(width 0.174)
		(layer "F.Cu")
		(net 320)
	)
	(via
		(at 189.299 126.701)
		(size 0.35)
		(drill 0.15)
		(layers "F.Cu" "B.Cu")
		(remove_unused_layers yes)
		(keep_end_layers yes)
		(zone_layer_connections)
		(net 320)
	)
	(via
		(at 176.8055 123.7415)
		(size 0.35)
		(drill 0.15)
		(layers "F.Cu" "B.Cu")
		(remove_unused_layers yes)
		(keep_end_layers yes)
		(zone_layer_connections)
		(net 320)
	)
	(segment
		(start 180.575 125.675)
		(end 182.15 125.675)
		(width 0.09)
		(layer "In2.Cu")
		(net 320)
	)
	(segment
		(start 176.4805 124.0665)
		(end 176.4805 125.17712)
		(width 0.09)
		(layer "In2.Cu")
		(net 320)
	)
	(segment
		(start 176.8055 123.7415)
		(end 176.4805 124.0665)
		(width 0.09)
		(layer "In2.Cu")
		(net 320)
	)
	(segment
		(start 186.077069 126.975)
		(end 187.5 126.975)
		(width 0.09)
		(layer "In2.Cu")
		(net 320)
	)
	(segment
		(start 182.9 125.675)
		(end 182.95 125.675)
		(width 0.09)
		(layer "In2.Cu")
		(net 320)
	)
	(segment
		(start 179.175 125.675)
		(end 179.375 125.675)
		(width 0.09)
		(layer "In2.Cu")
		(net 320)
	)
	(segment
		(start 178.1825 124.7175)
		(end 178.675 124.7175)
		(width 0.09)
		(layer "In2.Cu")
		(net 320)
	)
	(segment
		(start 180.425 124.68922)
		(end 180.425 125.525)
		(width 0.09)
		(layer "In2.Cu")
		(net 320)
	)
	(segment
		(start 185.402811 126.795715)
		(end 185.508876 126.689649)
		(width 0.09)
		(layer "In2.Cu")
		(net 320)
	)
	(segment
		(start 180.125 125.525)
		(end 180.125 124.68922)
		(width 0.09)
		(layer "In2.Cu")
		(net 320)
	)
	(segment
		(start 176.4805 125.17712)
		(end 176.67088 125.3675)
		(width 0.09)
		(layer "In2.Cu")
		(net 320)
	)
	(segment
		(start 179.825 124.689237)
		(end 179.825 125.525)
		(width 0.09)
		(layer "In2.Cu")
		(net 320)
	)
	(segment
		(start 178.85 124.8925)
		(end 178.85 125.35)
		(width 0.09)
		(layer "In2.Cu")
		(net 320)
	)
	(segment
		(start 188.175 127.5)
		(end 188.175 127.2)
		(width 0.09)
		(layer "In2.Cu")
		(net 320)
	)
	(segment
		(start 188.949 126.701)
		(end 189.299 126.701)
		(width 0.09)
		(layer "In2.Cu")
		(net 320)
	)
	(segment
		(start 185.791719 126.68965)
		(end 186.077069 126.975)
		(width 0.09)
		(layer "In2.Cu")
		(net 320)
	)
	(segment
		(start 187.725 127.2)
		(end 187.725 127.5)
		(width 0.09)
		(layer "In2.Cu")
		(net 320)
	)
	(segment
		(start 184.5 125.675)
		(end 184.777069 125.675)
		(width 0.09)
		(layer "In2.Cu")
		(net 320)
	)
	(segment
		(start 177.5325 125.3675)
		(end 178.1825 124.7175)
		(width 0.09)
		(layer "In2.Cu")
		(net 320)
	)
	(segment
		(start 183.7 125.675)
		(end 183.75 125.675)
		(width 0.09)
		(layer "In2.Cu")
		(net 320)
	)
	(segment
		(start 178.675 124.7175)
		(end 178.85 124.8925)
		(width 0.09)
		(layer "In2.Cu")
		(net 320)
	)
	(segment
		(start 188.675 126.975)
		(end 188.949 126.701)
		(width 0.09)
		(layer "In2.Cu")
		(net 320)
	)
	(segment
		(start 183.3 126.025)
		(end 183.35 126.025)
		(width 0.09)
		(layer "In2.Cu")
		(net 320)
	)
	(segment
		(start 184.777069 125.675)
		(end 185.226035 126.123966)
		(width 0.09)
		(layer "In2.Cu")
		(net 320)
	)
	(segment
		(start 178.85 125.35)
		(end 179.175 125.675)
		(width 0.09)
		(layer "In2.Cu")
		(net 320)
	)
	(segment
		(start 185.226034 126.406809)
		(end 185.119968 126.512874)
		(width 0.09)
		(layer "In2.Cu")
		(net 320)
	)
	(segment
		(start 179.525 125.525)
		(end 179.525 124.689237)
		(width 0.09)
		(layer "In2.Cu")
		(net 320)
	)
	(segment
		(start 185.119969 126.795717)
		(end 185.119968 126.795716)
		(width 0.09)
		(layer "In2.Cu")
		(net 320)
	)
	(segment
		(start 182.5 126.025)
		(end 182.55 126.025)
		(width 0.09)
		(layer "In2.Cu")
		(net 320)
	)
	(segment
		(start 176.67088 125.3675)
		(end 177.5325 125.3675)
		(width 0.09)
		(layer "In2.Cu")
		(net 320)
	)
	(segment
		(start 188.4 126.975)
		(end 188.675 126.975)
		(width 0.09)
		(layer "In2.Cu")
		(net 320)
	)
	(segment
		(start 184.1 126.025)
		(end 184.15 126.025)
		(width 0.09)
		(layer "In2.Cu")
		(net 320)
	)
	(arc
		(start 183.125 125.85)
		(mid 183.176256 125.973744)
		(end 183.3 126.025)
		(width 0.09)
		(layer "In2.Cu")
		(net 320)
	)
	(arc
		(start 182.55 126.025)
		(mid 182.673744 125.973744)
		(end 182.725 125.85)
		(width 0.09)
		(layer "In2.Cu")
		(net 320)
	)
	(arc
		(start 180.125 124.68922)
		(mid 180.168934 124.583154)
		(end 180.275 124.53922)
		(width 0.09)
		(layer "In2.Cu")
		(net 320)
	)
	(arc
		(start 187.725 127.5)
		(mid 187.790901 127.659099)
		(end 187.95 127.725)
		(width 0.09)
		(layer "In2.Cu")
		(net 320)
	)
	(arc
		(start 179.675 124.539237)
		(mid 179.781066 124.583171)
		(end 179.825 124.689237)
		(width 0.09)
		(layer "In2.Cu")
		(net 320)
	)
	(arc
		(start 187.95 127.725)
		(mid 188.109099 127.659099)
		(end 188.175 127.5)
		(width 0.09)
		(layer "In2.Cu")
		(net 320)
	)
	(arc
		(start 180.275 124.53922)
		(mid 180.381066 124.583154)
		(end 180.425 124.68922)
		(width 0.09)
		(layer "In2.Cu")
		(net 320)
	)
	(arc
		(start 188.175 127.2)
		(mid 188.240901 127.040901)
		(end 188.4 126.975)
		(width 0.09)
		(layer "In2.Cu")
		(net 320)
	)
	(arc
		(start 185.226035 126.123966)
		(mid 185.284613 126.265388)
		(end 185.226034 126.406809)
		(width 0.09)
		(layer "In2.Cu")
		(net 320)
	)
	(arc
		(start 182.325 125.85)
		(mid 182.376256 125.973744)
		(end 182.5 126.025)
		(width 0.09)
		(layer "In2.Cu")
		(net 320)
	)
	(arc
		(start 179.375 125.675)
		(mid 179.481066 125.631066)
		(end 179.525 125.525)
		(width 0.09)
		(layer "In2.Cu")
		(net 320)
	)
	(arc
		(start 183.35 126.025)
		(mid 183.473744 125.973744)
		(end 183.525 125.85)
		(width 0.09)
		(layer "In2.Cu")
		(net 320)
	)
	(arc
		(start 183.925 125.85)
		(mid 183.976256 125.973744)
		(end 184.1 126.025)
		(width 0.09)
		(layer "In2.Cu")
		(net 320)
	)
	(arc
		(start 183.75 125.675)
		(mid 183.873744 125.726256)
		(end 183.925 125.85)
		(width 0.09)
		(layer "In2.Cu")
		(net 320)
	)
	(arc
		(start 185.508876 126.689649)
		(mid 185.650298 126.631071)
		(end 185.791719 126.68965)
		(width 0.09)
		(layer "In2.Cu")
		(net 320)
	)
	(arc
		(start 182.725 125.85)
		(mid 182.776256 125.726256)
		(end 182.9 125.675)
		(width 0.09)
		(layer "In2.Cu")
		(net 320)
	)
	(arc
		(start 182.95 125.675)
		(mid 183.073744 125.726256)
		(end 183.125 125.85)
		(width 0.09)
		(layer "In2.Cu")
		(net 320)
	)
	(arc
		(start 187.5 126.975)
		(mid 187.659099 127.040901)
		(end 187.725 127.2)
		(width 0.09)
		(layer "In2.Cu")
		(net 320)
	)
	(arc
		(start 180.425 125.525)
		(mid 180.468934 125.631066)
		(end 180.575 125.675)
		(width 0.09)
		(layer "In2.Cu")
		(net 320)
	)
	(arc
		(start 179.975 125.675)
		(mid 180.081066 125.631066)
		(end 180.125 125.525)
		(width 0.09)
		(layer "In2.Cu")
		(net 320)
	)
	(arc
		(start 179.525 124.689237)
		(mid 179.568934 124.583171)
		(end 179.675 124.539237)
		(width 0.09)
		(layer "In2.Cu")
		(net 320)
	)
	(arc
		(start 179.825 125.525)
		(mid 179.868934 125.631066)
		(end 179.975 125.675)
		(width 0.09)
		(layer "In2.Cu")
		(net 320)
	)
	(arc
		(start 183.525 125.85)
		(mid 183.576256 125.726256)
		(end 183.7 125.675)
		(width 0.09)
		(layer "In2.Cu")
		(net 320)
	)
	(arc
		(start 182.15 125.675)
		(mid 182.273744 125.726256)
		(end 182.325 125.85)
		(width 0.09)
		(layer "In2.Cu")
		(net 320)
	)
	(arc
		(start 184.325 125.85)
		(mid 184.376256 125.726256)
		(end 184.5 125.675)
		(width 0.09)
		(layer "In2.Cu")
		(net 320)
	)
	(arc
		(start 185.119968 126.795716)
		(mid 185.26139 126.854294)
		(end 185.402811 126.795715)
		(width 0.09)
		(layer "In2.Cu")
		(net 320)
	)
	(arc
		(start 185.119968 126.512874)
		(mid 185.06139 126.654296)
		(end 185.119969 126.795717)
		(width 0.09)
		(layer "In2.Cu")
		(net 320)
	)
	(arc
		(start 184.15 126.025)
		(mid 184.273744 125.973744)
		(end 184.325 125.85)
		(width 0.09)
		(layer "In2.Cu")
		(net 320)
	)
	(segment
		(start 183.604 125.367)
		(end 184.0035 125.0425)
		(width 0.174)
		(layer "F.Cu")
		(net 321)
	)
	(via
		(at 184.0035 125.0425)
		(size 0.35)
		(drill 0.15)
		(layers "F.Cu" "B.Cu")
		(remove_unused_layers yes)
		(keep_end_layers yes)
		(zone_layer_connections)
		(net 321)
	)
	(via
		(at 189.299 127.5)
		(size 0.35)
		(drill 0.15)
		(layers "F.Cu" "B.Cu")
		(remove_unused_layers yes)
		(keep_end_layers yes)
		(zone_layer_connections)
		(net 321)
	)
	(segment
		(start 188.07 124.27045)
		(end 188.07 124.5625)
		(width 0.09)
		(layer "In4.Cu")
		(net 321)
	)
	(segment
		(start 187.77 124.5625)
		(end 187.77 124.27045)
		(width 0.09)
		(layer "In4.Cu")
		(net 321)
	)
	(segment
		(start 190.767451 128.62)
		(end 190.58 128.432549)
		(width 0.09)
		(layer "In4.Cu")
		(net 321)
	)
	(segment
		(start 186.57 124.5625)
		(end 186.57 124.270444)
		(width 0.09)
		(layer "In4.Cu")
		(net 321)
	)
	(segment
		(start 189.63 124.979451)
		(end 189.63 125.1)
		(width 0.09)
		(layer "In4.Cu")
		(net 321)
	)
	(segment
		(start 185.97 124.5625)
		(end 185.97 124.270444)
		(width 0.09)
		(layer "In4.Cu")
		(net 321)
	)
	(segment
		(start 190.58 128.432549)
		(end 190.58 128.31)
		(width 0.09)
		(layer "In4.Cu")
		(net 321)
	)
	(segment
		(start 186.87 124.270444)
		(end 186.87 124.5625)
		(width 0.09)
		(layer "In4.Cu")
		(net 321)
	)
	(segment
		(start 190.767451 126.221)
		(end 191.031 126.221)
		(width 0.09)
		(layer "In4.Cu")
		(net 321)
	)
	(segment
		(start 188.22 124.7125)
		(end 189.363049 124.7125)
		(width 0.09)
		(layer "In4.Cu")
		(net 321)
	)
	(segment
		(start 191.031 126.221)
		(end 192.16 127.35)
		(width 0.09)
		(layer "In4.Cu")
		(net 321)
	)
	(segment
		(start 192.16 127.35)
		(end 192.16 128.292549)
		(width 0.09)
		(layer "In4.Cu")
		(net 321)
	)
	(segment
		(start 184.3335 124.7125)
		(end 185.22 124.7125)
		(width 0.09)
		(layer "In4.Cu")
		(net 321)
	)
	(segment
		(start 190.097198 127.98)
		(end 189.617198 127.5)
		(width 0.09)
		(layer "In4.Cu")
		(net 321)
	)
	(segment
		(start 189.63 125.1)
		(end 190.111 125.581)
		(width 0.09)
		(layer "In4.Cu")
		(net 321)
	)
	(segment
		(start 186.27 124.270444)
		(end 186.27 124.5625)
		(width 0.09)
		(layer "In4.Cu")
		(net 321)
	)
	(segment
		(start 190.301 125.581)
		(end 190.55 125.83)
		(width 0.09)
		(layer "In4.Cu")
		(net 321)
	)
	(segment
		(start 185.67 124.270444)
		(end 185.67 124.5625)
		(width 0.09)
		(layer "In4.Cu")
		(net 321)
	)
	(segment
		(start 185.37 124.5625)
		(end 185.37 124.270444)
		(width 0.09)
		(layer "In4.Cu")
		(net 321)
	)
	(segment
		(start 190.25 127.98)
		(end 190.097198 127.98)
		(width 0.09)
		(layer "In4.Cu")
		(net 321)
	)
	(segment
		(start 192.16 128.292549)
		(end 191.832549 128.62)
		(width 0.09)
		(layer "In4.Cu")
		(net 321)
	)
	(segment
		(start 191.832549 128.62)
		(end 190.767451 128.62)
		(width 0.09)
		(layer "In4.Cu")
		(net 321)
	)
	(segment
		(start 190.111 125.581)
		(end 190.301 125.581)
		(width 0.09)
		(layer "In4.Cu")
		(net 321)
	)
	(segment
		(start 190.55 125.83)
		(end 190.55 126.003549)
		(width 0.09)
		(layer "In4.Cu")
		(net 321)
	)
	(segment
		(start 184.0035 125.0425)
		(end 184.3335 124.7125)
		(width 0.09)
		(layer "In4.Cu")
		(net 321)
	)
	(segment
		(start 189.617198 127.5)
		(end 189.299 127.5)
		(width 0.09)
		(layer "In4.Cu")
		(net 321)
	)
	(segment
		(start 190.58 128.31)
		(end 190.25 127.98)
		(width 0.09)
		(layer "In4.Cu")
		(net 321)
	)
	(segment
		(start 189.363049 124.7125)
		(end 189.63 124.979451)
		(width 0.09)
		(layer "In4.Cu")
		(net 321)
	)
	(segment
		(start 187.17 124.5625)
		(end 187.17 124.270448)
		(width 0.09)
		(layer "In4.Cu")
		(net 321)
	)
	(segment
		(start 187.47 124.270448)
		(end 187.47 124.5625)
		(width 0.09)
		(layer "In4.Cu")
		(net 321)
	)
	(segment
		(start 190.55 126.003549)
		(end 190.767451 126.221)
		(width 0.09)
		(layer "In4.Cu")
		(net 321)
	)
	(arc
		(start 186.42 124.7125)
		(mid 186.526066 124.668566)
		(end 186.57 124.5625)
		(width 0.09)
		(layer "In4.Cu")
		(net 321)
	)
	(arc
		(start 185.37 124.270444)
		(mid 185.413934 124.164378)
		(end 185.52 124.120444)
		(width 0.09)
		(layer "In4.Cu")
		(net 321)
	)
	(arc
		(start 185.52 124.120444)
		(mid 185.626066 124.164378)
		(end 185.67 124.270444)
		(width 0.09)
		(layer "In4.Cu")
		(net 321)
	)
	(arc
		(start 187.47 124.5625)
		(mid 187.513934 124.668566)
		(end 187.62 124.7125)
		(width 0.09)
		(layer "In4.Cu")
		(net 321)
	)
	(arc
		(start 188.07 124.5625)
		(mid 188.113934 124.668566)
		(end 188.22 124.7125)
		(width 0.09)
		(layer "In4.Cu")
		(net 321)
	)
	(arc
		(start 187.92 124.12045)
		(mid 188.026066 124.164384)
		(end 188.07 124.27045)
		(width 0.09)
		(layer "In4.Cu")
		(net 321)
	)
	(arc
		(start 186.27 124.5625)
		(mid 186.313934 124.668566)
		(end 186.42 124.7125)
		(width 0.09)
		(layer "In4.Cu")
		(net 321)
	)
	(arc
		(start 187.62 124.7125)
		(mid 187.726066 124.668566)
		(end 187.77 124.5625)
		(width 0.09)
		(layer "In4.Cu")
		(net 321)
	)
	(arc
		(start 187.32 124.120448)
		(mid 187.426066 124.164382)
		(end 187.47 124.270448)
		(width 0.09)
		(layer "In4.Cu")
		(net 321)
	)
	(arc
		(start 187.17 124.270448)
		(mid 187.213934 124.164382)
		(end 187.32 124.120448)
		(width 0.09)
		(layer "In4.Cu")
		(net 321)
	)
	(arc
		(start 187.02 124.7125)
		(mid 187.126066 124.668566)
		(end 187.17 124.5625)
		(width 0.09)
		(layer "In4.Cu")
		(net 321)
	)
	(arc
		(start 185.82 124.7125)
		(mid 185.926066 124.668566)
		(end 185.97 124.5625)
		(width 0.09)
		(layer "In4.Cu")
		(net 321)
	)
	(arc
		(start 185.67 124.5625)
		(mid 185.713934 124.668566)
		(end 185.82 124.7125)
		(width 0.09)
		(layer "In4.Cu")
		(net 321)
	)
	(arc
		(start 186.12 124.120444)
		(mid 186.226066 124.164378)
		(end 186.27 124.270444)
		(width 0.09)
		(layer "In4.Cu")
		(net 321)
	)
	(arc
		(start 185.97 124.270444)
		(mid 186.013934 124.164378)
		(end 186.12 124.120444)
		(width 0.09)
		(layer "In4.Cu")
		(net 321)
	)
	(arc
		(start 187.77 124.27045)
		(mid 187.813934 124.164384)
		(end 187.92 124.12045)
		(width 0.09)
		(layer "In4.Cu")
		(net 321)
	)
	(arc
		(start 186.72 124.120444)
		(mid 186.826066 124.164378)
		(end 186.87 124.270444)
		(width 0.09)
		(layer "In4.Cu")
		(net 321)
	)
	(arc
		(start 185.22 124.7125)
		(mid 185.326066 124.668566)
		(end 185.37 124.5625)
		(width 0.09)
		(layer "In4.Cu")
		(net 321)
	)
	(arc
		(start 186.57 124.270444)
		(mid 186.613934 124.164378)
		(end 186.72 124.120444)
		(width 0.09)
		(layer "In4.Cu")
		(net 321)
	)
	(arc
		(start 186.87 124.5625)
		(mid 186.913934 124.668566)
		(end 187.02 124.7125)
		(width 0.09)
		(layer "In4.Cu")
		(net 321)
	)
	(segment
		(start 182.004 126.016)
		(end 181.6045 126.3405)
		(width 0.174)
		(layer "F.Cu")
		(net 322)
	)
	(via
		(at 181.6045 126.3405)
		(size 0.35)
		(drill 0.15)
		(layers "F.Cu" "B.Cu")
		(remove_unused_layers yes)
		(keep_end_layers yes)
		(zone_layer_connections)
		(net 322)
	)
	(via
		(at 189.299 129.1)
		(size 0.35)
		(drill 0.15)
		(layers "F.Cu" "B.Cu")
		(remove_unused_layers yes)
		(keep_end_layers yes)
		(zone_layer_connections)
		(net 322)
	)
	(segment
		(start 187.89 128.9615)
		(end 187.89 129.1115)
		(width 0.09)
		(layer "In4.Cu")
		(net 322)
	)
	(segment
		(start 184.39 128.979549)
		(end 184.39 128.16)
		(width 0.09)
		(layer "In4.Cu")
		(net 322)
	)
	(segment
		(start 189.1375 129.2615)
		(end 188.94 129.2615)
		(width 0.09)
		(layer "In4.Cu")
		(net 322)
	)
	(segment
		(start 181.992385 125.942385)
		(end 181.76 125.71)
		(width 0.09)
		(layer "In4.Cu")
		(net 322)
	)
	(segment
		(start 182.443907 127.570355)
		(end 182.408552 127.535)
		(width 0.09)
		(layer "In4.Cu")
		(net 322)
	)
	(segment
		(start 182.4915 127.9715)
		(end 182.443908 127.923909)
		(width 0.09)
		(layer "In4.Cu")
		(net 322)
	)
	(segment
		(start 184.671951 129.2615)
		(end 185.34 129.2615)
		(width 0.09)
		(layer "In4.Cu")
		(net 322)
	)
	(segment
		(start 184.671951 129.2615)
		(end 184.39 128.979549)
		(width 0.09)
		(layer "In4.Cu")
		(net 322)
	)
	(segment
		(start 181.992385 126.806874)
		(end 181.992385 125.942385)
		(width 0.09)
		(layer "In4.Cu")
		(net 322)
	)
	(segment
		(start 182.055 127.535)
		(end 181.99 127.47)
		(width 0.09)
		(layer "In4.Cu")
		(net 322)
	)
	(segment
		(start 186.69 128.791311)
		(end 186.69 129.1115)
		(width 0.09)
		(layer "In4.Cu")
		(net 322)
	)
	(segment
		(start 184.2015 127.9715)
		(end 182.4915 127.9715)
		(width 0.09)
		(layer "In4.Cu")
		(net 322)
	)
	(segment
		(start 187.59 129.1115)
		(end 187.59 128.9615)
		(width 0.09)
		(layer "In4.Cu")
		(net 322)
	)
	(segment
		(start 186.99 129.1115)
		(end 186.99 128.791311)
		(width 0.09)
		(layer "In4.Cu")
		(net 322)
	)
	(segment
		(start 189.299 129.1)
		(end 189.1375 129.2615)
		(width 0.09)
		(layer "In4.Cu")
		(net 322)
	)
	(segment
		(start 187.29 128.9615)
		(end 187.29 129.1115)
		(width 0.09)
		(layer "In4.Cu")
		(net 322)
	)
	(segment
		(start 181.6045 126.1145)
		(end 181.6045 126.3405)
		(width 0.09)
		(layer "In4.Cu")
		(net 322)
	)
	(segment
		(start 185.79 129.1115)
		(end 185.79 128.791311)
		(width 0.09)
		(layer "In4.Cu")
		(net 322)
	)
	(segment
		(start 188.19 129.1115)
		(end 188.19 128.9615)
		(width 0.09)
		(layer "In4.Cu")
		(net 322)
	)
	(segment
		(start 182.231776 127.535)
		(end 182.231777 127.534999)
		(width 0.09)
		(layer "In4.Cu")
		(net 322)
	)
	(segment
		(start 181.44 125.79)
		(end 181.44 125.95)
		(width 0.09)
		(layer "In4.Cu")
		(net 322)
	)
	(segment
		(start 181.52 125.71)
		(end 181.44 125.79)
		(width 0.09)
		(layer "In4.Cu")
		(net 322)
	)
	(segment
		(start 181.44 125.95)
		(end 181.6045 126.1145)
		(width 0.09)
		(layer "In4.Cu")
		(net 322)
	)
	(segment
		(start 186.39 129.1115)
		(end 186.39 128.791311)
		(width 0.09)
		(layer "In4.Cu")
		(net 322)
	)
	(segment
		(start 188.49 128.9615)
		(end 188.49 129.1115)
		(width 0.09)
		(layer "In4.Cu")
		(net 322)
	)
	(segment
		(start 182.8 126.91)
		(end 182.13 126.91)
		(width 0.09)
		(layer "In4.Cu")
		(net 322)
	)
	(segment
		(start 186.09 128.791311)
		(end 186.09 129.1115)
		(width 0.09)
		(layer "In4.Cu")
		(net 322)
	)
	(segment
		(start 181.99 127.47)
		(end 181.99 127.33)
		(width 0.09)
		(layer "In4.Cu")
		(net 322)
	)
	(segment
		(start 181.76 125.71)
		(end 181.52 125.71)
		(width 0.09)
		(layer "In4.Cu")
		(net 322)
	)
	(segment
		(start 182.13 127.19)
		(end 182.8 127.19)
		(width 0.09)
		(layer "In4.Cu")
		(net 322)
	)
	(segment
		(start 182.443908 127.747133)
		(end 182.443906 127.747132)
		(width 0.09)
		(layer "In4.Cu")
		(net 322)
	)
	(segment
		(start 185.49 128.791311)
		(end 185.49 129.1115)
		(width 0.09)
		(layer "In4.Cu")
		(net 322)
	)
	(segment
		(start 188.79 129.1115)
		(end 188.79 128.9615)
		(width 0.09)
		(layer "In4.Cu")
		(net 322)
	)
	(segment
		(start 184.39 128.16)
		(end 184.2015 127.9715)
		(width 0.09)
		(layer "In4.Cu")
		(net 322)
	)
	(arc
		(start 182.13 126.91)
		(mid 182.044773 126.88107)
		(end 181.992385 126.806874)
		(width 0.09)
		(layer "In4.Cu")
		(net 322)
	)
	(arc
		(start 182.231777 127.534999)
		(mid 182.143389 127.571611)
		(end 182.055 127.535)
		(width 0.09)
		(layer "In4.Cu")
		(net 322)
	)
	(arc
		(start 182.408552 127.535)
		(mid 182.320164 127.498388)
		(end 182.231776 127.535)
		(width 0.09)
		(layer "In4.Cu")
		(net 322)
	)
	(arc
		(start 188.49 129.1115)
		(mid 188.446066 129.217566)
		(end 188.34 129.2615)
		(width 0.09)
		(layer "In4.Cu")
		(net 322)
	)
	(arc
		(start 186.99 128.791311)
		(mid 186.946066 128.685245)
		(end 186.84 128.641311)
		(width 0.09)
		(layer "In4.Cu")
		(net 322)
	)
	(arc
		(start 188.64 128.8115)
		(mid 188.533934 128.855434)
		(end 188.49 128.9615)
		(width 0.09)
		(layer "In4.Cu")
		(net 322)
	)
	(arc
		(start 182.8 127.19)
		(mid 182.898995 127.148995)
		(end 182.94 127.05)
		(width 0.09)
		(layer "In4.Cu")
		(net 322)
	)
	(arc
		(start 188.34 129.2615)
		(mid 188.233934 129.217566)
		(end 188.19 129.1115)
		(width 0.09)
		(layer "In4.Cu")
		(net 322)
	)
	(arc
		(start 182.443906 127.747132)
		(mid 182.480518 127.658744)
		(end 182.443907 127.570355)
		(width 0.09)
		(layer "In4.Cu")
		(net 322)
	)
	(arc
		(start 186.24 128.641311)
		(mid 186.133934 128.685245)
		(end 186.09 128.791311)
		(width 0.09)
		(layer "In4.Cu")
		(net 322)
	)
	(arc
		(start 185.64 128.641311)
		(mid 185.533934 128.685245)
		(end 185.49 128.791311)
		(width 0.09)
		(layer "In4.Cu")
		(net 322)
	)
	(arc
		(start 188.19 128.9615)
		(mid 188.146066 128.855434)
		(end 188.04 128.8115)
		(width 0.09)
		(layer "In4.Cu")
		(net 322)
	)
	(arc
		(start 186.39 128.791311)
		(mid 186.346066 128.685245)
		(end 186.24 128.641311)
		(width 0.09)
		(layer "In4.Cu")
		(net 322)
	)
	(arc
		(start 188.04 128.8115)
		(mid 187.933934 128.855434)
		(end 187.89 128.9615)
		(width 0.09)
		(layer "In4.Cu")
		(net 322)
	)
	(arc
		(start 187.89 129.1115)
		(mid 187.846066 129.217566)
		(end 187.74 129.2615)
		(width 0.09)
		(layer "In4.Cu")
		(net 322)
	)
	(arc
		(start 182.94 127.05)
		(mid 182.898995 126.951005)
		(end 182.8 126.91)
		(width 0.09)
		(layer "In4.Cu")
		(net 322)
	)
	(arc
		(start 186.09 129.1115)
		(mid 186.046066 129.217566)
		(end 185.94 129.2615)
		(width 0.09)
		(layer "In4.Cu")
		(net 322)
	)
	(arc
		(start 187.74 129.2615)
		(mid 187.633934 129.217566)
		(end 187.59 129.1115)
		(width 0.09)
		(layer "In4.Cu")
		(net 322)
	)
	(arc
		(start 186.54 129.2615)
		(mid 186.433934 129.217566)
		(end 186.39 129.1115)
		(width 0.09)
		(layer "In4.Cu")
		(net 322)
	)
	(arc
		(start 187.14 129.2615)
		(mid 187.033934 129.217566)
		(end 186.99 129.1115)
		(width 0.09)
		(layer "In4.Cu")
		(net 322)
	)
	(arc
		(start 188.94 129.2615)
		(mid 188.833934 129.217566)
		(end 188.79 129.1115)
		(width 0.09)
		(layer "In4.Cu")
		(net 322)
	)
	(arc
		(start 185.94 129.2615)
		(mid 185.833934 129.217566)
		(end 185.79 129.1115)
		(width 0.09)
		(layer "In4.Cu")
		(net 322)
	)
	(arc
		(start 187.29 129.1115)
		(mid 187.246066 129.217566)
		(end 187.14 129.2615)
		(width 0.09)
		(layer "In4.Cu")
		(net 322)
	)
	(arc
		(start 186.84 128.641311)
		(mid 186.733934 128.685245)
		(end 186.69 128.791311)
		(width 0.09)
		(layer "In4.Cu")
		(net 322)
	)
	(arc
		(start 182.443908 127.923909)
		(mid 182.407296 127.835521)
		(end 182.443908 127.747133)
		(width 0.09)
		(layer "In4.Cu")
		(net 322)
	)
	(arc
		(start 186.69 129.1115)
		(mid 186.646066 129.217566)
		(end 186.54 129.2615)
		(width 0.09)
		(layer "In4.Cu")
		(net 322)
	)
	(arc
		(start 185.49 129.1115)
		(mid 185.446066 129.217566)
		(end 185.34 129.2615)
		(width 0.09)
		(layer "In4.Cu")
		(net 322)
	)
	(arc
		(start 185.79 128.791311)
		(mid 185.746066 128.685245)
		(end 185.64 128.641311)
		(width 0.09)
		(layer "In4.Cu")
		(net 322)
	)
	(arc
		(start 181.99 127.33)
		(mid 182.031005 127.231005)
		(end 182.13 127.19)
		(width 0.09)
		(layer "In4.Cu")
		(net 322)
	)
	(arc
		(start 188.79 128.9615)
		(mid 188.746066 128.855434)
		(end 188.64 128.8115)
		(width 0.09)
		(layer "In4.Cu")
		(net 322)
	)
	(arc
		(start 187.59 128.9615)
		(mid 187.546066 128.855434)
		(end 187.44 128.8115)
		(width 0.09)
		(layer "In4.Cu")
		(net 322)
	)
	(arc
		(start 187.44 128.8115)
		(mid 187.333934 128.855434)
		(end 187.29 128.9615)
		(width 0.09)
		(layer "In4.Cu")
		(net 322)
	)
	(segment
		(start 181.475 125.059242)
		(end 181.696242 125.059242)
		(width 0.174)
		(layer "F.Cu")
		(net 323)
	)
	(segment
		(start 181.696242 125.059242)
		(end 182.004 125.367)
		(width 0.174)
		(layer "F.Cu")
		(net 323)
	)
	(via
		(at 189.3 129.85)
		(size 0.35)
		(drill 0.15)
		(layers "F.Cu" "B.Cu")
		(remove_unused_layers yes)
		(keep_end_layers yes)
		(zone_layer_connections)
		(net 323)
	)
	(via
		(at 181.475 125.059242)
		(size 0.35)
		(drill 0.15)
		(layers "F.Cu" "B.Cu")
		(remove_unused_layers yes)
		(keep_end_layers yes)
		(zone_layer_connections)
		(net 323)
	)
	(segment
		(start 186.99 129.71)
		(end 186.99 129.91)
		(width 0.09)
		(layer "In4.Cu")
		(net 323)
	)
	(segment
		(start 181.16 125.96)
		(end 181.16 128.37)
		(width 0.09)
		(layer "In4.Cu")
		(net 323)
	)
	(segment
		(start 183.58 129.3)
		(end 183.84 129.56)
		(width 0.09)
		(layer "In4.Cu")
		(net 323)
	)
	(segment
		(start 181.16 125.374242)
		(end 181.16 125.43)
		(width 0.09)
		(layer "In4.Cu")
		(net 323)
	)
	(segment
		(start 185.79 129.71)
		(end 185.79 129.91)
		(width 0.09)
		(layer "In4.Cu")
		(net 323)
	)
	(segment
		(start 181.16 128.37)
		(end 181.4115 128.6215)
		(width 0.09)
		(layer "In4.Cu")
		(net 323)
	)
	(segment
		(start 181.475 125.059242)
		(end 181.16 125.374242)
		(width 0.09)
		(layer "In4.Cu")
		(net 323)
	)
	(segment
		(start 186.39 129.71)
		(end 186.39 129.91)
		(width 0.09)
		(layer "In4.Cu")
		(net 323)
	)
	(segment
		(start 180.91 125.68)
		(end 180.91 125.71)
		(width 0.09)
		(layer "In4.Cu")
		(net 323)
	)
	(segment
		(start 188.74 129.56)
		(end 189.03 129.85)
		(width 0.09)
		(layer "In4.Cu")
		(net 323)
	)
	(segment
		(start 188.64 129.56)
		(end 188.74 129.56)
		(width 0.09)
		(layer "In4.Cu")
		(net 323)
	)
	(segment
		(start 182.03 128.4715)
		(end 182.03 128.2215)
		(width 0.09)
		(layer "In4.Cu")
		(net 323)
	)
	(segment
		(start 187.59 129.71)
		(end 187.59 129.91)
		(width 0.09)
		(layer "In4.Cu")
		(net 323)
	)
	(segment
		(start 182.33 128.2215)
		(end 182.33 129.0215)
		(width 0.09)
		(layer "In4.Cu")
		(net 323)
	)
	(segment
		(start 181.4115 128.6215)
		(end 181.88 128.6215)
		(width 0.09)
		(layer "In4.Cu")
		(net 323)
	)
	(segment
		(start 182.63 129.0215)
		(end 182.63 128.7715)
		(width 0.09)
		(layer "In4.Cu")
		(net 323)
	)
	(segment
		(start 186.69 129.91)
		(end 186.69 129.71)
		(width 0.09)
		(layer "In4.Cu")
		(net 323)
	)
	(segment
		(start 189.03 129.85)
		(end 189.3 129.85)
		(width 0.09)
		(layer "In4.Cu")
		(net 323)
	)
	(segment
		(start 183.4015 128.6215)
		(end 183.58 128.8)
		(width 0.09)
		(layer "In4.Cu")
		(net 323)
	)
	(segment
		(start 187.89 129.91)
		(end 187.89 129.71)
		(width 0.09)
		(layer "In4.Cu")
		(net 323)
	)
	(segment
		(start 188.49 129.91)
		(end 188.49 129.71)
		(width 0.09)
		(layer "In4.Cu")
		(net 323)
	)
	(segment
		(start 188.19 129.71)
		(end 188.19 129.91)
		(width 0.09)
		(layer "In4.Cu")
		(net 323)
	)
	(segment
		(start 183.58 128.8)
		(end 183.58 129.3)
		(width 0.09)
		(layer "In4.Cu")
		(net 323)
	)
	(segment
		(start 183.84 129.56)
		(end 185.64 129.56)
		(width 0.09)
		(layer "In4.Cu")
		(net 323)
	)
	(segment
		(start 182.78 128.6215)
		(end 183.4015 128.6215)
		(width 0.09)
		(layer "In4.Cu")
		(net 323)
	)
	(segment
		(start 186.09 129.91)
		(end 186.09 129.71)
		(width 0.09)
		(layer "In4.Cu")
		(net 323)
	)
	(segment
		(start 187.29 129.91)
		(end 187.29 129.71)
		(width 0.09)
		(layer "In4.Cu")
		(net 323)
	)
	(arc
		(start 181.035 125.555)
		(mid 180.946612 125.591612)
		(end 180.91 125.68)
		(width 0.09)
		(layer "In4.Cu")
		(net 323)
	)
	(arc
		(start 180.91 125.71)
		(mid 180.946612 125.798388)
		(end 181.035 125.835)
		(width 0.09)
		(layer "In4.Cu")
		(net 323)
	)
	(arc
		(start 185.94 130.06)
		(mid 186.046066 130.016066)
		(end 186.09 129.91)
		(width 0.09)
		(layer "In4.Cu")
		(net 323)
	)
	(arc
		(start 186.54 130.06)
		(mid 186.646066 130.016066)
		(end 186.69 129.91)
		(width 0.09)
		(layer "In4.Cu")
		(net 323)
	)
	(arc
		(start 186.99 129.91)
		(mid 187.033934 130.016066)
		(end 187.14 130.06)
		(width 0.09)
		(layer "In4.Cu")
		(net 323)
	)
	(arc
		(start 181.16 125.43)
		(mid 181.123388 125.518388)
		(end 181.035 125.555)
		(width 0.09)
		(layer "In4.Cu")
		(net 323)
	)
	(arc
		(start 187.89 129.71)
		(mid 187.933934 129.603934)
		(end 188.04 129.56)
		(width 0.09)
		(layer "In4.Cu")
		(net 323)
	)
	(arc
		(start 188.04 129.56)
		(mid 188.146066 129.603934)
		(end 188.19 129.71)
		(width 0.09)
		(layer "In4.Cu")
		(net 323)
	)
	(arc
		(start 181.88 128.6215)
		(mid 181.986066 128.577566)
		(end 182.03 128.4715)
		(width 0.09)
		(layer "In4.Cu")
		(net 323)
	)
	(arc
		(start 186.69 129.71)
		(mid 186.733934 129.603934)
		(end 186.84 129.56)
		(width 0.09)
		(layer "In4.Cu")
		(net 323)
	)
	(arc
		(start 187.44 129.56)
		(mid 187.546066 129.603934)
		(end 187.59 129.71)
		(width 0.09)
		(layer "In4.Cu")
		(net 323)
	)
	(arc
		(start 182.18 128.0715)
		(mid 182.286066 128.115434)
		(end 182.33 128.2215)
		(width 0.09)
		(layer "In4.Cu")
		(net 323)
	)
	(arc
		(start 188.34 130.06)
		(mid 188.446066 130.016066)
		(end 188.49 129.91)
		(width 0.09)
		(layer "In4.Cu")
		(net 323)
	)
	(arc
		(start 188.49 129.71)
		(mid 188.533934 129.603934)
		(end 188.64 129.56)
		(width 0.09)
		(layer "In4.Cu")
		(net 323)
	)
	(arc
		(start 187.74 130.06)
		(mid 187.846066 130.016066)
		(end 187.89 129.91)
		(width 0.09)
		(layer "In4.Cu")
		(net 323)
	)
	(arc
		(start 185.79 129.91)
		(mid 185.833934 130.016066)
		(end 185.94 130.06)
		(width 0.09)
		(layer "In4.Cu")
		(net 323)
	)
	(arc
		(start 182.63 128.7715)
		(mid 182.673934 128.665434)
		(end 182.78 128.6215)
		(width 0.09)
		(layer "In4.Cu")
		(net 323)
	)
	(arc
		(start 182.03 128.2215)
		(mid 182.073934 128.115434)
		(end 182.18 128.0715)
		(width 0.09)
		(layer "In4.Cu")
		(net 323)
	)
	(arc
		(start 188.19 129.91)
		(mid 188.233934 130.016066)
		(end 188.34 130.06)
		(width 0.09)
		(layer "In4.Cu")
		(net 323)
	)
	(arc
		(start 186.09 129.71)
		(mid 186.133934 129.603934)
		(end 186.24 129.56)
		(width 0.09)
		(layer "In4.Cu")
		(net 323)
	)
	(arc
		(start 181.035 125.835)
		(mid 181.123388 125.871612)
		(end 181.16 125.96)
		(width 0.09)
		(layer "In4.Cu")
		(net 323)
	)
	(arc
		(start 186.39 129.91)
		(mid 186.433934 130.016066)
		(end 186.54 130.06)
		(width 0.09)
		(layer "In4.Cu")
		(net 323)
	)
	(arc
		(start 182.48 129.1715)
		(mid 182.586066 129.127566)
		(end 182.63 129.0215)
		(width 0.09)
		(layer "In4.Cu")
		(net 323)
	)
	(arc
		(start 186.84 129.56)
		(mid 186.946066 129.603934)
		(end 186.99 129.71)
		(width 0.09)
		(layer "In4.Cu")
		(net 323)
	)
	(arc
		(start 187.59 129.91)
		(mid 187.633934 130.016066)
		(end 187.74 130.06)
		(width 0.09)
		(layer "In4.Cu")
		(net 323)
	)
	(arc
		(start 182.33 129.0215)
		(mid 182.373934 129.127566)
		(end 182.48 129.1715)
		(width 0.09)
		(layer "In4.Cu")
		(net 323)
	)
	(arc
		(start 185.64 129.56)
		(mid 185.746066 129.603934)
		(end 185.79 129.71)
		(width 0.09)
		(layer "In4.Cu")
		(net 323)
	)
	(arc
		(start 187.29 129.71)
		(mid 187.333934 129.603934)
		(end 187.44 129.56)
		(width 0.09)
		(layer "In4.Cu")
		(net 323)
	)
	(arc
		(start 186.24 129.56)
		(mid 186.346066 129.603934)
		(end 186.39 129.71)
		(width 0.09)
		(layer "In4.Cu")
		(net 323)
	)
	(arc
		(start 187.14 130.06)
		(mid 187.246066 130.016066)
		(end 187.29 129.91)
		(width 0.09)
		(layer "In4.Cu")
		(net 323)
	)
	(segment
		(start 176.404 133.817)
		(end 176.8035 133.4925)
		(width 0.174)
		(layer "F.Cu")
		(net 324)
	)
	(via
		(at 176.8035 133.4925)
		(size 0.35)
		(drill 0.15)
		(layers "F.Cu" "B.Cu")
		(remove_unused_layers yes)
		(keep_end_layers yes)
		(zone_layer_connections)
		(net 324)
	)
	(via
		(at 189.299 130.701)
		(size 0.35)
		(drill 0.15)
		(layers "F.Cu" "B.Cu")
		(remove_unused_layers yes)
		(keep_end_layers yes)
		(zone_layer_connections)
		(net 324)
	)
	(segment
		(start 180.65 131.2165)
		(end 185.05 131.2165)
		(width 0.09)
		(layer "In2.Cu")
		(net 324)
	)
	(segment
		(start 179.425 131.0415)
		(end 179.425 130.9415)
		(width 0.09)
		(layer "In2.Cu")
		(net 324)
	)
	(segment
		(start 177.586395 131.313602)
		(end 177.586396 131.313603)
		(width 0.09)
		(layer "In2.Cu")
		(net 324)
	)
	(segment
		(start 178.725 131.0415)
		(end 178.725 130.9415)
		(width 0.09)
		(layer "In2.Cu")
		(net 324)
	)
	(segment
		(start 177.268198 131.95)
		(end 177.657106 132.338908)
		(width 0.09)
		(layer "In2.Cu")
		(net 324)
	)
	(segment
		(start 186.625 131.0415)
		(end 186.625 130.792751)
		(width 0.09)
		(layer "In2.Cu")
		(net 324)
	)
	(segment
		(start 186.975 130.792751)
		(end 186.975 131.0415)
		(width 0.09)
		(layer "In2.Cu")
		(net 324)
	)
	(segment
		(start 185.575 130.842751)
		(end 185.575 131.0415)
		(width 0.09)
		(layer "In2.Cu")
		(net 324)
	)
	(segment
		(start 179.075 130.9415)
		(end 179.075 131.0415)
		(width 0.09)
		(layer "In2.Cu")
		(net 324)
	)
	(segment
		(start 180.475 130.9415)
		(end 180.475 131.0415)
		(width 0.09)
		(layer "In2.Cu")
		(net 324)
	)
	(segment
		(start 187.675 130.792753)
		(end 187.675 131.0415)
		(width 0.09)
		(layer "In2.Cu")
		(net 324)
	)
	(segment
		(start 177.586396 131.313603)
		(end 177.6835 131.2165)
		(width 0.09)
		(layer "In2.Cu")
		(net 324)
	)
	(segment
		(start 180.125 131.0415)
		(end 180.125 130.9415)
		(width 0.09)
		(layer "In2.Cu")
		(net 324)
	)
	(segment
		(start 187.9335 131.2165)
		(end 188.449 130.701)
		(width 0.09)
		(layer "In2.Cu")
		(net 324)
	)
	(segment
		(start 188.449 130.701)
		(end 189.299 130.701)
		(width 0.09)
		(layer "In2.Cu")
		(net 324)
	)
	(segment
		(start 176.4785 133.17)
		(end 176.4785 132.4215)
		(width 0.09)
		(layer "In2.Cu")
		(net 324)
	)
	(segment
		(start 186.275 130.792746)
		(end 186.275 131.0415)
		(width 0.09)
		(layer "In2.Cu")
		(net 324)
	)
	(segment
		(start 177.975304 132.020709)
		(end 177.586395 131.6318)
		(width 0.09)
		(layer "In2.Cu")
		(net 324)
	)
	(segment
		(start 179.775 130.9415)
		(end 179.775 131.0415)
		(width 0.09)
		(layer "In2.Cu")
		(net 324)
	)
	(segment
		(start 187.325 131.0415)
		(end 187.325 130.792753)
		(width 0.09)
		(layer "In2.Cu")
		(net 324)
	)
	(segment
		(start 177.6835 131.2165)
		(end 178.55 131.2165)
		(width 0.09)
		(layer "In2.Cu")
		(net 324)
	)
	(segment
		(start 176.8035 133.4925)
		(end 176.4785 133.17)
		(width 0.09)
		(layer "In2.Cu")
		(net 324)
	)
	(segment
		(start 185.225 131.0415)
		(end 185.225 130.842751)
		(width 0.09)
		(layer "In2.Cu")
		(net 324)
	)
	(segment
		(start 177.975304 132.020708)
		(end 177.975304 132.020709)
		(width 0.09)
		(layer "In2.Cu")
		(net 324)
	)
	(segment
		(start 187.85 131.2165)
		(end 187.9335 131.2165)
		(width 0.09)
		(layer "In2.Cu")
		(net 324)
	)
	(segment
		(start 176.4785 132.4215)
		(end 176.95 131.95)
		(width 0.09)
		(layer "In2.Cu")
		(net 324)
	)
	(segment
		(start 185.925 131.0415)
		(end 185.925 130.792746)
		(width 0.09)
		(layer "In2.Cu")
		(net 324)
	)
	(arc
		(start 180.125 130.9415)
		(mid 180.176256 130.817756)
		(end 180.3 130.7665)
		(width 0.09)
		(layer "In2.Cu")
		(net 324)
	)
	(arc
		(start 185.925 130.792746)
		(mid 185.976256 130.669002)
		(end 186.1 130.617746)
		(width 0.09)
		(layer "In2.Cu")
		(net 324)
	)
	(arc
		(start 185.4 130.667751)
		(mid 185.523744 130.719007)
		(end 185.575 130.842751)
		(width 0.09)
		(layer "In2.Cu")
		(net 324)
	)
	(arc
		(start 178.725 130.9415)
		(mid 178.776256 130.817756)
		(end 178.9 130.7665)
		(width 0.09)
		(layer "In2.Cu")
		(net 324)
	)
	(arc
		(start 185.75 131.2165)
		(mid 185.873744 131.165244)
		(end 185.925 131.0415)
		(width 0.09)
		(layer "In2.Cu")
		(net 324)
	)
	(arc
		(start 179.075 131.0415)
		(mid 179.126256 131.165244)
		(end 179.25 131.2165)
		(width 0.09)
		(layer "In2.Cu")
		(net 324)
	)
	(arc
		(start 186.975 131.0415)
		(mid 187.026256 131.165244)
		(end 187.15 131.2165)
		(width 0.09)
		(layer "In2.Cu")
		(net 324)
	)
	(arc
		(start 179.25 131.2165)
		(mid 179.373744 131.165244)
		(end 179.425 131.0415)
		(width 0.09)
		(layer "In2.Cu")
		(net 324)
	)
	(arc
		(start 177.975304 132.338908)
		(mid 178.041205 132.179808)
		(end 177.975304 132.020708)
		(width 0.09)
		(layer "In2.Cu")
		(net 324)
	)
	(arc
		(start 179.95 131.2165)
		(mid 180.073744 131.165244)
		(end 180.125 131.0415)
		(width 0.09)
		(layer "In2.Cu")
		(net 324)
	)
	(arc
		(start 187.15 131.2165)
		(mid 187.273744 131.165244)
		(end 187.325 131.0415)
		(width 0.09)
		(layer "In2.Cu")
		(net 324)
	)
	(arc
		(start 187.5 130.617753)
		(mid 187.623744 130.669009)
		(end 187.675 130.792753)
		(width 0.09)
		(layer "In2.Cu")
		(net 324)
	)
	(arc
		(start 186.8 130.617751)
		(mid 186.923744 130.669007)
		(end 186.975 130.792751)
		(width 0.09)
		(layer "In2.Cu")
		(net 324)
	)
	(arc
		(start 180.475 131.0415)
		(mid 180.526256 131.165244)
		(end 180.65 131.2165)
		(width 0.09)
		(layer "In2.Cu")
		(net 324)
	)
	(arc
		(start 186.275 131.0415)
		(mid 186.326256 131.165244)
		(end 186.45 131.2165)
		(width 0.09)
		(layer "In2.Cu")
		(net 324)
	)
	(arc
		(start 178.9 130.7665)
		(mid 179.023744 130.817756)
		(end 179.075 130.9415)
		(width 0.09)
		(layer "In2.Cu")
		(net 324)
	)
	(arc
		(start 180.3 130.7665)
		(mid 180.423744 130.817756)
		(end 180.475 130.9415)
		(width 0.09)
		(layer "In2.Cu")
		(net 324)
	)
	(arc
		(start 177.657106 132.338908)
		(mid 177.816205 132.404809)
		(end 177.975304 132.338908)
		(width 0.09)
		(layer "In2.Cu")
		(net 324)
	)
	(arc
		(start 179.775 131.0415)
		(mid 179.826256 131.165244)
		(end 179.95 131.2165)
		(width 0.09)
		(layer "In2.Cu")
		(net 324)
	)
	(arc
		(start 186.1 130.617746)
		(mid 186.223744 130.669002)
		(end 186.275 130.792746)
		(width 0.09)
		(layer "In2.Cu")
		(net 324)
	)
	(arc
		(start 185.225 130.842751)
		(mid 185.276256 130.719007)
		(end 185.4 130.667751)
		(width 0.09)
		(layer "In2.Cu")
		(net 324)
	)
	(arc
		(start 187.325 130.792753)
		(mid 187.376256 130.669009)
		(end 187.5 130.617753)
		(width 0.09)
		(layer "In2.Cu")
		(net 324)
	)
	(arc
		(start 176.95 131.95)
		(mid 177.109099 131.884099)
		(end 177.268198 131.95)
		(width 0.09)
		(layer "In2.Cu")
		(net 324)
	)
	(arc
		(start 185.05 131.2165)
		(mid 185.173744 131.165244)
		(end 185.225 131.0415)
		(width 0.09)
		(layer "In2.Cu")
		(net 324)
	)
	(arc
		(start 185.575 131.0415)
		(mid 185.626256 131.165244)
		(end 185.75 131.2165)
		(width 0.09)
		(layer "In2.Cu")
		(net 324)
	)
	(arc
		(start 178.55 131.2165)
		(mid 178.673744 131.165244)
		(end 178.725 131.0415)
		(width 0.09)
		(layer "In2.Cu")
		(net 324)
	)
	(arc
		(start 186.625 130.792751)
		(mid 186.676256 130.669007)
		(end 186.8 130.617751)
		(width 0.09)
		(layer "In2.Cu")
		(net 324)
	)
	(arc
		(start 187.675 131.0415)
		(mid 187.726256 131.165244)
		(end 187.85 131.2165)
		(width 0.09)
		(layer "In2.Cu")
		(net 324)
	)
	(arc
		(start 179.6 130.7665)
		(mid 179.723744 130.817756)
		(end 179.775 130.9415)
		(width 0.09)
		(layer "In2.Cu")
		(net 324)
	)
	(arc
		(start 186.45 131.2165)
		(mid 186.573744 131.165244)
		(end 186.625 131.0415)
		(width 0.09)
		(layer "In2.Cu")
		(net 324)
	)
	(arc
		(start 179.425 130.9415)
		(mid 179.476256 130.817756)
		(end 179.6 130.7665)
		(width 0.09)
		(layer "In2.Cu")
		(net 324)
	)
	(arc
		(start 177.586395 131.6318)
		(mid 177.520494 131.472701)
		(end 177.586395 131.313602)
		(width 0.09)
		(layer "In2.Cu")
		(net 324)
	)
	(segment
		(start 213.615 146.112)
		(end 212.942 146.112)
		(width 0.174)
		(layer "F.Cu")
		(net 325)
	)
	(segment
		(start 212.942 146.112)
		(end 212.93 146.1)
		(width 0.174)
		(layer "F.Cu")
		(net 325)
	)
	(via
		(at 212.93 146.1)
		(size 0.35)
		(drill 0.15)
		(layers "F.Cu" "B.Cu")
		(remove_unused_layers yes)
		(keep_end_layers yes)
		(zone_layer_connections)
		(net 325)
	)
	(segment
		(start 176.404 133.167)
		(end 176.8035 132.8425)
		(width 0.174)
		(layer "F.Cu")
		(net 326)
	)
	(via
		(at 189.299 131.501)
		(size 0.35)
		(drill 0.15)
		(layers "F.Cu" "B.Cu")
		(remove_unused_layers yes)
		(keep_end_layers yes)
		(zone_layer_connections)
		(net 326)
	)
	(via
		(at 176.8035 132.8425)
		(size 0.35)
		(drill 0.15)
		(layers "F.Cu" "B.Cu")
		(remove_unused_layers yes)
		(keep_end_layers yes)
		(zone_layer_connections)
		(net 326)
	)
	(segment
		(start 179.075951 132.5175)
		(end 179.5 132.5175)
		(width 0.09)
		(layer "In2.Cu")
		(net 326)
	)
	(segment
		(start 188.676279 131.501)
		(end 189.299 131.501)
		(width 0.09)
		(layer "In2.Cu")
		(net 326)
	)
	(segment
		(start 185.75925 132.664277)
		(end 185.759251 132.664276)
		(width 0.09)
		(layer "In2.Cu")
		(net 326)
	)
	(segment
		(start 177.6425 132.8425)
		(end 177.9675 133.1675)
		(width 0.09)
		(layer "In2.Cu")
		(net 326)
	)
	(segment
		(start 182.775 132.9425)
		(end 182.775 132.6925)
		(width 0.09)
		(layer "In2.Cu")
		(net 326)
	)
	(segment
		(start 188.2 131.9)
		(end 188.277279 131.9)
		(width 0.09)
		(layer "In2.Cu")
		(net 326)
	)
	(segment
		(start 187.675 132.075)
		(end 187.675 132.560808)
		(width 0.09)
		(layer "In2.Cu")
		(net 326)
	)
	(segment
		(start 179.675 132.6925)
		(end 179.675 132.8925)
		(width 0.09)
		(layer "In2.Cu")
		(net 326)
	)
	(segment
		(start 182.95 132.5175)
		(end 185.0575 132.5175)
		(width 0.09)
		(layer "In2.Cu")
		(net 326)
	)
	(segment
		(start 188.277279 131.9)
		(end 188.676279 131.501)
		(width 0.09)
		(layer "In2.Cu")
		(net 326)
	)
	(segment
		(start 178.85 132.9)
		(end 178.85 132.743451)
		(width 0.09)
		(layer "In2.Cu")
		(net 326)
	)
	(segment
		(start 185.334986 132.4875)
		(end 185.511763 132.664276)
		(width 0.09)
		(layer "In2.Cu")
		(net 326)
	)
	(segment
		(start 178.85 132.743451)
		(end 179.075951 132.5175)
		(width 0.09)
		(layer "In2.Cu")
		(net 326)
	)
	(segment
		(start 186.275 132.075)
		(end 186.275 132.560785)
		(width 0.09)
		(layer "In2.Cu")
		(net 326)
	)
	(segment
		(start 182.075 132.3425)
		(end 182.075 132.2425)
		(width 0.09)
		(layer "In2.Cu")
		(net 326)
	)
	(segment
		(start 187.325 132.560785)
		(end 187.325 132.075)
		(width 0.09)
		(layer "In2.Cu")
		(net 326)
	)
	(segment
		(start 185.582473 131.992524)
		(end 185.675 131.9)
		(width 0.09)
		(layer "In2.Cu")
		(net 326)
	)
	(segment
		(start 180.375 132.2425)
		(end 180.375 132.3425)
		(width 0.09)
		(layer "In2.Cu")
		(net 326)
	)
	(segment
		(start 185.675 131.9)
		(end 186.1 131.9)
		(width 0.09)
		(layer "In2.Cu")
		(net 326)
	)
	(segment
		(start 177.9675 133.1675)
		(end 178.5825 133.1675)
		(width 0.09)
		(layer "In2.Cu")
		(net 326)
	)
	(segment
		(start 182.425 132.2425)
		(end 182.425 132.9425)
		(width 0.09)
		(layer "In2.Cu")
		(net 326)
	)
	(segment
		(start 185.0575 132.5175)
		(end 185.0875 132.4875)
		(width 0.09)
		(layer "In2.Cu")
		(net 326)
	)
	(segment
		(start 185.759251 132.416788)
		(end 185.582474 132.240011)
		(width 0.09)
		(layer "In2.Cu")
		(net 326)
	)
	(segment
		(start 188.025 132.560808)
		(end 188.025 132.075)
		(width 0.09)
		(layer "In2.Cu")
		(net 326)
	)
	(segment
		(start 180.025 132.8925)
		(end 180.025 132.2425)
		(width 0.09)
		(layer "In2.Cu")
		(net 326)
	)
	(segment
		(start 176.8035 132.8425)
		(end 177.6425 132.8425)
		(width 0.09)
		(layer "In2.Cu")
		(net 326)
	)
	(segment
		(start 180.55 132.5175)
		(end 181.9 132.5175)
		(width 0.09)
		(layer "In2.Cu")
		(net 326)
	)
	(segment
		(start 178.5825 133.1675)
		(end 178.85 132.9)
		(width 0.09)
		(layer "In2.Cu")
		(net 326)
	)
	(segment
		(start 186.625 132.560785)
		(end 186.625 132.075)
		(width 0.09)
		(layer "In2.Cu")
		(net 326)
	)
	(segment
		(start 186.975 132.075)
		(end 186.975 132.560785)
		(width 0.09)
		(layer "In2.Cu")
		(net 326)
	)
	(arc
		(start 179.675 132.8925)
		(mid 179.726256 133.016244)
		(end 179.85 133.0675)
		(width 0.09)
		(layer "In2.Cu")
		(net 326)
	)
	(arc
		(start 182.425 132.9425)
		(mid 182.476256 133.066244)
		(end 182.6 133.1175)
		(width 0.09)
		(layer "In2.Cu")
		(net 326)
	)
	(arc
		(start 186.625 132.075)
		(mid 186.676256 131.951256)
		(end 186.8 131.9)
		(width 0.09)
		(layer "In2.Cu")
		(net 326)
	)
	(arc
		(start 182.25 132.0675)
		(mid 182.373744 132.118756)
		(end 182.425 132.2425)
		(width 0.09)
		(layer "In2.Cu")
		(net 326)
	)
	(arc
		(start 188.025 132.075)
		(mid 188.076256 131.951256)
		(end 188.2 131.9)
		(width 0.09)
		(layer "In2.Cu")
		(net 326)
	)
	(arc
		(start 180.025 132.2425)
		(mid 180.076256 132.118756)
		(end 180.2 132.0675)
		(width 0.09)
		(layer "In2.Cu")
		(net 326)
	)
	(arc
		(start 185.511763 132.664276)
		(mid 185.635506 132.715533)
		(end 185.75925 132.664277)
		(width 0.09)
		(layer "In2.Cu")
		(net 326)
	)
	(arc
		(start 185.582474 132.240011)
		(mid 185.531217 132.116268)
		(end 185.582473 131.992524)
		(width 0.09)
		(layer "In2.Cu")
		(net 326)
	)
	(arc
		(start 187.325 132.075)
		(mid 187.376256 131.951256)
		(end 187.5 131.9)
		(width 0.09)
		(layer "In2.Cu")
		(net 326)
	)
	(arc
		(start 187.675 132.560808)
		(mid 187.726256 132.684552)
		(end 187.85 132.735808)
		(width 0.09)
		(layer "In2.Cu")
		(net 326)
	)
	(arc
		(start 181.9 132.5175)
		(mid 182.023744 132.466244)
		(end 182.075 132.3425)
		(width 0.09)
		(layer "In2.Cu")
		(net 326)
	)
	(arc
		(start 186.45 132.735785)
		(mid 186.573744 132.684529)
		(end 186.625 132.560785)
		(width 0.09)
		(layer "In2.Cu")
		(net 326)
	)
	(arc
		(start 182.775 132.6925)
		(mid 182.826256 132.568756)
		(end 182.95 132.5175)
		(width 0.09)
		(layer "In2.Cu")
		(net 326)
	)
	(arc
		(start 187.85 132.735808)
		(mid 187.973744 132.684552)
		(end 188.025 132.560808)
		(width 0.09)
		(layer "In2.Cu")
		(net 326)
	)
	(arc
		(start 186.1 131.9)
		(mid 186.223744 131.951256)
		(end 186.275 132.075)
		(width 0.09)
		(layer "In2.Cu")
		(net 326)
	)
	(arc
		(start 185.0875 132.4875)
		(mid 185.211243 132.436244)
		(end 185.334986 132.4875)
		(width 0.09)
		(layer "In2.Cu")
		(net 326)
	)
	(arc
		(start 182.6 133.1175)
		(mid 182.723744 133.066244)
		(end 182.775 132.9425)
		(width 0.09)
		(layer "In2.Cu")
		(net 326)
	)
	(arc
		(start 187.5 131.9)
		(mid 187.623744 131.951256)
		(end 187.675 132.075)
		(width 0.09)
		(layer "In2.Cu")
		(net 326)
	)
	(arc
		(start 180.375 132.3425)
		(mid 180.426256 132.466244)
		(end 180.55 132.5175)
		(width 0.09)
		(layer "In2.Cu")
		(net 326)
	)
	(arc
		(start 186.975 132.560785)
		(mid 187.026256 132.684529)
		(end 187.15 132.735785)
		(width 0.09)
		(layer "In2.Cu")
		(net 326)
	)
	(arc
		(start 186.8 131.9)
		(mid 186.923744 131.951256)
		(end 186.975 132.075)
		(width 0.09)
		(layer "In2.Cu")
		(net 326)
	)
	(arc
		(start 187.15 132.735785)
		(mid 187.273744 132.684529)
		(end 187.325 132.560785)
		(width 0.09)
		(layer "In2.Cu")
		(net 326)
	)
	(arc
		(start 179.5 132.5175)
		(mid 179.623744 132.568756)
		(end 179.675 132.6925)
		(width 0.09)
		(layer "In2.Cu")
		(net 326)
	)
	(arc
		(start 185.759251 132.664276)
		(mid 185.810507 132.540532)
		(end 185.759251 132.416788)
		(width 0.09)
		(layer "In2.Cu")
		(net 326)
	)
	(arc
		(start 186.275 132.560785)
		(mid 186.326256 132.684529)
		(end 186.45 132.735785)
		(width 0.09)
		(layer "In2.Cu")
		(net 326)
	)
	(arc
		(start 179.85 133.0675)
		(mid 179.973744 133.016244)
		(end 180.025 132.8925)
		(width 0.09)
		(layer "In2.Cu")
		(net 326)
	)
	(arc
		(start 182.075 132.2425)
		(mid 182.126256 132.118756)
		(end 182.25 132.0675)
		(width 0.09)
		(layer "In2.Cu")
		(net 326)
	)
	(arc
		(start 180.2 132.0675)
		(mid 180.323744 132.118756)
		(end 180.375 132.2425)
		(width 0.09)
		(layer "In2.Cu")
		(net 326)
	)
	(via
		(at 192.499 137.101)
		(size 0.35)
		(drill 0.15)
		(layers "F.Cu" "B.Cu")
		(remove_unused_layers yes)
		(keep_end_layers yes)
		(zone_layer_connections)
		(net 327)
	)
	(via
		(at 206.299 147.401)
		(size 0.35)
		(drill 0.15)
		(layers "F.Cu" "B.Cu")
		(remove_unused_layers yes)
		(keep_end_layers yes)
		(zone_layer_connections)
		(net 327)
	)
	(segment
		(start 195.27 140.91)
		(end 195.05 140.69)
		(width 0.09)
		(layer "In7.Cu")
		(net 327)
	)
	(segment
		(start 196.04 141.55)
		(end 195.58 141.55)
		(width 0.09)
		(layer "In7.Cu")
		(net 327)
	)
	(segment
		(start 193.391549 138.29)
		(end 193.235451 138.29)
		(width 0.09)
		(layer "In7.Cu")
		(net 327)
	)
	(segment
		(start 194.52 140.47)
		(end 194.52 140.11)
		(width 0.09)
		(layer "In7.Cu")
		(net 327)
	)
	(segment
		(start 195.27 141.24)
		(end 195.27 140.91)
		(width 0.09)
		(layer "In7.Cu")
		(net 327)
	)
	(segment
		(start 194.52 140.11)
		(end 194.28 139.87)
		(width 0.09)
		(layer "In7.Cu")
		(net 327)
	)
	(segment
		(start 193.92 139.87)
		(end 193.71 139.66)
		(width 0.09)
		(layer "In7.Cu")
		(net 327)
	)
	(segment
		(start 200.271 145.781)
		(end 196.04 141.55)
		(width 0.09)
		(layer "In7.Cu")
		(net 327)
	)
	(segment
		(start 192.88 137.482)
		(end 192.499 137.101)
		(width 0.09)
		(layer "In7.Cu")
		(net 327)
	)
	(segment
		(start 195.58 141.55)
		(end 195.27 141.24)
		(width 0.09)
		(layer "In7.Cu")
		(net 327)
	)
	(segment
		(start 192.88 137.934549)
		(end 192.88 137.482)
		(width 0.09)
		(layer "In7.Cu")
		(net 327)
	)
	(segment
		(start 204.841 146.431)
		(end 201.881549 146.431)
		(width 0.09)
		(layer "In7.Cu")
		(net 327)
	)
	(segment
		(start 205.811 147.401)
		(end 204.841 146.431)
		(width 0.09)
		(layer "In7.Cu")
		(net 327)
	)
	(segment
		(start 195.05 140.69)
		(end 194.74 140.69)
		(width 0.09)
		(layer "In7.Cu")
		(net 327)
	)
	(segment
		(start 193.235451 138.29)
		(end 192.88 137.934549)
		(width 0.09)
		(layer "In7.Cu")
		(net 327)
	)
	(segment
		(start 194.74 140.69)
		(end 194.52 140.47)
		(width 0.09)
		(layer "In7.Cu")
		(net 327)
	)
	(segment
		(start 193.71 138.608451)
		(end 193.391549 138.29)
		(width 0.09)
		(layer "In7.Cu")
		(net 327)
	)
	(segment
		(start 201.231549 145.781)
		(end 200.271 145.781)
		(width 0.09)
		(layer "In7.Cu")
		(net 327)
	)
	(segment
		(start 201.881549 146.431)
		(end 201.231549 145.781)
		(width 0.09)
		(layer "In7.Cu")
		(net 327)
	)
	(segment
		(start 206.299 147.401)
		(end 205.811 147.401)
		(width 0.09)
		(layer "In7.Cu")
		(net 327)
	)
	(segment
		(start 193.71 139.66)
		(end 193.71 138.608451)
		(width 0.09)
		(layer "In7.Cu")
		(net 327)
	)
	(segment
		(start 194.28 139.87)
		(end 193.92 139.87)
		(width 0.09)
		(layer "In7.Cu")
		(net 327)
	)
	(via
		(at 192.499 138.7)
		(size 0.35)
		(drill 0.15)
		(layers "F.Cu" "B.Cu")
		(remove_unused_layers yes)
		(keep_end_layers yes)
		(zone_layer_connections)
		(net 328)
	)
	(via
		(at 203.049 144.151)
		(size 0.35)
		(drill 0.15)
		(layers "F.Cu" "B.Cu")
		(remove_unused_layers yes)
		(keep_end_layers yes)
		(zone_layer_connections)
		(net 328)
	)
	(segment
		(start 203.049 144.151)
		(end 203.049 143.949)
		(width 0.09)
		(layer "In11.Cu")
		(net 328)
	)
	(segment
		(start 198.152549 138.3)
		(end 196.88 138.3)
		(width 0.09)
		(layer "In11.Cu")
		(net 328)
	)
	(segment
		(start 200.019 140.272549)
		(end 200.019 140.167451)
		(width 0.09)
		(layer "In11.Cu")
		(net 328)
	)
	(segment
		(start 200.5 140.62)
		(end 200.366451 140.62)
		(width 0.09)
		(layer "In11.Cu")
		(net 328)
	)
	(segment
		(start 194.28 138.27)
		(end 192.415 138.27)
		(width 0.09)
		(layer "In11.Cu")
		(net 328)
	)
	(segment
		(start 194.669 137.581)
		(end 194.45 137.8)
		(width 0.09)
		(layer "In11.Cu")
		(net 328)
	)
	(segment
		(start 198.579 138.832549)
		(end 198.579 138.726451)
		(width 0.09)
		(layer "In11.Cu")
		(net 328)
	)
	(segment
		(start 194.45 138.1)
		(end 194.28 138.27)
		(width 0.09)
		(layer "In11.Cu")
		(net 328)
	)
	(segment
		(start 194.45 137.8)
		(end 194.45 138.1)
		(width 0.09)
		(layer "In11.Cu")
		(net 328)
	)
	(segment
		(start 200.366451 140.62)
		(end 200.019 140.272549)
		(width 0.09)
		(layer "In11.Cu")
		(net 328)
	)
	(segment
		(start 192.415 138.27)
		(end 192.31 138.375)
		(width 0.09)
		(layer "In11.Cu")
		(net 328)
	)
	(segment
		(start 198.766451 139.02)
		(end 198.579 138.832549)
		(width 0.09)
		(layer "In11.Cu")
		(net 328)
	)
	(segment
		(start 196.355 137.975)
		(end 196.355 138.625)
		(width 0.09)
		(layer "In11.Cu")
		(net 328)
	)
	(segment
		(start 195.3 137.848451)
		(end 195.032549 137.581)
		(width 0.09)
		(layer "In11.Cu")
		(net 328)
	)
	(segment
		(start 200.819 141.072549)
		(end 200.819 140.939)
		(width 0.09)
		(layer "In11.Cu")
		(net 328)
	)
	(segment
		(start 192.31 138.375)
		(end 192.31 138.511)
		(width 0.09)
		(layer "In11.Cu")
		(net 328)
	)
	(segment
		(start 195.3 138.05)
		(end 195.3 137.848451)
		(width 0.09)
		(layer "In11.Cu")
		(net 328)
	)
	(segment
		(start 195.83 138.3)
		(end 195.55 138.3)
		(width 0.09)
		(layer "In11.Cu")
		(net 328)
	)
	(segment
		(start 195.032549 137.581)
		(end 194.669 137.581)
		(width 0.09)
		(layer "In11.Cu")
		(net 328)
	)
	(segment
		(start 198.579 138.726451)
		(end 198.152549 138.3)
		(width 0.09)
		(layer "In11.Cu")
		(net 328)
	)
	(segment
		(start 196.705 138.125)
		(end 196.705 137.975)
		(width 0.09)
		(layer "In11.Cu")
		(net 328)
	)
	(segment
		(start 200.819 140.939)
		(end 200.5 140.62)
		(width 0.09)
		(layer "In11.Cu")
		(net 328)
	)
	(segment
		(start 201.62 141.873549)
		(end 200.819 141.072549)
		(width 0.09)
		(layer "In11.Cu")
		(net 328)
	)
	(segment
		(start 200.019 140.167451)
		(end 198.871549 139.02)
		(width 0.09)
		(layer "In11.Cu")
		(net 328)
	)
	(segment
		(start 195.55 138.3)
		(end 195.3 138.05)
		(width 0.09)
		(layer "In11.Cu")
		(net 328)
	)
	(segment
		(start 201.62 142.52)
		(end 201.62 141.873549)
		(width 0.09)
		(layer "In11.Cu")
		(net 328)
	)
	(segment
		(start 203.049 143.949)
		(end 201.62 142.52)
		(width 0.09)
		(layer "In11.Cu")
		(net 328)
	)
	(segment
		(start 198.871549 139.02)
		(end 198.766451 139.02)
		(width 0.09)
		(layer "In11.Cu")
		(net 328)
	)
	(segment
		(start 196.005 138.625)
		(end 196.005 138.475)
		(width 0.09)
		(layer "In11.Cu")
		(net 328)
	)
	(segment
		(start 192.31 138.511)
		(end 192.499 138.7)
		(width 0.09)
		(layer "In11.Cu")
		(net 328)
	)
	(arc
		(start 196.355 138.625)
		(mid 196.303744 138.748744)
		(end 196.18 138.8)
		(width 0.09)
		(layer "In11.Cu")
		(net 328)
	)
	(arc
		(start 196.88 138.3)
		(mid 196.756256 138.248744)
		(end 196.705 138.125)
		(width 0.09)
		(layer "In11.Cu")
		(net 328)
	)
	(arc
		(start 196.53 137.8)
		(mid 196.406256 137.851256)
		(end 196.355 137.975)
		(width 0.09)
		(layer "In11.Cu")
		(net 328)
	)
	(arc
		(start 196.705 137.975)
		(mid 196.653744 137.851256)
		(end 196.53 137.8)
		(width 0.09)
		(layer "In11.Cu")
		(net 328)
	)
	(arc
		(start 196.005 138.475)
		(mid 195.953744 138.351256)
		(end 195.83 138.3)
		(width 0.09)
		(layer "In11.Cu")
		(net 328)
	)
	(arc
		(start 196.18 138.8)
		(mid 196.056256 138.748744)
		(end 196.005 138.625)
		(width 0.09)
		(layer "In11.Cu")
		(net 328)
	)
	(via
		(at 201.099 145.451)
		(size 0.35)
		(drill 0.15)
		(layers "F.Cu" "B.Cu")
		(remove_unused_layers yes)
		(keep_end_layers yes)
		(zone_layer_connections)
		(net 329)
	)
	(via
		(at 192.499 139.5)
		(size 0.35)
		(drill 0.15)
		(layers "F.Cu" "B.Cu")
		(remove_unused_layers yes)
		(keep_end_layers yes)
		(zone_layer_connections)
		(net 329)
	)
	(segment
		(start 200.769 145.781)
		(end 199.621 145.781)
		(width 0.09)
		(layer "In9.Cu")
		(net 329)
	)
	(segment
		(start 195.36 142.7)
		(end 194.45 142.7)
		(width 0.09)
		(layer "In9.Cu")
		(net 329)
	)
	(segment
		(start 198.018625 143.071375)
		(end 198.018624 143.071375)
		(width 0.09)
		(layer "In9.Cu")
		(net 329)
	)
	(segment
		(start 194.45 140.92)
		(end 194.24 140.71)
		(width 0.09)
		(layer "In9.Cu")
		(net 329)
	)
	(segment
		(start 198.12 142.67)
		(end 198.12 142.06)
		(width 0.09)
		(layer "In9.Cu")
		(net 329)
	)
	(segment
		(start 194.200976 142.630975)
		(end 194.200976 142.630976)
		(width 0.09)
		(layer "In9.Cu")
		(net 329)
	)
	(segment
		(start 195.58 142.15)
		(end 195.58 142.48)
		(width 0.09)
		(layer "In9.Cu")
		(net 329)
	)
	(segment
		(start 193.72 140.17)
		(end 193.45 139.9)
		(width 0.09)
		(layer "In9.Cu")
		(net 329)
	)
	(segment
		(start 198.018624 142.771375)
		(end 198.018625 142.771375)
		(width 0.09)
		(layer "In9.Cu")
		(net 329)
	)
	(segment
		(start 194.380976 142.630976)
		(end 194.380976 142.630975)
		(width 0.09)
		(layer "In9.Cu")
		(net 329)
	)
	(segment
		(start 193.72 140.48)
		(end 193.72 140.17)
		(width 0.09)
		(layer "In9.Cu")
		(net 329)
	)
	(segment
		(start 194.24 140.71)
		(end 193.95 140.71)
		(width 0.09)
		(layer "In9.Cu")
		(net 329)
	)
	(segment
		(start 194.25 141.5)
		(end 194.45 141.3)
		(width 0.09)
		(layer "In9.Cu")
		(net 329)
	)
	(segment
		(start 198.12 142.06)
		(end 197.85 141.79)
		(width 0.09)
		(layer "In9.Cu")
		(net 329)
	)
	(segment
		(start 194.45 141.3)
		(end 194.45 140.92)
		(width 0.09)
		(layer "In9.Cu")
		(net 329)
	)
	(segment
		(start 193.246451 139.9)
		(end 192.846451 139.5)
		(width 0.09)
		(layer "In9.Cu")
		(net 329)
	)
	(segment
		(start 194.11 141.89)
		(end 193.86 141.89)
		(width 0.09)
		(layer "In9.Cu")
		(net 329)
	)
	(segment
		(start 197.917249 142.97)
		(end 197.917249 142.87275)
		(width 0.09)
		(layer "In9.Cu")
		(net 329)
	)
	(segment
		(start 193.99 142.7)
		(end 193.71 142.42)
		(width 0.09)
		(layer "In9.Cu")
		(net 329)
	)
	(segment
		(start 195.94 141.79)
		(end 195.58 142.15)
		(width 0.09)
		(layer "In9.Cu")
		(net 329)
	)
	(segment
		(start 197.85 141.79)
		(end 195.94 141.79)
		(width 0.09)
		(layer "In9.Cu")
		(net 329)
	)
	(segment
		(start 198.12 144.28)
		(end 198.12 143.17275)
		(width 0.09)
		(layer "In9.Cu")
		(net 329)
	)
	(segment
		(start 194.131952 142.7)
		(end 193.99 142.7)
		(width 0.09)
		(layer "In9.Cu")
		(net 329)
	)
	(segment
		(start 193.71 142.42)
		(end 193.71 142.34)
		(width 0.09)
		(layer "In9.Cu")
		(net 329)
	)
	(segment
		(start 193.45 139.9)
		(end 193.246451 139.9)
		(width 0.09)
		(layer "In9.Cu")
		(net 329)
	)
	(segment
		(start 193.71 141.74)
		(end 193.95 141.5)
		(width 0.09)
		(layer "In9.Cu")
		(net 329)
	)
	(segment
		(start 193.95 140.71)
		(end 193.72 140.48)
		(width 0.09)
		(layer "In9.Cu")
		(net 329)
	)
	(segment
		(start 193.95 141.5)
		(end 194.25 141.5)
		(width 0.09)
		(layer "In9.Cu")
		(net 329)
	)
	(segment
		(start 194.311952 142.561951)
		(end 194.27 142.561951)
		(width 0.09)
		(layer "In9.Cu")
		(net 329)
	)
	(segment
		(start 199.621 145.781)
		(end 198.12 144.28)
		(width 0.09)
		(layer "In9.Cu")
		(net 329)
	)
	(segment
		(start 195.58 142.48)
		(end 195.36 142.7)
		(width 0.09)
		(layer "In9.Cu")
		(net 329)
	)
	(segment
		(start 201.099 145.451)
		(end 200.769 145.781)
		(width 0.09)
		(layer "In9.Cu")
		(net 329)
	)
	(segment
		(start 192.846451 139.5)
		(end 192.499 139.5)
		(width 0.09)
		(layer "In9.Cu")
		(net 329)
	)
	(segment
		(start 193.86 142.19)
		(end 194.11 142.19)
		(width 0.09)
		(layer "In9.Cu")
		(net 329)
	)
	(arc
		(start 194.26 142.04)
		(mid 194.216066 141.933934)
		(end 194.11 141.89)
		(width 0.09)
		(layer "In9.Cu")
		(net 329)
	)
	(arc
		(start 194.27 142.561951)
		(mid 194.221193 142.582168)
		(end 194.200976 142.630975)
		(width 0.09)
		(layer "In9.Cu")
		(net 329)
	)
	(arc
		(start 198.018624 143.071375)
		(mid 197.946941 143.041683)
		(end 197.917249 142.97)
		(width 0.09)
		(layer "In9.Cu")
		(net 329)
	)
	(arc
		(start 193.86 141.89)
		(mid 193.753934 141.846066)
		(end 193.71 141.74)
		(width 0.09)
		(layer "In9.Cu")
		(net 329)
	)
	(arc
		(start 198.018625 142.771375)
		(mid 198.090308 142.741683)
		(end 198.12 142.67)
		(width 0.09)
		(layer "In9.Cu")
		(net 329)
	)
	(arc
		(start 194.45 142.7)
		(mid 194.401193 142.679783)
		(end 194.380976 142.630976)
		(width 0.09)
		(layer "In9.Cu")
		(net 329)
	)
	(arc
		(start 194.200976 142.630976)
		(mid 194.180759 142.679783)
		(end 194.131952 142.7)
		(width 0.09)
		(layer "In9.Cu")
		(net 329)
	)
	(arc
		(start 193.71 142.34)
		(mid 193.753934 142.233934)
		(end 193.86 142.19)
		(width 0.09)
		(layer "In9.Cu")
		(net 329)
	)
	(arc
		(start 194.11 142.19)
		(mid 194.216066 142.146066)
		(end 194.26 142.04)
		(width 0.09)
		(layer "In9.Cu")
		(net 329)
	)
	(arc
		(start 194.380976 142.630975)
		(mid 194.360759 142.582168)
		(end 194.311952 142.561951)
		(width 0.09)
		(layer "In9.Cu")
		(net 329)
	)
	(arc
		(start 197.917249 142.87275)
		(mid 197.946941 142.801067)
		(end 198.018624 142.771375)
		(width 0.09)
		(layer "In9.Cu")
		(net 329)
	)
	(arc
		(start 198.12 143.17275)
		(mid 198.090308 143.101067)
		(end 198.018625 143.071375)
		(width 0.09)
		(layer "In9.Cu")
		(net 329)
	)
	(segment
		(start 216.802 143.952)
		(end 216.802 143.65)
		(width 0.15)
		(layer "F.Cu")
		(net 330)
	)
	(segment
		(start 217.4 144.55)
		(end 216.802 143.952)
		(width 0.15)
		(layer "F.Cu")
		(net 330)
	)
	(segment
		(start 217.4 145)
		(end 217.4 144.55)
		(width 0.15)
		(layer "F.Cu")
		(net 330)
	)
	(via
		(at 201.099 146.101)
		(size 0.35)
		(drill 0.15)
		(layers "F.Cu" "B.Cu")
		(remove_unused_layers yes)
		(keep_end_layers yes)
		(zone_layer_connections)
		(net 331)
	)
	(via
		(at 192.499 140.3)
		(size 0.35)
		(drill 0.15)
		(layers "F.Cu" "B.Cu")
		(remove_unused_layers yes)
		(keep_end_layers yes)
		(zone_layer_connections)
		(net 331)
	)
	(segment
		(start 196.78 142.33)
		(end 196.78 142.69)
		(width 0.09)
		(layer "In9.Cu")
		(net 331)
	)
	(segment
		(start 192.511502 142.258498)
		(end 192.580287 142.298211)
		(width 0.09)
		(layer "In9.Cu")
		(net 331)
	)
	(segment
		(start 192.499 140.539)
		(end 192.9 140.94)
		(width 0.09)
		(layer "In9.Cu")
		(net 331)
	)
	(segment
		(start 193.37 143.2)
		(end 194.09 143.2)
		(width 0.09)
		(layer "In9.Cu")
		(net 331)
	)
	(segment
		(start 195.679796 143.669796)
		(end 195.729796 143.669796)
		(width 0.09)
		(layer "In9.Cu")
		(net 331)
	)
	(segment
		(start 196.02 142.36)
		(end 196.23 142.15)
		(width 0.09)
		(layer "In9.Cu")
		(net 331)
	)
	(segment
		(start 193.25 143.08)
		(end 193.37 143.2)
		(width 0.09)
		(layer "In9.Cu")
		(net 331)
	)
	(segment
		(start 195.429796 143.346348)
		(end 195.479796 143.346348)
		(width 0.09)
		(layer "In9.Cu")
		(net 331)
	)
	(segment
		(start 194.559796 143.669796)
		(end 194.729796 143.669796)
		(width 0.09)
		(layer "In9.Cu")
		(net 331)
	)
	(segment
		(start 193.078498 141.958498)
		(end 193.009713 141.998211)
		(width 0.09)
		(layer "In9.Cu")
		(net 331)
	)
	(segment
		(start 192.9 140.94)
		(end 192.9 141.16162)
		(width 0.09)
		(layer "In9.Cu")
		(net 331)
	)
	(segment
		(start 193.25 142.82)
		(end 193.25 143.08)
		(width 0.09)
		(layer "In9.Cu")
		(net 331)
	)
	(segment
		(start 195.579796 143.446348)
		(end 195.579796 143.569796)
		(width 0.09)
		(layer "In9.Cu")
		(net 331)
	)
	(segment
		(start 193.12 142.45)
		(end 193.12 142.69)
		(width 0.09)
		(layer "In9.Cu")
		(net 331)
	)
	(segment
		(start 193.078498 142.341502)
		(end 193.118211 142.410287)
		(width 0.09)
		(layer "In9.Cu")
		(net 331)
	)
	(segment
		(start 194.929796 143.346348)
		(end 194.979796 143.346348)
		(width 0.09)
		(layer "In9.Cu")
		(net 331)
	)
	(segment
		(start 196.270204 143.669796)
		(end 196.4 143.54)
		(width 0.09)
		(layer "In9.Cu")
		(net 331)
	)
	(segment
		(start 192.471789 142.110287)
		(end 192.47 142.15)
		(width 0.09)
		(layer "In9.Cu")
		(net 331)
	)
	(segment
		(start 192.62 142.3)
		(end 192.97 142.3)
		(width 0.09)
		(layer "In9.Cu")
		(net 331)
	)
	(segment
		(start 196.4 143.18)
		(end 196.02 142.8)
		(width 0.09)
		(layer "In9.Cu")
		(net 331)
	)
	(segment
		(start 192.97 142)
		(end 192.62 142)
		(width 0.09)
		(layer "In9.Cu")
		(net 331)
	)
	(segment
		(start 196.02 142.8)
		(end 196.02 142.36)
		(width 0.09)
		(layer "In9.Cu")
		(net 331)
	)
	(segment
		(start 196.78 142.69)
		(end 197.56 143.47)
		(width 0.09)
		(layer "In9.Cu")
		(net 331)
	)
	(segment
		(start 195.079796 143.446348)
		(end 195.079796 143.569796)
		(width 0.09)
		(layer "In9.Cu")
		(net 331)
	)
	(segment
		(start 196.6 142.15)
		(end 196.78 142.33)
		(width 0.09)
		(layer "In9.Cu")
		(net 331)
	)
	(segment
		(start 196.079796 143.246327)
		(end 196.079796 143.569796)
		(width 0.09)
		(layer "In9.Cu")
		(net 331)
	)
	(segment
		(start 192.511502 142.041502)
		(end 192.471789 142.110287)
		(width 0.09)
		(layer "In9.Cu")
		(net 331)
	)
	(segment
		(start 197.56 143.47)
		(end 197.56 144.67)
		(width 0.09)
		(layer "In9.Cu")
		(net 331)
	)
	(segment
		(start 196.179796 143.669796)
		(end 196.270204 143.669796)
		(width 0.09)
		(layer "In9.Cu")
		(net 331)
	)
	(segment
		(start 193.12 141.38162)
		(end 193.12 141.85)
		(width 0.09)
		(layer "In9.Cu")
		(net 331)
	)
	(segment
		(start 192.499 140.3)
		(end 192.499 140.539)
		(width 0.09)
		(layer "In9.Cu")
		(net 331)
	)
	(segment
		(start 192.9 141.16162)
		(end 193.12 141.38162)
		(width 0.09)
		(layer "In9.Cu")
		(net 331)
	)
	(segment
		(start 193.118211 142.410287)
		(end 193.12 142.45)
		(width 0.09)
		(layer "In9.Cu")
		(net 331)
	)
	(segment
		(start 192.580287 142.298211)
		(end 192.62 142.3)
		(width 0.09)
		(layer "In9.Cu")
		(net 331)
	)
	(segment
		(start 193.009713 142.301789)
		(end 193.078498 142.341502)
		(width 0.09)
		(layer "In9.Cu")
		(net 331)
	)
	(segment
		(start 196.23 142.15)
		(end 196.6 142.15)
		(width 0.09)
		(layer "In9.Cu")
		(net 331)
	)
	(segment
		(start 193.12 141.85)
		(end 193.118211 141.889713)
		(width 0.09)
		(layer "In9.Cu")
		(net 331)
	)
	(segment
		(start 197.56 144.67)
		(end 199.316 146.426)
		(width 0.09)
		(layer "In9.Cu")
		(net 331)
	)
	(segment
		(start 192.47 142.15)
		(end 192.471789 142.189713)
		(width 0.09)
		(layer "In9.Cu")
		(net 331)
	)
	(segment
		(start 196.4 143.54)
		(end 196.4 143.18)
		(width 0.09)
		(layer "In9.Cu")
		(net 331)
	)
	(segment
		(start 195.929796 143.146327)
		(end 195.979796 143.146327)
		(width 0.09)
		(layer "In9.Cu")
		(net 331)
	)
	(segment
		(start 193.009713 141.998211)
		(end 192.97 142)
		(width 0.09)
		(layer "In9.Cu")
		(net 331)
	)
	(segment
		(start 193.118211 141.889713)
		(end 193.078498 141.958498)
		(width 0.09)
		(layer "In9.Cu")
		(net 331)
	)
	(segment
		(start 192.471789 142.189713)
		(end 192.511502 142.258498)
		(width 0.09)
		(layer "In9.Cu")
		(net 331)
	)
	(segment
		(start 193.12 142.69)
		(end 193.25 142.82)
		(width 0.09)
		(layer "In9.Cu")
		(net 331)
	)
	(segment
		(start 192.62 142)
		(end 192.580287 142.001789)
		(width 0.09)
		(layer "In9.Cu")
		(net 331)
	)
	(segment
		(start 192.97 142.3)
		(end 193.009713 142.301789)
		(width 0.09)
		(layer "In9.Cu")
		(net 331)
	)
	(segment
		(start 195.829796 143.569796)
		(end 195.829796 143.246327)
		(width 0.09)
		(layer "In9.Cu")
		(net 331)
	)
	(segment
		(start 192.580287 142.001789)
		(end 192.511502 142.041502)
		(width 0.09)
		(layer "In9.Cu")
		(net 331)
	)
	(segment
		(start 195.329796 143.569796)
		(end 195.329796 143.446348)
		(width 0.09)
		(layer "In9.Cu")
		(net 331)
	)
	(segment
		(start 199.316 146.426)
		(end 200.774 146.426)
		(width 0.09)
		(layer "In9.Cu")
		(net 331)
	)
	(segment
		(start 195.179796 143.669796)
		(end 195.229796 143.669796)
		(width 0.09)
		(layer "In9.Cu")
		(net 331)
	)
	(segment
		(start 200.774 146.426)
		(end 201.099 146.101)
		(width 0.09)
		(layer "In9.Cu")
		(net 331)
	)
	(segment
		(start 194.09 143.2)
		(end 194.559796 143.669796)
		(width 0.09)
		(layer "In9.Cu")
		(net 331)
	)
	(segment
		(start 194.829796 143.569796)
		(end 194.829796 143.446348)
		(width 0.09)
		(layer "In9.Cu")
		(net 331)
	)
	(arc
		(start 195.829796 143.246327)
		(mid 195.859085 143.175616)
		(end 195.929796 143.146327)
		(width 0.09)
		(layer "In9.Cu")
		(net 331)
	)
	(arc
		(start 195.479796 143.346348)
		(mid 195.550507 143.375637)
		(end 195.579796 143.446348)
		(width 0.09)
		(layer "In9.Cu")
		(net 331)
	)
	(arc
		(start 195.329796 143.446348)
		(mid 195.359085 143.375637)
		(end 195.429796 143.346348)
		(width 0.09)
		(layer "In9.Cu")
		(net 331)
	)
	(arc
		(start 195.979796 143.146327)
		(mid 196.050507 143.175616)
		(end 196.079796 143.246327)
		(width 0.09)
		(layer "In9.Cu")
		(net 331)
	)
	(arc
		(start 195.579796 143.569796)
		(mid 195.609085 143.640507)
		(end 195.679796 143.669796)
		(width 0.09)
		(layer "In9.Cu")
		(net 331)
	)
	(arc
		(start 195.079796 143.569796)
		(mid 195.109085 143.640507)
		(end 195.179796 143.669796)
		(width 0.09)
		(layer "In9.Cu")
		(net 331)
	)
	(arc
		(start 196.079796 143.569796)
		(mid 196.109085 143.640507)
		(end 196.179796 143.669796)
		(width 0.09)
		(layer "In9.Cu")
		(net 331)
	)
	(arc
		(start 194.829796 143.446348)
		(mid 194.859085 143.375637)
		(end 194.929796 143.346348)
		(width 0.09)
		(layer "In9.Cu")
		(net 331)
	)
	(arc
		(start 194.729796 143.669796)
		(mid 194.800507 143.640507)
		(end 194.829796 143.569796)
		(width 0.09)
		(layer "In9.Cu")
		(net 331)
	)
	(arc
		(start 195.729796 143.669796)
		(mid 195.800507 143.640507)
		(end 195.829796 143.569796)
		(width 0.09)
		(layer "In9.Cu")
		(net 331)
	)
	(arc
		(start 195.229796 143.669796)
		(mid 195.300507 143.640507)
		(end 195.329796 143.569796)
		(width 0.09)
		(layer "In9.Cu")
		(net 331)
	)
	(arc
		(start 194.979796 143.346348)
		(mid 195.050507 143.375637)
		(end 195.079796 143.446348)
		(width 0.09)
		(layer "In9.Cu")
		(net 331)
	)
	(segment
		(start 206.3 142.85)
		(end 205.974 143.176)
		(width 0.1)
		(layer "F.Cu")
		(net 332)
	)
	(segment
		(start 205.974 143.176)
		(end 205.974 144.476)
		(width 0.1)
		(layer "F.Cu")
		(net 332)
	)
	(segment
		(start 205.974 144.476)
		(end 205.649 144.801)
		(width 0.1)
		(layer "F.Cu")
		(net 332)
	)
	(via
		(at 221.35 134.225)
		(size 0.35)
		(drill 0.15)
		(layers "F.Cu" "B.Cu")
		(remove_unused_layers yes)
		(keep_end_layers yes)
		(zone_layer_connections)
		(net 333)
	)
	(via
		(at 198.182 118.560417)
		(size 0.35)
		(drill 0.15)
		(layers "F.Cu" "B.Cu")
		(remove_unused_layers yes)
		(keep_end_layers yes)
		(zone_layer_connections)
		(net 333)
	)
	(via
		(at 193.555 118.96405)
		(size 0.35)
		(drill 0.15)
		(layers "F.Cu" "B.Cu")
		(remove_unused_layers yes)
		(keep_end_layers yes)
		(zone_layer_connections)
		(net 333)
	)
	(segment
		(start 194.122 120.171)
		(end 194.122 119.53105)
		(width 0.11)
		(layer "B.Cu")
		(net 333)
	)
	(segment
		(start 194.122 119.53105)
		(end 193.555 118.96405)
		(width 0.11)
		(layer "B.Cu")
		(net 333)
	)
	(segment
		(start 221.35 134.235)
		(end 221.35 134.225)
		(width 0.256)
		(layer "B.Cu")
		(net 333)
	)
	(segment
		(start 198.182 118.560417)
		(end 198.612417 118.13)
		(width 0.1)
		(layer "In4.Cu")
		(net 333)
	)
	(segment
		(start 220.975 133.85)
		(end 221.35 134.225)
		(width 0.1)
		(layer "In4.Cu")
		(net 333)
	)
	(segment
		(start 212.73 125.3)
		(end 215.0185 127.5885)
		(width 0.1)
		(layer "In4.Cu")
		(net 333)
	)
	(segment
		(start 215.0185 133.1685)
		(end 215.7 133.85)
		(width 0.1)
		(layer "In4.Cu")
		(net 333)
	)
	(segment
		(start 199.35 117.4)
		(end 208.9 117.4)
		(width 0.1)
		(layer "In4.Cu")
		(net 333)
	)
	(segment
		(start 209.475 124.425)
		(end 210.35 125.3)
		(width 0.1)
		(layer "In4.Cu")
		(net 333)
	)
	(segment
		(start 198.612417 118.13)
		(end 198.62 118.13)
		(width 0.1)
		(layer "In4.Cu")
		(net 333)
	)
	(segment
		(start 210.05 120.30538)
		(end 209.475 120.88038)
		(width 0.1)
		(layer "In4.Cu")
		(net 333)
	)
	(segment
		(start 210.35 125.3)
		(end 212.73 125.3)
		(width 0.1)
		(layer "In4.Cu")
		(net 333)
	)
	(segment
		(start 209.475 120.88038)
		(end 209.475 124.425)
		(width 0.1)
		(layer "In4.Cu")
		(net 333)
	)
	(segment
		(start 215.0185 127.5885)
		(end 215.0185 133.1685)
		(width 0.1)
		(layer "In4.Cu")
		(net 333)
	)
	(segment
		(start 208.9 117.4)
		(end 210.05 118.55)
		(width 0.1)
		(layer "In4.Cu")
		(net 333)
	)
	(segment
		(start 210.05 118.55)
		(end 210.05 120.30538)
		(width 0.1)
		(layer "In4.Cu")
		(net 333)
	)
	(segment
		(start 215.7 133.85)
		(end 220.975 133.85)
		(width 0.1)
		(layer "In4.Cu")
		(net 333)
	)
	(segment
		(start 198.62 118.13)
		(end 199.35 117.4)
		(width 0.1)
		(layer "In4.Cu")
		(net 333)
	)
	(segment
		(start 197.429264 120.075)
		(end 194.66595 120.075)
		(width 0.15)
		(layer "In7.Cu")
		(net 333)
	)
	(segment
		(start 198.182 118.560417)
		(end 198.182 119.322264)
		(width 0.15)
		(layer "In7.Cu")
		(net 333)
	)
	(segment
		(start 198.182 119.322264)
		(end 197.429264 120.075)
		(width 0.15)
		(layer "In7.Cu")
		(net 333)
	)
	(segment
		(start 194.66595 120.075)
		(end 193.555 118.96405)
		(width 0.15)
		(layer "In7.Cu")
		(net 333)
	)
	(segment
		(start 206.34 127.74)
		(end 206.1 127.5)
		(width 0.2)
		(layer "F.Cu")
		(net 334)
	)
	(segment
		(start 218.495 134.775)
		(end 218.495 132.4995)
		(width 0.2)
		(layer "F.Cu")
		(net 334)
	)
	(segment
		(start 213.47 129.95)
		(end 212.97 130.45)
		(width 0.2)
		(layer "F.Cu")
		(net 334)
	)
	(segment
		(start 215.4405 128.95)
		(end 214.4405 129.95)
		(width 0.2)
		(layer "F.Cu")
		(net 334)
	)
	(segment
		(start 217.9425 131.947)
		(end 216.817 131.947)
		(width 0.2)
		(layer "F.Cu")
		(net 334)
	)
	(segment
		(start 210.32 129.55)
		(end 210.32 128.2)
		(width 0.2)
		(layer "F.Cu")
		(net 334)
	)
	(segment
		(start 216.42 129.4275)
		(end 215.9425 128.95)
		(width 0.2)
		(layer "F.Cu")
		(net 334)
	)
	(segment
		(start 211.22 130.45)
		(end 210.32 129.55)
		(width 0.2)
		(layer "F.Cu")
		(net 334)
	)
	(segment
		(start 210.32 128.2)
		(end 209.86 127.74)
		(width 0.2)
		(layer "F.Cu")
		(net 334)
	)
	(segment
		(start 215.9425 128.95)
		(end 215.4405 128.95)
		(width 0.2)
		(layer "F.Cu")
		(net 334)
	)
	(segment
		(start 216.42 131.55)
		(end 216.42 129.4275)
		(width 0.2)
		(layer "F.Cu")
		(net 334)
	)
	(segment
		(start 216.817 131.947)
		(end 216.42 131.55)
		(width 0.2)
		(layer "F.Cu")
		(net 334)
	)
	(segment
		(start 214.4405 129.95)
		(end 213.47 129.95)
		(width 0.2)
		(layer "F.Cu")
		(net 334)
	)
	(segment
		(start 209.86 127.74)
		(end 206.34 127.74)
		(width 0.2)
		(layer "F.Cu")
		(net 334)
	)
	(segment
		(start 218.495 132.4995)
		(end 217.9425 131.947)
		(width 0.2)
		(layer "F.Cu")
		(net 334)
	)
	(segment
		(start 212.97 130.45)
		(end 211.22 130.45)
		(width 0.2)
		(layer "F.Cu")
		(net 334)
	)
	(via
		(at 218.495 134.775)
		(size 0.35)
		(drill 0.15)
		(layers "F.Cu" "B.Cu")
		(net 334)
	)
	(segment
		(start 218.601 133.729)
		(end 218.601 134.669)
		(width 0.256)
		(layer "B.Cu")
		(net 334)
	)
	(segment
		(start 218.601 134.669)
		(end 218.495 134.775)
		(width 0.256)
		(layer "B.Cu")
		(net 334)
	)
	(via
		(at 205.649 146.751)
		(size 0.35)
		(drill 0.15)
		(layers "F.Cu" "B.Cu")
		(remove_unused_layers yes)
		(keep_end_layers yes)
		(zone_layer_connections)
		(net 335)
	)
	(via
		(at 192.499 141.101)
		(size 0.35)
		(drill 0.15)
		(layers "F.Cu" "B.Cu")
		(remove_unused_layers yes)
		(keep_end_layers yes)
		(zone_layer_connections)
		(net 335)
	)
	(segment
		(start 200.31438 145.776)
		(end 199.97 145.43162)
		(width 0.09)
		(layer "In11.Cu")
		(net 335)
	)
	(segment
		(start 199.01519 142.90519)
		(end 197.57 141.46)
		(width 0.09)
		(layer "In11.Cu")
		(net 335)
	)
	(segment
		(start 201.53 146.426)
		(end 200.96438 146.426)
		(width 0.09)
		(layer "In11.Cu")
		(net 335)
	)
	(segment
		(start 199.97 144.78962)
		(end 199.01519 143.83481)
		(width 0.09)
		(layer "In11.Cu")
		(net 335)
	)
	(segment
		(start 200.774 145.96638)
		(end 200.58362 145.776)
		(width 0.09)
		(layer "In11.Cu")
		(net 335)
	)
	(segment
		(start 199.01519 143.83481)
		(end 199.01519 142.90519)
		(width 0.09)
		(layer "In11.Cu")
		(net 335)
	)
	(segment
		(start 203.56438 147.726)
		(end 203.374 147.53562)
		(width 0.09)
		(layer "In11.Cu")
		(net 335)
	)
	(segment
		(start 200.774 146.23562)
		(end 200.774 145.96638)
		(width 0.09)
		(layer "In11.Cu")
		(net 335)
	)
	(segment
		(start 203.374 147.53562)
		(end 203.374 146.834)
		(width 0.09)
		(layer "In11.Cu")
		(net 335)
	)
	(segment
		(start 199.97 145.43162)
		(end 199.97 144.78962)
		(width 0.09)
		(layer "In11.Cu")
		(net 335)
	)
	(segment
		(start 203.374 146.834)
		(end 202.966 146.426)
		(width 0.09)
		(layer "In11.Cu")
		(net 335)
	)
	(segment
		(start 205.649 146.751)
		(end 205.649 147.256)
		(width 0.09)
		(layer "In11.Cu")
		(net 335)
	)
	(segment
		(start 192.801 141.101)
		(end 192.499 141.101)
		(width 0.09)
		(layer "In11.Cu")
		(net 335)
	)
	(segment
		(start 201.919525 146.515525)
		(end 201.919525 146.515526)
		(width 0.09)
		(layer "In11.Cu")
		(net 335)
	)
	(segment
		(start 205.649 147.256)
		(end 205.179 147.726)
		(width 0.09)
		(layer "In11.Cu")
		(net 335)
	)
	(segment
		(start 201.619525 146.515526)
		(end 201.619525 146.515525)
		(width 0.09)
		(layer "In11.Cu")
		(net 335)
	)
	(segment
		(start 193.16 141.46)
		(end 192.801 141.101)
		(width 0.09)
		(layer "In11.Cu")
		(net 335)
	)
	(segment
		(start 200.58362 145.776)
		(end 200.31438 145.776)
		(width 0.09)
		(layer "In11.Cu")
		(net 335)
	)
	(segment
		(start 205.179 147.726)
		(end 203.56438 147.726)
		(width 0.09)
		(layer "In11.Cu")
		(net 335)
	)
	(segment
		(start 202.966 146.426)
		(end 202.00905 146.426)
		(width 0.09)
		(layer "In11.Cu")
		(net 335)
	)
	(segment
		(start 197.57 141.46)
		(end 193.16 141.46)
		(width 0.09)
		(layer "In11.Cu")
		(net 335)
	)
	(segment
		(start 200.96438 146.426)
		(end 200.774 146.23562)
		(width 0.09)
		(layer "In11.Cu")
		(net 335)
	)
	(segment
		(start 201.83 146.605051)
		(end 201.70905 146.605051)
		(width 0.09)
		(layer "In11.Cu")
		(net 335)
	)
	(arc
		(start 202.00905 146.426)
		(mid 201.945746 146.452221)
		(end 201.919525 146.515525)
		(width 0.09)
		(layer "In11.Cu")
		(net 335)
	)
	(arc
		(start 201.919525 146.515526)
		(mid 201.893304 146.57883)
		(end 201.83 146.605051)
		(width 0.09)
		(layer "In11.Cu")
		(net 335)
	)
	(arc
		(start 201.619525 146.515525)
		(mid 201.593304 146.452221)
		(end 201.53 146.426)
		(width 0.09)
		(layer "In11.Cu")
		(net 335)
	)
	(arc
		(start 201.70905 146.605051)
		(mid 201.645746 146.57883)
		(end 201.619525 146.515526)
		(width 0.09)
		(layer "In11.Cu")
		(net 335)
	)
	(segment
		(start 192.1 133.501)
		(end 191.7 133.101)
		(width 0.15)
		(layer "F.Cu")
		(net 336)
	)
	(segment
		(start 198.85 142.39)
		(end 198.13 141.67)
		(width 0.15)
		(layer "F.Cu")
		(net 336)
	)
	(segment
		(start 198.85 143.73)
		(end 198.85 142.39)
		(width 0.15)
		(layer "F.Cu")
		(net 336)
	)
	(segment
		(start 193.63 142.14)
		(end 192.43 142.14)
		(width 0.15)
		(layer "F.Cu")
		(net 336)
	)
	(segment
		(start 194.1 141.67)
		(end 193.63 142.14)
		(width 0.15)
		(layer "F.Cu")
		(net 336)
	)
	(segment
		(start 192.43 142.14)
		(end 192.1 141.81)
		(width 0.15)
		(layer "F.Cu")
		(net 336)
	)
	(segment
		(start 198.13 141.67)
		(end 194.1 141.67)
		(width 0.15)
		(layer "F.Cu")
		(net 336)
	)
	(segment
		(start 192.1 141.81)
		(end 192.1 133.501)
		(width 0.15)
		(layer "F.Cu")
		(net 336)
	)
	(via
		(at 202.399 144.151)
		(size 0.35)
		(drill 0.15)
		(layers "F.Cu" "B.Cu")
		(remove_unused_layers yes)
		(keep_end_layers yes)
		(zone_layer_connections)
		(net 337)
	)
	(via
		(at 191.7 138.7)
		(size 0.35)
		(drill 0.15)
		(layers "F.Cu" "B.Cu")
		(remove_unused_layers yes)
		(keep_end_layers yes)
		(zone_layer_connections)
		(net 337)
	)
	(segment
		(start 193.44 139.16)
		(end 193.7 139.42)
		(width 0.09)
		(layer "In11.Cu")
		(net 337)
	)
	(segment
		(start 192.9 139.96)
		(end 193.03 139.83)
		(width 0.09)
		(layer "In11.Cu")
		(net 337)
	)
	(segment
		(start 191.27 139.27)
		(end 191.43 139.27)
		(width 0.09)
		(layer "In11.Cu")
		(net 337)
	)
	(segment
		(start 196.67 139.75)
		(end 196.67 139.549219)
		(width 0.09)
		(layer "In11.Cu")
		(net 337)
	)
	(segment
		(start 201.616451 144.471)
		(end 202.079 144.471)
		(width 0.09)
		(layer "In11.Cu")
		(net 337)
	)
	(segment
		(start 196.07 139.75)
		(end 196.07 139.549233)
		(width 0.09)
		(layer "In11.Cu")
		(net 337)
	)
	(segment
		(start 191.58 139.12)
		(end 191.82 139.12)
		(width 0.09)
		(layer "In11.Cu")
		(net 337)
	)
	(segment
		(start 199.379 141.079)
		(end 199.379 141.233549)
		(width 0.09)
		(layer "In11.Cu")
		(net 337)
	)
	(segment
		(start 198.45 140.35)
		(end 198.8 140.7)
		(width 0.09)
		(layer "In11.Cu")
		(net 337)
	)
	(segment
		(start 193.03 139.83)
		(end 193.03 139.71)
		(width 0.09)
		(layer "In11.Cu")
		(net 337)
	)
	(segment
		(start 191.45 138.7)
		(end 191.17 138.98)
		(width 0.09)
		(layer "In11.Cu")
		(net 337)
	)
	(segment
		(start 192.88 139.31)
		(end 193.03 139.16)
		(width 0.09)
		(layer "In11.Cu")
		(net 337)
	)
	(segment
		(start 198.8 140.7)
		(end 199 140.7)
		(width 0.09)
		(layer "In11.Cu")
		(net 337)
	)
	(segment
		(start 201.429 144.283549)
		(end 201.616451 144.471)
		(width 0.09)
		(layer "In11.Cu")
		(net 337)
	)
	(segment
		(start 200.6 142.175)
		(end 200.6 143)
		(width 0.09)
		(layer "In11.Cu")
		(net 337)
	)
	(segment
		(start 191.7 138.7)
		(end 191.45 138.7)
		(width 0.09)
		(layer "In11.Cu")
		(net 337)
	)
	(segment
		(start 199.566451 141.421)
		(end 199.846 141.421)
		(width 0.09)
		(layer "In11.Cu")
		(net 337)
	)
	(segment
		(start 192.88 139.56)
		(end 192.88 139.31)
		(width 0.09)
		(layer "In11.Cu")
		(net 337)
	)
	(segment
		(start 198.152549 139.9)
		(end 198.45 140.197451)
		(width 0.09)
		(layer "In11.Cu")
		(net 337)
	)
	(segment
		(start 202.079 144.471)
		(end 202.399 144.151)
		(width 0.09)
		(layer "In11.Cu")
		(net 337)
	)
	(segment
		(start 197.12 139.9)
		(end 198.152549 139.9)
		(width 0.09)
		(layer "In11.Cu")
		(net 337)
	)
	(segment
		(start 193.7 139.42)
		(end 193.7 139.78)
		(width 0.09)
		(layer "In11.Cu")
		(net 337)
	)
	(segment
		(start 193.82 139.9)
		(end 195.92 139.9)
		(width 0.09)
		(layer "In11.Cu")
		(net 337)
	)
	(segment
		(start 199.379 141.233549)
		(end 199.566451 141.421)
		(width 0.09)
		(layer "In11.Cu")
		(net 337)
	)
	(segment
		(start 200.6 143)
		(end 201.429 143.829)
		(width 0.09)
		(layer "In11.Cu")
		(net 337)
	)
	(segment
		(start 198.45 140.197451)
		(end 198.45 140.35)
		(width 0.09)
		(layer "In11.Cu")
		(net 337)
	)
	(segment
		(start 196.37 139.549233)
		(end 196.37 139.75)
		(width 0.09)
		(layer "In11.Cu")
		(net 337)
	)
	(segment
		(start 191.17 139.17)
		(end 191.27 139.27)
		(width 0.09)
		(layer "In11.Cu")
		(net 337)
	)
	(segment
		(start 191.82 139.12)
		(end 192.15 139.45)
		(width 0.09)
		(layer "In11.Cu")
		(net 337)
	)
	(segment
		(start 192.506451 139.96)
		(end 192.9 139.96)
		(width 0.09)
		(layer "In11.Cu")
		(net 337)
	)
	(segment
		(start 193.03 139.16)
		(end 193.44 139.16)
		(width 0.09)
		(layer "In11.Cu")
		(net 337)
	)
	(segment
		(start 199.846 141.421)
		(end 200.6 142.175)
		(width 0.09)
		(layer "In11.Cu")
		(net 337)
	)
	(segment
		(start 196.97 139.549219)
		(end 196.97 139.75)
		(width 0.09)
		(layer "In11.Cu")
		(net 337)
	)
	(segment
		(start 191.17 138.98)
		(end 191.17 139.17)
		(width 0.09)
		(layer "In11.Cu")
		(net 337)
	)
	(segment
		(start 193.7 139.78)
		(end 193.82 139.9)
		(width 0.09)
		(layer "In11.Cu")
		(net 337)
	)
	(segment
		(start 193.03 139.71)
		(end 192.88 139.56)
		(width 0.09)
		(layer "In11.Cu")
		(net 337)
	)
	(segment
		(start 192.15 139.45)
		(end 192.15 139.603549)
		(width 0.09)
		(layer "In11.Cu")
		(net 337)
	)
	(segment
		(start 201.429 143.829)
		(end 201.429 144.283549)
		(width 0.09)
		(layer "In11.Cu")
		(net 337)
	)
	(segment
		(start 191.43 139.27)
		(end 191.58 139.12)
		(width 0.09)
		(layer "In11.Cu")
		(net 337)
	)
	(segment
		(start 192.15 139.603549)
		(end 192.506451 139.96)
		(width 0.09)
		(layer "In11.Cu")
		(net 337)
	)
	(segment
		(start 199 140.7)
		(end 199.379 141.079)
		(width 0.09)
		(layer "In11.Cu")
		(net 337)
	)
	(arc
		(start 196.07 139.549233)
		(mid 196.113934 139.443167)
		(end 196.22 139.399233)
		(width 0.09)
		(layer "In11.Cu")
		(net 337)
	)
	(arc
		(start 195.92 139.9)
		(mid 196.026066 139.856066)
		(end 196.07 139.75)
		(width 0.09)
		(layer "In11.Cu")
		(net 337)
	)
	(arc
		(start 196.82 139.399219)
		(mid 196.926066 139.443153)
		(end 196.97 139.549219)
		(width 0.09)
		(layer "In11.Cu")
		(net 337)
	)
	(arc
		(start 196.52 139.9)
		(mid 196.626066 139.856066)
		(end 196.67 139.75)
		(width 0.09)
		(layer "In11.Cu")
		(net 337)
	)
	(arc
		(start 196.37 139.75)
		(mid 196.413934 139.856066)
		(end 196.52 139.9)
		(width 0.09)
		(layer "In11.Cu")
		(net 337)
	)
	(arc
		(start 196.97 139.75)
		(mid 197.013934 139.856066)
		(end 197.12 139.9)
		(width 0.09)
		(layer "In11.Cu")
		(net 337)
	)
	(arc
		(start 196.67 139.549219)
		(mid 196.713934 139.443153)
		(end 196.82 139.399219)
		(width 0.09)
		(layer "In11.Cu")
		(net 337)
	)
	(arc
		(start 196.22 139.399233)
		(mid 196.326066 139.443167)
		(end 196.37 139.549233)
		(width 0.09)
		(layer "In11.Cu")
		(net 337)
	)
	(via
		(at 200.449 146.751)
		(size 0.35)
		(drill 0.15)
		(layers "F.Cu" "B.Cu")
		(remove_unused_layers yes)
		(keep_end_layers yes)
		(zone_layer_connections)
		(net 338)
	)
	(via
		(at 191.7 140.3)
		(size 0.35)
		(drill 0.15)
		(layers "F.Cu" "B.Cu")
		(remove_unused_layers yes)
		(keep_end_layers yes)
		(zone_layer_connections)
		(net 338)
	)
	(segment
		(start 191.62 142.27)
		(end 191.675736 142.214267)
		(width 0.09)
		(layer "In9.Cu")
		(net 338)
	)
	(segment
		(start 194.76 144.42)
		(end 194.41 144.07)
		(width 0.09)
		(layer "In9.Cu")
		(net 338)
	)
	(segment
		(start 195.1 144.77)
		(end 195.1 144.97)
		(width 0.09)
		(layer "In9.Cu")
		(net 338)
	)
	(segment
		(start 191.73 140.3)
		(end 191.7 140.3)
		(width 0.09)
		(layer "In9.Cu")
		(net 338)
	)
	(segment
		(start 192.099999 142.002134)
		(end 192.1 142.002134)
		(width 0.09)
		(layer "In9.Cu")
		(net 338)
	)
	(segment
		(start 196.3 144.87)
		(end 196.3 144.97)
		(width 0.09)
		(layer "In9.Cu")
		(net 338)
	)
	(segment
		(start 192.012868 142.934668)
		(end 191.977511 142.970024)
		(width 0.09)
		(layer "In9.Cu")
		(net 338)
	)
	(segment
		(start 192.29 143.53)
		(end 192.225 143.465)
		(width 0.09)
		(layer "In9.Cu")
		(net 338)
	)
	(segment
		(start 192.94 143.38)
		(end 192.94 143.03)
		(width 0.09)
		(layer "In9.Cu")
		(net 338)
	)
	(segment
		(start 191.887868 142.214267)
		(end 191.993934 142.320333)
		(width 0.09)
		(layer "In9.Cu")
		(net 338)
	)
	(segment
		(start 194.95 145.12)
		(end 194.89 145.12)
		(width 0.09)
		(layer "In9.Cu")
		(net 338)
	)
	(segment
		(start 197.53 145.12)
		(end 197.35 145.12)
		(width 0.09)
		(layer "In9.Cu")
		(net 338)
	)
	(segment
		(start 200.449 146.751)
		(end 199.161 146.751)
		(width 0.09)
		(layer "In9.Cu")
		(net 338)
	)
	(segment
		(start 191.730023 142.970024)
		(end 191.62 142.86)
		(width 0.09)
		(layer "In9.Cu")
		(net 338)
	)
	(segment
		(start 192.1 140.67)
		(end 191.73 140.3)
		(width 0.09)
		(layer "In9.Cu")
		(net 338)
	)
	(segment
		(start 196 144.97)
		(end 196 144.87)
		(width 0.09)
		(layer "In9.Cu")
		(net 338)
	)
	(segment
		(start 194.89 145.12)
		(end 194.76 144.99)
		(width 0.09)
		(layer "In9.Cu")
		(net 338)
	)
	(segment
		(start 196.6 144.97)
		(end 196.6 144.87)
		(width 0.09)
		(layer "In9.Cu")
		(net 338)
	)
	(segment
		(start 196.9 144.72)
		(end 196.9 144.97)
		(width 0.09)
		(layer "In9.Cu")
		(net 338)
	)
	(segment
		(start 194.76 144.99)
		(end 194.76 144.42)
		(width 0.09)
		(layer "In9.Cu")
		(net 338)
	)
	(segment
		(start 192.206066 142.320333)
		(end 192.206065 142.320334)
		(width 0.09)
		(layer "In9.Cu")
		(net 338)
	)
	(segment
		(start 199.161 146.751)
		(end 197.53 145.12)
		(width 0.09)
		(layer "In9.Cu")
		(net 338)
	)
	(segment
		(start 194.41 144.07)
		(end 194.41 143.9)
		(width 0.09)
		(layer "In9.Cu")
		(net 338)
	)
	(segment
		(start 197.2 144.97)
		(end 197.2 144.72)
		(width 0.09)
		(layer "In9.Cu")
		(net 338)
	)
	(segment
		(start 192.1 141.79)
		(end 192.1 140.67)
		(width 0.09)
		(layer "In9.Cu")
		(net 338)
	)
	(segment
		(start 192.64 143.03)
		(end 192.64 143.38)
		(width 0.09)
		(layer "In9.Cu")
		(net 338)
	)
	(segment
		(start 195.4 144.97)
		(end 195.4 144.77)
		(width 0.09)
		(layer "In9.Cu")
		(net 338)
	)
	(segment
		(start 191.62 142.86)
		(end 191.62 142.27)
		(width 0.09)
		(layer "In9.Cu")
		(net 338)
	)
	(segment
		(start 194.04 143.53)
		(end 193.09 143.53)
		(width 0.09)
		(layer "In9.Cu")
		(net 338)
	)
	(segment
		(start 192.224999 143.217513)
		(end 192.260355 143.182156)
		(width 0.09)
		(layer "In9.Cu")
		(net 338)
	)
	(segment
		(start 192.260355 142.934668)
		(end 192.260355 142.934669)
		(width 0.09)
		(layer "In9.Cu")
		(net 338)
	)
	(segment
		(start 194.41 143.9)
		(end 194.04 143.53)
		(width 0.09)
		(layer "In9.Cu")
		(net 338)
	)
	(segment
		(start 192.49 143.53)
		(end 192.29 143.53)
		(width 0.09)
		(layer "In9.Cu")
		(net 338)
	)
	(segment
		(start 195.7 144.87)
		(end 195.7 144.97)
		(width 0.09)
		(layer "In9.Cu")
		(net 338)
	)
	(segment
		(start 192.206066 142.108201)
		(end 192.099999 142.002134)
		(width 0.09)
		(layer "In9.Cu")
		(net 338)
	)
	(arc
		(start 196.75 145.12)
		(mid 196.643934 145.076066)
		(end 196.6 144.97)
		(width 0.09)
		(layer "In9.Cu")
		(net 338)
	)
	(arc
		(start 196.15 145.12)
		(mid 196.043934 145.076066)
		(end 196 144.97)
		(width 0.09)
		(layer "In9.Cu")
		(net 338)
	)
	(arc
		(start 195.1 144.97)
		(mid 195.056066 145.076066)
		(end 194.95 145.12)
		(width 0.09)
		(layer "In9.Cu")
		(net 338)
	)
	(arc
		(start 191.993934 142.320333)
		(mid 192.1 142.364267)
		(end 192.206066 142.320333)
		(width 0.09)
		(layer "In9.Cu")
		(net 338)
	)
	(arc
		(start 197.35 145.12)
		(mid 197.243934 145.076066)
		(end 197.2 144.97)
		(width 0.09)
		(layer "In9.Cu")
		(net 338)
	)
	(arc
		(start 195.25 144.62)
		(mid 195.143934 144.663934)
		(end 195.1 144.77)
		(width 0.09)
		(layer "In9.Cu")
		(net 338)
	)
	(arc
		(start 196.9 144.97)
		(mid 196.856066 145.076066)
		(end 196.75 145.12)
		(width 0.09)
		(layer "In9.Cu")
		(net 338)
	)
	(arc
		(start 196.6 144.87)
		(mid 196.556066 144.763934)
		(end 196.45 144.72)
		(width 0.09)
		(layer "In9.Cu")
		(net 338)
	)
	(arc
		(start 196.45 144.72)
		(mid 196.343934 144.763934)
		(end 196.3 144.87)
		(width 0.09)
		(layer "In9.Cu")
		(net 338)
	)
	(arc
		(start 191.977511 142.970024)
		(mid 191.853767 143.02128)
		(end 191.730023 142.970024)
		(width 0.09)
		(layer "In9.Cu")
		(net 338)
	)
	(arc
		(start 192.225 143.465)
		(mid 192.173743 143.341257)
		(end 192.224999 143.217513)
		(width 0.09)
		(layer "In9.Cu")
		(net 338)
	)
	(arc
		(start 196 144.87)
		(mid 195.956066 144.763934)
		(end 195.85 144.72)
		(width 0.09)
		(layer "In9.Cu")
		(net 338)
	)
	(arc
		(start 193.09 143.53)
		(mid 192.983934 143.486066)
		(end 192.94 143.38)
		(width 0.09)
		(layer "In9.Cu")
		(net 338)
	)
	(arc
		(start 191.675736 142.214267)
		(mid 191.781802 142.170333)
		(end 191.887868 142.214267)
		(width 0.09)
		(layer "In9.Cu")
		(net 338)
	)
	(arc
		(start 195.4 144.77)
		(mid 195.356066 144.663934)
		(end 195.25 144.62)
		(width 0.09)
		(layer "In9.Cu")
		(net 338)
	)
	(arc
		(start 195.55 145.12)
		(mid 195.443934 145.076066)
		(end 195.4 144.97)
		(width 0.09)
		(layer "In9.Cu")
		(net 338)
	)
	(arc
		(start 196.3 144.97)
		(mid 196.256066 145.076066)
		(end 196.15 145.12)
		(width 0.09)
		(layer "In9.Cu")
		(net 338)
	)
	(arc
		(start 192.79 142.88)
		(mid 192.683934 142.923934)
		(end 192.64 143.03)
		(width 0.09)
		(layer "In9.Cu")
		(net 338)
	)
	(arc
		(start 197.05 144.57)
		(mid 196.943934 144.613934)
		(end 196.9 144.72)
		(width 0.09)
		(layer "In9.Cu")
		(net 338)
	)
	(arc
		(start 195.85 144.72)
		(mid 195.743934 144.763934)
		(end 195.7 144.87)
		(width 0.09)
		(layer "In9.Cu")
		(net 338)
	)
	(arc
		(start 192.206065 142.320334)
		(mid 192.250001 142.214267)
		(end 192.206066 142.108201)
		(width 0.09)
		(layer "In9.Cu")
		(net 338)
	)
	(arc
		(start 192.260355 142.934669)
		(mid 192.136612 142.883412)
		(end 192.012868 142.934668)
		(width 0.09)
		(layer "In9.Cu")
		(net 338)
	)
	(arc
		(start 192.260355 143.182156)
		(mid 192.311611 143.058412)
		(end 192.260355 142.934668)
		(width 0.09)
		(layer "In9.Cu")
		(net 338)
	)
	(arc
		(start 192.1 142.002134)
		(mid 192.056065 141.896068)
		(end 192.1 141.79)
		(width 0.09)
		(layer "In9.Cu")
		(net 338)
	)
	(arc
		(start 195.7 144.97)
		(mid 195.656066 145.076066)
		(end 195.55 145.12)
		(width 0.09)
		(layer "In9.Cu")
		(net 338)
	)
	(arc
		(start 192.94 143.03)
		(mid 192.896066 142.923934)
		(end 192.79 142.88)
		(width 0.09)
		(layer "In9.Cu")
		(net 338)
	)
	(arc
		(start 192.64 143.38)
		(mid 192.596066 143.486066)
		(end 192.49 143.53)
		(width 0.09)
		(layer "In9.Cu")
		(net 338)
	)
	(arc
		(start 197.2 144.72)
		(mid 197.156066 144.613934)
		(end 197.05 144.57)
		(width 0.09)
		(layer "In9.Cu")
		(net 338)
	)
	(via
		(at 206.299 146.751)
		(size 0.35)
		(drill 0.15)
		(layers "F.Cu" "B.Cu")
		(remove_unused_layers yes)
		(keep_end_layers yes)
		(zone_layer_connections)
		(net 339)
	)
	(via
		(at 191.7 141.101)
		(size 0.35)
		(drill 0.15)
		(layers "F.Cu" "B.Cu")
		(remove_unused_layers yes)
		(keep_end_layers yes)
		(zone_layer_connections)
		(net 339)
	)
	(segment
		(start 192.609 142.01)
		(end 191.7 141.101)
		(width 0.09)
		(layer "In7.Cu")
		(net 339)
	)
	(segment
		(start 200.276 146.426)
		(end 200.04 146.19)
		(width 0.09)
		(layer "In7.Cu")
		(net 339)
	)
	(segment
		(start 196.21 142.9)
		(end 195.32 142.01)
		(width 0.09)
		(layer "In7.Cu")
		(net 339)
	)
	(segment
		(start 206.77 147.48)
		(end 206.524 147.726)
		(width 0.09)
		(layer "In7.Cu")
		(net 339)
	)
	(segment
		(start 206.524 147.726)
		(end 205.65437 147.726)
		(width 0.09)
		(layer "In7.Cu")
		(net 339)
	)
	(segment
		(start 206.299 146.751)
		(end 206.581 146.751)
		(width 0.09)
		(layer "In7.Cu")
		(net 339)
	)
	(segment
		(start 202.016 147.076)
		(end 201.366 146.426)
		(width 0.09)
		(layer "In7.Cu")
		(net 339)
	)
	(segment
		(start 201.366 146.426)
		(end 200.276 146.426)
		(width 0.09)
		(layer "In7.Cu")
		(net 339)
	)
	(segment
		(start 200.04 145.979104)
		(end 196.820896 142.76)
		(width 0.09)
		(layer "In7.Cu")
		(net 339)
	)
	(segment
		(start 205.00437 147.076)
		(end 202.016 147.076)
		(width 0.09)
		(layer "In7.Cu")
		(net 339)
	)
	(segment
		(start 196.820896 142.76)
		(end 196.6 142.76)
		(width 0.09)
		(layer "In7.Cu")
		(net 339)
	)
	(segment
		(start 200.04 146.19)
		(end 200.04 145.979104)
		(width 0.09)
		(layer "In7.Cu")
		(net 339)
	)
	(segment
		(start 195.32 142.01)
		(end 192.609 142.01)
		(width 0.09)
		(layer "In7.Cu")
		(net 339)
	)
	(segment
		(start 205.65437 147.726)
		(end 205.00437 147.076)
		(width 0.09)
		(layer "In7.Cu")
		(net 339)
	)
	(segment
		(start 206.77 146.94)
		(end 206.77 147.48)
		(width 0.09)
		(layer "In7.Cu")
		(net 339)
	)
	(segment
		(start 196.6 142.76)
		(end 196.46 142.9)
		(width 0.09)
		(layer "In7.Cu")
		(net 339)
	)
	(segment
		(start 196.46 142.9)
		(end 196.21 142.9)
		(width 0.09)
		(layer "In7.Cu")
		(net 339)
	)
	(segment
		(start 206.581 146.751)
		(end 206.77 146.94)
		(width 0.09)
		(layer "In7.Cu")
		(net 339)
	)
	(via
		(at 202.399 144.801)
		(size 0.35)
		(drill 0.15)
		(layers "F.Cu" "B.Cu")
		(remove_unused_layers yes)
		(keep_end_layers yes)
		(zone_layer_connections)
		(net 340)
	)
	(via
		(at 190.9 139.5)
		(size 0.35)
		(drill 0.15)
		(layers "F.Cu" "B.Cu")
		(remove_unused_layers yes)
		(keep_end_layers yes)
		(zone_layer_connections)
		(net 340)
	)
	(segment
		(start 202.32 145.17)
		(end 202.32 145.59)
		(width 0.09)
		(layer "In11.Cu")
		(net 340)
	)
	(segment
		(start 201.425 144.66538)
		(end 201.23462 144.475)
		(width 0.09)
		(layer "In11.Cu")
		(net 340)
	)
	(segment
		(start 201.23462 144.475)
		(end 200.96538 144.475)
		(width 0.09)
		(layer "In11.Cu")
		(net 340)
	)
	(segment
		(start 196.291376 140.708624)
		(end 196.291376 140.708625)
		(width 0.09)
		(layer "In11.Cu")
		(net 340)
	)
	(segment
		(start 201.425 144.93462)
		(end 201.425 144.66538)
		(width 0.09)
		(layer "In11.Cu")
		(net 340)
	)
	(segment
		(start 198.666421 141.789974)
		(end 198.666422 141.789973)
		(width 0.09)
		(layer "In11.Cu")
		(net 340)
	)
	(segment
		(start 192.025 140.115)
		(end 191.75 139.84)
		(width 0.09)
		(layer "In11.Cu")
		(net 340)
	)
	(segment
		(start 198.737131 141.719263)
		(end 198.666421 141.789974)
		(width 0.09)
		(layer "In11.Cu")
		(net 340)
	)
	(segment
		(start 200.774 145.58562)
		(end 200.774 145.31638)
		(width 0.09)
		(layer "In11.Cu")
		(net 340)
	)
	(segment
		(start 198.44 140.98138)
		(end 198.08862 140.63)
		(width 0.09)
		(layer "In11.Cu")
		(net 340)
	)
	(segment
		(start 200.22 143.46238)
		(end 200.22 142.41038)
		(width 0.09)
		(layer "In11.Cu")
		(net 340)
	)
	(segment
		(start 200.774 144.01638)
		(end 200.22 143.46238)
		(width 0.09)
		(layer "In11.Cu")
		(net 340)
	)
	(segment
		(start 192.22038 140.63)
		(end 195.912752 140.63)
		(width 0.09)
		(layer "In11.Cu")
		(net 340)
	)
	(segment
		(start 192.22038 140.63)
		(end 192.025 140.43462)
		(width 0.09)
		(layer "In11.Cu")
		(net 340)
	)
	(segment
		(start 196.37 140.63)
		(end 196.63 140.63)
		(width 0.09)
		(layer "In11.Cu")
		(net 340)
	)
	(segment
		(start 201.42 145.776)
		(end 200.96438 145.776)
		(width 0.09)
		(layer "In11.Cu")
		(net 340)
	)
	(segment
		(start 201.87 145.626)
		(end 201.87 145.376)
		(width 0.09)
		(layer "In11.Cu")
		(net 340)
	)
	(segment
		(start 200.774 145.31638)
		(end 200.96538 145.125)
		(width 0.09)
		(layer "In11.Cu")
		(net 340)
	)
	(segment
		(start 202.399 144.801)
		(end 202.399 145.091)
		(width 0.09)
		(layer "In11.Cu")
		(net 340)
	)
	(segment
		(start 200.96538 144.475)
		(end 200.774 144.28362)
		(width 0.09)
		(layer "In11.Cu")
		(net 340)
	)
	(segment
		(start 199.58462 141.775)
		(end 199.005 141.775)
		(width 0.09)
		(layer "In11.Cu")
		(net 340)
	)
	(segment
		(start 198.44 141.21)
		(end 198.44 140.98138)
		(width 0.09)
		(layer "In11.Cu")
		(net 340)
	)
	(segment
		(start 200.22 142.41038)
		(end 199.58462 141.775)
		(width 0.09)
		(layer "In11.Cu")
		(net 340)
	)
	(segment
		(start 200.96538 145.125)
		(end 201.23462 145.125)
		(width 0.09)
		(layer "In11.Cu")
		(net 340)
	)
	(segment
		(start 201.23462 145.125)
		(end 201.425 144.93462)
		(width 0.09)
		(layer "In11.Cu")
		(net 340)
	)
	(segment
		(start 191.24 139.84)
		(end 190.9 139.5)
		(width 0.09)
		(layer "In11.Cu")
		(net 340)
	)
	(segment
		(start 202.134 145.776)
		(end 202.02 145.776)
		(width 0.09)
		(layer "In11.Cu")
		(net 340)
	)
	(segment
		(start 200.774 144.28362)
		(end 200.774 144.01638)
		(width 0.09)
		(layer "In11.Cu")
		(net 340)
	)
	(segment
		(start 198.525 141.507132)
		(end 198.524999 141.507133)
		(width 0.09)
		(layer "In11.Cu")
		(net 340)
	)
	(segment
		(start 196.212752 140.787249)
		(end 196.07 140.787249)
		(width 0.09)
		(layer "In11.Cu")
		(net 340)
	)
	(segment
		(start 192.025 140.43462)
		(end 192.025 140.115)
		(width 0.09)
		(layer "In11.Cu")
		(net 340)
	)
	(segment
		(start 200.96438 145.776)
		(end 200.774 145.58562)
		(width 0.09)
		(layer "In11.Cu")
		(net 340)
	)
	(segment
		(start 202.32 145.59)
		(end 202.134 145.776)
		(width 0.09)
		(layer "In11.Cu")
		(net 340)
	)
	(segment
		(start 198.08862 140.63)
		(end 197.18 140.63)
		(width 0.09)
		(layer "In11.Cu")
		(net 340)
	)
	(segment
		(start 198.454289 141.577842)
		(end 198.525 141.507132)
		(width 0.09)
		(layer "In11.Cu")
		(net 340)
	)
	(segment
		(start 201.57 145.376)
		(end 201.57 145.626)
		(width 0.09)
		(layer "In11.Cu")
		(net 340)
	)
	(segment
		(start 198.525 141.295)
		(end 198.44 141.21)
		(width 0.09)
		(layer "In11.Cu")
		(net 340)
	)
	(segment
		(start 202.399 145.091)
		(end 202.32 145.17)
		(width 0.09)
		(layer "In11.Cu")
		(net 340)
	)
	(segment
		(start 191.75 139.84)
		(end 191.24 139.84)
		(width 0.09)
		(layer "In11.Cu")
		(net 340)
	)
	(segment
		(start 195.991376 140.708625)
		(end 195.991376 140.708624)
		(width 0.09)
		(layer "In11.Cu")
		(net 340)
	)
	(segment
		(start 196.93 140.88)
		(end 196.88 140.88)
		(width 0.09)
		(layer "In11.Cu")
		(net 340)
	)
	(segment
		(start 199.005 141.775)
		(end 198.949263 141.719263)
		(width 0.09)
		(layer "In11.Cu")
		(net 340)
	)
	(arc
		(start 201.72 145.226)
		(mid 201.613934 145.269934)
		(end 201.57 145.376)
		(width 0.09)
		(layer "In11.Cu")
		(net 340)
	)
	(arc
		(start 198.949263 141.719263)
		(mid 198.843197 141.675329)
		(end 198.737131 141.719263)
		(width 0.09)
		(layer "In11.Cu")
		(net 340)
	)
	(arc
		(start 197.055 140.755)
		(mid 197.018388 140.843388)
		(end 196.93 140.88)
		(width 0.09)
		(layer "In11.Cu")
		(net 340)
	)
	(arc
		(start 202.02 145.776)
		(mid 201.913934 145.732066)
		(end 201.87 145.626)
		(width 0.09)
		(layer "In11.Cu")
		(net 340)
	)
	(arc
		(start 201.87 145.376)
		(mid 201.826066 145.269934)
		(end 201.72 145.226)
		(width 0.09)
		(layer "In11.Cu")
		(net 340)
	)
	(arc
		(start 197.18 140.63)
		(mid 197.091612 140.666612)
		(end 197.055 140.755)
		(width 0.09)
		(layer "In11.Cu")
		(net 340)
	)
	(arc
		(start 195.991376 140.708624)
		(mid 195.968348 140.653028)
		(end 195.912752 140.63)
		(width 0.09)
		(layer "In11.Cu")
		(net 340)
	)
	(arc
		(start 196.755 140.755)
		(mid 196.718388 140.666612)
		(end 196.63 140.63)
		(width 0.09)
		(layer "In11.Cu")
		(net 340)
	)
	(arc
		(start 201.57 145.626)
		(mid 201.526066 145.732066)
		(end 201.42 145.776)
		(width 0.09)
		(layer "In11.Cu")
		(net 340)
	)
	(arc
		(start 198.454289 141.789974)
		(mid 198.410355 141.683908)
		(end 198.454289 141.577842)
		(width 0.09)
		(layer "In11.Cu")
		(net 340)
	)
	(arc
		(start 198.524999 141.507133)
		(mid 198.568934 141.401067)
		(end 198.525 141.295)
		(width 0.09)
		(layer "In11.Cu")
		(net 340)
	)
	(arc
		(start 198.666422 141.789973)
		(mid 198.560356 141.833908)
		(end 198.454289 141.789974)
		(width 0.09)
		(layer "In11.Cu")
		(net 340)
	)
	(arc
		(start 196.291376 140.708625)
		(mid 196.268348 140.764221)
		(end 196.212752 140.787249)
		(width 0.09)
		(layer "In11.Cu")
		(net 340)
	)
	(arc
		(start 196.37 140.63)
		(mid 196.314404 140.653028)
		(end 196.291376 140.708624)
		(width 0.09)
		(layer "In11.Cu")
		(net 340)
	)
	(arc
		(start 196.07 140.787249)
		(mid 196.014404 140.764221)
		(end 195.991376 140.708625)
		(width 0.09)
		(layer "In11.Cu")
		(net 340)
	)
	(arc
		(start 196.88 140.88)
		(mid 196.791612 140.843388)
		(end 196.755 140.755)
		(width 0.09)
		(layer "In11.Cu")
		(net 340)
	)
	(segment
		(start 207.6 133.05)
		(end 207.6 136.35)
		(width 0.1)
		(layer "F.Cu")
		(net 341)
	)
	(segment
		(start 223.375 135.525)
		(end 223.375 134.625)
		(width 0.1)
		(layer "F.Cu")
		(net 341)
	)
	(segment
		(start 202.9 132.3)
		(end 203.3 131.9)
		(width 0.1)
		(layer "F.Cu")
		(net 341)
	)
	(segment
		(start 220.45 137.6)
		(end 221.3 137.6)
		(width 0.1)
		(layer "F.Cu")
		(net 341)
	)
	(segment
		(start 223.375 134.625)
		(end 223.8 134.2)
		(width 0.1)
		(layer "F.Cu")
		(net 341)
	)
	(segment
		(start 207.6 136.35)
		(end 208.765 137.515)
		(width 0.1)
		(layer "F.Cu")
		(net 341)
	)
	(segment
		(start 210.429623 137.6)
		(end 215.775 137.6)
		(width 0.1)
		(layer "F.Cu")
		(net 341)
	)
	(segment
		(start 216.4 138.225)
		(end 219.825 138.225)
		(width 0.1)
		(layer "F.Cu")
		(net 341)
	)
	(segment
		(start 219.825 138.225)
		(end 220.45 137.6)
		(width 0.1)
		(layer "F.Cu")
		(net 341)
	)
	(segment
		(start 210.344623 137.515)
		(end 210.429623 137.6)
		(width 0.1)
		(layer "F.Cu")
		(net 341)
	)
	(segment
		(start 206.45 131.9)
		(end 207.6 133.05)
		(width 0.1)
		(layer "F.Cu")
		(net 341)
	)
	(segment
		(start 221.3 137.6)
		(end 223.375 135.525)
		(width 0.1)
		(layer "F.Cu")
		(net 341)
	)
	(segment
		(start 215.775 137.6)
		(end 216.4 138.225)
		(width 0.1)
		(layer "F.Cu")
		(net 341)
	)
	(segment
		(start 203.3 131.9)
		(end 206.45 131.9)
		(width 0.1)
		(layer "F.Cu")
		(net 341)
	)
	(segment
		(start 208.765 137.515)
		(end 210.344623 137.515)
		(width 0.1)
		(layer "F.Cu")
		(net 341)
	)
	(via
		(at 223.8 134.2)
		(size 0.35)
		(drill 0.15)
		(layers "F.Cu" "B.Cu")
		(remove_unused_layers yes)
		(keep_end_layers yes)
		(zone_layer_connections)
		(net 341)
	)
	(segment
		(start 223.8 134.2)
		(end 223.325 133.725)
		(width 0.1)
		(layer "B.Cu")
		(net 341)
	)
	(segment
		(start 223.80196 132.164634)
		(end 224.295366 132.164634)
		(width 0.1)
		(layer "B.Cu")
		(net 341)
	)
	(segment
		(start 223.325 132.641594)
		(end 223.80196 132.164634)
		(width 0.1)
		(layer "B.Cu")
		(net 341)
	)
	(segment
		(start 224.88 131.585)
		(end 224.865 131.6)
		(width 0.15)
		(layer "B.Cu")
		(net 341)
	)
	(segment
		(start 224.295366 132.164634)
		(end 224.86 131.6)
		(width 0.1)
		(layer "B.Cu")
		(net 341)
	)
	(segment
		(start 224.88 130.55)
		(end 224.88 131.585)
		(width 0.15)
		(layer "B.Cu")
		(net 341)
	)
	(segment
		(start 223.325 133.725)
		(end 223.325 132.641594)
		(width 0.1)
		(layer "B.Cu")
		(net 341)
	)
	(segment
		(start 207.15 133.375)
		(end 207.15 136.55)
		(width 0.1)
		(layer "F.Cu")
		(net 342)
	)
	(segment
		(start 221.4 138.15)
		(end 223.7 135.85)
		(width 0.1)
		(layer "F.Cu")
		(net 342)
	)
	(segment
		(start 210.344623 138.165)
		(end 210.509623 138)
		(width 0.1)
		(layer "F.Cu")
		(net 342)
	)
	(segment
		(start 203.699 133.101)
		(end 204.1 132.7)
		(width 0.1)
		(layer "F.Cu")
		(net 342)
	)
	(segment
		(start 220.325 138.775)
		(end 220.95 138.15)
		(width 0.1)
		(layer "F.Cu")
		(net 342)
	)
	(segment
		(start 223.7 135)
		(end 224.5 134.2)
		(width 0.1)
		(layer "F.Cu")
		(net 342)
	)
	(segment
		(start 223.7 135.85)
		(end 223.7 135)
		(width 0.1)
		(layer "F.Cu")
		(net 342)
	)
	(segment
		(start 206.475 132.7)
		(end 207.15 133.375)
		(width 0.1)
		(layer "F.Cu")
		(net 342)
	)
	(segment
		(start 220.95 138.15)
		(end 221.4 138.15)
		(width 0.1)
		(layer "F.Cu")
		(net 342)
	)
	(segment
		(start 216.225 138.775)
		(end 220.325 138.775)
		(width 0.1)
		(layer "F.Cu")
		(net 342)
	)
	(segment
		(start 207.15 136.55)
		(end 208.765 138.165)
		(width 0.1)
		(layer "F.Cu")
		(net 342)
	)
	(segment
		(start 208.765 138.165)
		(end 210.344623 138.165)
		(width 0.1)
		(layer "F.Cu")
		(net 342)
	)
	(segment
		(start 215.45 138)
		(end 216.225 138.775)
		(width 0.1)
		(layer "F.Cu")
		(net 342)
	)
	(segment
		(start 204.1 132.7)
		(end 206.475 132.7)
		(width 0.1)
		(layer "F.Cu")
		(net 342)
	)
	(segment
		(start 210.509623 138)
		(end 215.45 138)
		(width 0.1)
		(layer "F.Cu")
		(net 342)
	)
	(via
		(at 224.5 134.2)
		(size 0.35)
		(drill 0.15)
		(layers "F.Cu" "B.Cu")
		(remove_unused_layers yes)
		(keep_end_layers yes)
		(zone_layer_connections)
		(net 342)
	)
	(segment
		(start 227.18 131.585)
		(end 227.165 131.6)
		(width 0.15)
		(layer "B.Cu")
		(net 342)
	)
	(segment
		(start 226.325 133.875)
		(end 224.825 133.875)
		(width 0.1)
		(layer "B.Cu")
		(net 342)
	)
	(segment
		(start 227.16 131.6)
		(end 227.16 133.04)
		(width 0.1)
		(layer "B.Cu")
		(net 342)
	)
	(segment
		(start 227.18 130.55)
		(end 227.18 131.585)
		(width 0.15)
		(layer "B.Cu")
		(net 342)
	)
	(segment
		(start 224.825 133.875)
		(end 224.5 134.2)
		(width 0.1)
		(layer "B.Cu")
		(net 342)
	)
	(segment
		(start 227.16 133.04)
		(end 226.325 133.875)
		(width 0.1)
		(layer "B.Cu")
		(net 342)
	)
	(via
		(at 221.9 119.400001)
		(size 0.35)
		(drill 0.15)
		(layers "F.Cu" "B.Cu")
		(remove_unused_layers yes)
		(keep_end_layers yes)
		(zone_layer_connections)
		(net 343)
	)
	(via
		(at 217.55 116.411)
		(size 0.35)
		(drill 0.15)
		(layers "F.Cu" "B.Cu")
		(remove_unused_layers yes)
		(keep_end_layers yes)
		(zone_layer_connections)
		(net 343)
	)
	(segment
		(start 217.55 116.485975)
		(end 218.134025 117.07)
		(width 0.15)
		(layer "B.Cu")
		(net 343)
	)
	(segment
		(start 217.55 116.411)
		(end 217.55 116.485975)
		(width 0.15)
		(layer "B.Cu")
		(net 343)
	)
	(segment
		(start 218.134025 117.07)
		(end 218.41 117.07)
		(width 0.15)
		(layer "B.Cu")
		(net 343)
	)
	(segment
		(start 222.3 118.35)
		(end 222.3 117.408)
		(width 0.09)
		(layer "In9.Cu")
		(net 343)
	)
	(segment
		(start 221.9 119.400001)
		(end 221.9 118.75)
		(width 0.09)
		(layer "In9.Cu")
		(net 343)
	)
	(segment
		(start 222.3 117.408)
		(end 222.071 117.179)
		(width 0.09)
		(layer "In9.Cu")
		(net 343)
	)
	(segment
		(start 222.071 117.179)
		(end 218.318 117.179)
		(width 0.09)
		(layer "In9.Cu")
		(net 343)
	)
	(segment
		(start 221.9 118.75)
		(end 222.3 118.35)
		(width 0.09)
		(layer "In9.Cu")
		(net 343)
	)
	(segment
		(start 218.318 117.179)
		(end 217.55 116.411)
		(width 0.09)
		(layer "In9.Cu")
		(net 343)
	)
	(via
		(at 206.1 135.5)
		(size 0.35)
		(drill 0.15)
		(layers "F.Cu" "B.Cu")
		(remove_unused_layers yes)
		(keep_end_layers yes)
		(zone_layer_connections)
		(net 344)
	)
	(via
		(at 222.8 120.9)
		(size 0.35)
		(drill 0.15)
		(layers "F.Cu" "B.Cu")
		(remove_unused_layers yes)
		(keep_end_layers yes)
		(zone_layer_connections)
		(net 344)
	)
	(segment
		(start 225 122)
		(end 227.05 122)
		(width 0.09)
		(layer "In9.Cu")
		(net 344)
	)
	(segment
		(start 204.178 133.234549)
		(end 204.393451 133.45)
		(width 0.09)
		(layer "In9.Cu")
		(net 344)
	)
	(segment
		(start 205.8 135.2)
		(end 206.1 135.5)
		(width 0.09)
		(layer "In9.Cu")
		(net 344)
	)
	(segment
		(start 220.692865 125.306)
		(end 218.848865 127.15)
		(width 0.09)
		(layer "In9.Cu")
		(net 344)
	)
	(segment
		(start 222.8 120.9)
		(end 223.9 120.9)
		(width 0.09)
		(layer "In9.Cu")
		(net 344)
	)
	(segment
		(start 222 126.75)
		(end 221.45 126.2)
		(width 0.09)
		(layer "In9.Cu")
		(net 344)
	)
	(segment
		(start 221.45 125.549432)
		(end 221.206568 125.306)
		(width 0.09)
		(layer "In9.Cu")
		(net 344)
	)
	(segment
		(start 204.178 132.969451)
		(end 204.178 133.234549)
		(width 0.09)
		(layer "In9.Cu")
		(net 344)
	)
	(segment
		(start 204.857451 132.289)
		(end 204.857451 132.432549)
		(width 0.09)
		(layer "In9.Cu")
		(net 344)
	)
	(segment
		(start 227.65 124.35)
		(end 225.25 126.75)
		(width 0.09)
		(layer "In9.Cu")
		(net 344)
	)
	(segment
		(start 205.507107 133.45)
		(end 205.799999 133.742892)
		(width 0.09)
		(layer "In9.Cu")
		(net 344)
	)
	(segment
		(start 204.857451 132.432549)
		(end 204.67 132.62)
		(width 0.09)
		(layer "In9.Cu")
		(net 344)
	)
	(segment
		(start 205.799999 133.742892)
		(end 205.8 135.2)
		(width 0.09)
		(layer "In9.Cu")
		(net 344)
	)
	(segment
		(start 216.773865 127.15)
		(end 215.5 128.423865)
		(width 0.09)
		(layer "In9.Cu")
		(net 344)
	)
	(segment
		(start 221.45 126.2)
		(end 221.45 125.549432)
		(width 0.09)
		(layer "In9.Cu")
		(net 344)
	)
	(segment
		(start 215.5 129.436951)
		(end 213.036951 131.9)
		(width 0.09)
		(layer "In9.Cu")
		(net 344)
	)
	(segment
		(start 215.5 128.423865)
		(end 215.5 129.436951)
		(width 0.09)
		(layer "In9.Cu")
		(net 344)
	)
	(segment
		(start 227.05 122)
		(end 227.65 122.6)
		(width 0.09)
		(layer "In9.Cu")
		(net 344)
	)
	(segment
		(start 227.65 122.6)
		(end 227.65 124.35)
		(width 0.09)
		(layer "In9.Cu")
		(net 344)
	)
	(segment
		(start 223.9 120.9)
		(end 225 122)
		(width 0.09)
		(layer "In9.Cu")
		(net 344)
	)
	(segment
		(start 213.036951 131.9)
		(end 205.246451 131.9)
		(width 0.09)
		(layer "In9.Cu")
		(net 344)
	)
	(segment
		(start 218.848865 127.15)
		(end 216.773865 127.15)
		(width 0.09)
		(layer "In9.Cu")
		(net 344)
	)
	(segment
		(start 225.25 126.75)
		(end 222 126.75)
		(width 0.09)
		(layer "In9.Cu")
		(net 344)
	)
	(segment
		(start 205.246451 131.9)
		(end 204.857451 132.289)
		(width 0.09)
		(layer "In9.Cu")
		(net 344)
	)
	(segment
		(start 204.393451 133.45)
		(end 205.507107 133.45)
		(width 0.09)
		(layer "In9.Cu")
		(net 344)
	)
	(segment
		(start 204.527451 132.62)
		(end 204.178 132.969451)
		(width 0.09)
		(layer "In9.Cu")
		(net 344)
	)
	(segment
		(start 221.206568 125.306)
		(end 220.692865 125.306)
		(width 0.09)
		(layer "In9.Cu")
		(net 344)
	)
	(segment
		(start 204.67 132.62)
		(end 204.527451 132.62)
		(width 0.09)
		(layer "In9.Cu")
		(net 344)
	)
	(via
		(at 206.299 145.451)
		(size 0.35)
		(drill 0.15)
		(layers "F.Cu" "B.Cu")
		(remove_unused_layers yes)
		(keep_end_layers yes)
		(zone_layer_connections)
		(net 345)
	)
	(via
		(at 205.299 130.701)
		(size 0.35)
		(drill 0.15)
		(layers "F.Cu" "B.Cu")
		(remove_unused_layers yes)
		(keep_end_layers yes)
		(zone_layer_connections)
		(net 345)
	)
	(segment
		(start 205.974 145.126)
		(end 205.974 143.276)
		(width 0.1)
		(layer "In11.Cu")
		(net 345)
	)
	(segment
		(start 205.48 136.705)
		(end 204.255 136.705)
		(width 0.1)
		(layer "In11.Cu")
		(net 345)
	)
	(segment
		(start 202.45 134.9)
		(end 202.45 132.6)
		(width 0.1)
		(layer "In11.Cu")
		(net 345)
	)
	(segment
		(start 206.025 143.225)
		(end 206.025 141.5)
		(width 0.1)
		(layer "In11.Cu")
		(net 345)
	)
	(segment
		(start 204.63362 131.826)
		(end 204.974 131.48562)
		(width 0.1)
		(layer "In11.Cu")
		(net 345)
	)
	(segment
		(start 205.974 143.276)
		(end 206.025 143.225)
		(width 0.1)
		(layer "In11.Cu")
		(net 345)
	)
	(segment
		(start 205.7 136.925)
		(end 205.48 136.705)
		(width 0.1)
		(layer "In11.Cu")
		(net 345)
	)
	(segment
		(start 204.255 136.705)
		(end 202.45 134.9)
		(width 0.1)
		(layer "In11.Cu")
		(net 345)
	)
	(segment
		(start 202.45 132.6)
		(end 203.224 131.826)
		(width 0.1)
		(layer "In11.Cu")
		(net 345)
	)
	(segment
		(start 206.025 141.5)
		(end 205.7 141.175)
		(width 0.1)
		(layer "In11.Cu")
		(net 345)
	)
	(segment
		(start 204.974 131.48562)
		(end 204.974 131.026)
		(width 0.1)
		(layer "In11.Cu")
		(net 345)
	)
	(segment
		(start 204.974 131.026)
		(end 205.299 130.701)
		(width 0.1)
		(layer "In11.Cu")
		(net 345)
	)
	(segment
		(start 203.224 131.826)
		(end 204.63362 131.826)
		(width 0.1)
		(layer "In11.Cu")
		(net 345)
	)
	(segment
		(start 205.7 141.175)
		(end 205.7 136.925)
		(width 0.1)
		(layer "In11.Cu")
		(net 345)
	)
	(segment
		(start 206.299 145.451)
		(end 205.974 145.126)
		(width 0.1)
		(layer "In11.Cu")
		(net 345)
	)
	(via
		(at 205.299 131.501)
		(size 0.35)
		(drill 0.15)
		(layers "F.Cu" "B.Cu")
		(remove_unused_layers yes)
		(keep_end_layers yes)
		(zone_layer_connections)
		(net 346)
	)
	(via
		(at 206.299 146.101)
		(size 0.35)
		(drill 0.15)
		(layers "F.Cu" "B.Cu")
		(remove_unused_layers yes)
		(keep_end_layers yes)
		(zone_layer_connections)
		(net 346)
	)
	(segment
		(start 203.773 132.777)
		(end 204.523 132.777)
		(width 0.1)
		(layer "In11.Cu")
		(net 346)
	)
	(segment
		(start 206.475 137.01638)
		(end 206.20862 136.75)
		(width 0.1)
		(layer "In11.Cu")
		(net 346)
	)
	(segment
		(start 205.65 136.2)
		(end 205.4 135.95)
		(width 0.1)
		(layer "In11.Cu")
		(net 346)
	)
	(segment
		(start 205.65 136.45)
		(end 205.65 136.2)
		(width 0.1)
		(layer "In11.Cu")
		(net 346)
	)
	(segment
		(start 203.5 135.1)
		(end 203.3 134.9)
		(width 0.1)
		(layer "In11.Cu")
		(net 346)
	)
	(segment
		(start 206.624 145.776)
		(end 206.624 143.749)
		(width 0.1)
		(layer "In11.Cu")
		(net 346)
	)
	(segment
		(start 203.3 134.9)
		(end 203.3 134.631315)
		(width 0.1)
		(layer "In11.Cu")
		(net 346)
	)
	(segment
		(start 204.974 132.326)
		(end 204.974 131.826)
		(width 0.1)
		(layer "In11.Cu")
		(net 346)
	)
	(segment
		(start 204.625 135.95)
		(end 203.775 135.1)
		(width 0.1)
		(layer "In11.Cu")
		(net 346)
	)
	(segment
		(start 205.95 136.75)
		(end 205.65 136.45)
		(width 0.1)
		(layer "In11.Cu")
		(net 346)
	)
	(segment
		(start 204.523 132.777)
		(end 204.974 132.326)
		(width 0.1)
		(layer "In11.Cu")
		(net 346)
	)
	(segment
		(start 203.775 135.1)
		(end 203.5 135.1)
		(width 0.1)
		(layer "In11.Cu")
		(net 346)
	)
	(segment
		(start 206.299 146.101)
		(end 206.624 145.776)
		(width 0.1)
		(layer "In11.Cu")
		(net 346)
	)
	(segment
		(start 206.20862 136.75)
		(end 205.95 136.75)
		(width 0.1)
		(layer "In11.Cu")
		(net 346)
	)
	(segment
		(start 203 134.331315)
		(end 203 133.55)
		(width 0.1)
		(layer "In11.Cu")
		(net 346)
	)
	(segment
		(start 203 133.55)
		(end 203.773 132.777)
		(width 0.1)
		(layer "In11.Cu")
		(net 346)
	)
	(segment
		(start 206.624 143.749)
		(end 206.475 143.6)
		(width 0.1)
		(layer "In11.Cu")
		(net 346)
	)
	(segment
		(start 203.3 134.631315)
		(end 203 134.331315)
		(width 0.1)
		(layer "In11.Cu")
		(net 346)
	)
	(segment
		(start 204.974 131.826)
		(end 205.299 131.501)
		(width 0.1)
		(layer "In11.Cu")
		(net 346)
	)
	(segment
		(start 206.475 143.6)
		(end 206.475 137.01638)
		(width 0.1)
		(layer "In11.Cu")
		(net 346)
	)
	(segment
		(start 205.4 135.95)
		(end 204.625 135.95)
		(width 0.1)
		(layer "In11.Cu")
		(net 346)
	)
	(via
		(at 190.9 140.3)
		(size 0.35)
		(drill 0.15)
		(layers "F.Cu" "B.Cu")
		(remove_unused_layers yes)
		(keep_end_layers yes)
		(zone_layer_connections)
		(net 347)
	)
	(via
		(at 201.099 146.751)
		(size 0.35)
		(drill 0.15)
		(layers "F.Cu" "B.Cu")
		(remove_unused_layers yes)
		(keep_end_layers yes)
		(zone_layer_connections)
		(net 347)
	)
	(segment
		(start 191.16 142.49)
		(end 191.13106 142.49)
		(width 0.09)
		(layer "In9.Cu")
		(net 347)
	)
	(segment
		(start 189.97 140.74)
		(end 191.11 140.74)
		(width 0.09)
		(layer "In9.Cu")
		(net 347)
	)
	(segment
		(start 191.3 140.93)
		(end 191.3 141.33)
		(width 0.09)
		(layer "In9.Cu")
		(net 347)
	)
	(segment
		(start 189.83 140.38)
		(end 189.83 140.6)
		(width 0.09)
		(layer "In9.Cu")
		(net 347)
	)
	(segment
		(start 191.11 140.74)
		(end 191.3 140.93)
		(width 0.09)
		(layer "In9.Cu")
		(net 347)
	)
	(segment
		(start 191.3 142.91)
		(end 191.3 142.93)
		(width 0.09)
		(layer "In9.Cu")
		(net 347)
	)
	(segment
		(start 197.35 145.35)
		(end 199.1 147.1)
		(width 0.09)
		(layer "In9.Cu")
		(net 347)
	)
	(segment
		(start 189.83 140.6)
		(end 189.97 140.74)
		(width 0.09)
		(layer "In9.Cu")
		(net 347)
	)
	(segment
		(start 199.1 147.1)
		(end 200.75 147.1)
		(width 0.09)
		(layer "In9.Cu")
		(net 347)
	)
	(segment
		(start 190.24 141.75)
		(end 191.16 141.75)
		(width 0.09)
		(layer "In9.Cu")
		(net 347)
	)
	(segment
		(start 191.67 144.562549)
		(end 191.918725 144.811275)
		(width 0.09)
		(layer "In9.Cu")
		(net 347)
	)
	(segment
		(start 194.6 145.35)
		(end 197.35 145.35)
		(width 0.09)
		(layer "In9.Cu")
		(net 347)
	)
	(segment
		(start 191.3 141.89)
		(end 191.3 142.35)
		(width 0.09)
		(layer "In9.Cu")
		(net 347)
	)
	(segment
		(start 189.95 140.26)
		(end 189.83 140.38)
		(width 0.09)
		(layer "In9.Cu")
		(net 347)
	)
	(segment
		(start 191.16 141.47)
		(end 190.24 141.47)
		(width 0.09)
		(layer "In9.Cu")
		(net 347)
	)
	(segment
		(start 191.918725 144.811275)
		(end 194.061275 144.811275)
		(width 0.09)
		(layer "In9.Cu")
		(net 347)
	)
	(segment
		(start 190.9 140.3)
		(end 190.86 140.26)
		(width 0.09)
		(layer "In9.Cu")
		(net 347)
	)
	(segment
		(start 190.86 140.26)
		(end 189.95 140.26)
		(width 0.09)
		(layer "In9.Cu")
		(net 347)
	)
	(segment
		(start 200.75 147.1)
		(end 201.099 146.751)
		(width 0.09)
		(layer "In9.Cu")
		(net 347)
	)
	(segment
		(start 191.13106 142.77)
		(end 191.16 142.77)
		(width 0.09)
		(layer "In9.Cu")
		(net 347)
	)
	(segment
		(start 191.3 142.93)
		(end 191.67 143.3)
		(width 0.09)
		(layer "In9.Cu")
		(net 347)
	)
	(segment
		(start 194.061275 144.811275)
		(end 194.6 145.35)
		(width 0.09)
		(layer "In9.Cu")
		(net 347)
	)
	(segment
		(start 191.67 143.3)
		(end 191.67 144.562549)
		(width 0.09)
		(layer "In9.Cu")
		(net 347)
	)
	(arc
		(start 191.13106 142.49)
		(mid 191.032065 142.531005)
		(end 190.99106 142.63)
		(width 0.09)
		(layer "In9.Cu")
		(net 347)
	)
	(arc
		(start 191.16 141.75)
		(mid 191.258995 141.791005)
		(end 191.3 141.89)
		(width 0.09)
		(layer "In9.Cu")
		(net 347)
	)
	(arc
		(start 190.99106 142.63)
		(mid 191.032065 142.728995)
		(end 191.13106 142.77)
		(width 0.09)
		(layer "In9.Cu")
		(net 347)
	)
	(arc
		(start 190.24 141.47)
		(mid 190.141005 141.511005)
		(end 190.1 141.61)
		(width 0.09)
		(layer "In9.Cu")
		(net 347)
	)
	(arc
		(start 190.1 141.61)
		(mid 190.141005 141.708995)
		(end 190.24 141.75)
		(width 0.09)
		(layer "In9.Cu")
		(net 347)
	)
	(arc
		(start 191.3 141.33)
		(mid 191.258995 141.428995)
		(end 191.16 141.47)
		(width 0.09)
		(layer "In9.Cu")
		(net 347)
	)
	(arc
		(start 191.3 142.35)
		(mid 191.258995 142.448995)
		(end 191.16 142.49)
		(width 0.09)
		(layer "In9.Cu")
		(net 347)
	)
	(arc
		(start 191.16 142.77)
		(mid 191.258995 142.811005)
		(end 191.3 142.91)
		(width 0.09)
		(layer "In9.Cu")
		(net 347)
	)
	(via
		(at 206.1 129.95)
		(size 0.35)
		(drill 0.15)
		(layers "F.Cu" "B.Cu")
		(remove_unused_layers yes)
		(keep_end_layers yes)
		(zone_layer_connections)
		(net 348)
	)
	(via
		(at 192.75 141.65)
		(size 0.35)
		(drill 0.15)
		(layers "F.Cu" "B.Cu")
		(remove_unused_layers yes)
		(keep_end_layers yes)
		(zone_layer_connections)
		(net 348)
	)
	(segment
		(start 190.5 140.489905)
		(end 190.5 139.25)
		(width 0.1)
		(layer "In11.Cu")
		(net 348)
	)
	(segment
		(start 192.174 141.3063)
		(end 192.174 141.11538)
		(width 0.1)
		(layer "In11.Cu")
		(net 348)
	)
	(segment
		(start 204.974 130.726)
		(end 204.974 130.476)
		(width 0.1)
		(layer "In11.Cu")
		(net 348)
	)
	(segment
		(start 191.75862 140.7)
		(end 190.710095 140.7)
		(width 0.1)
		(layer "In11.Cu")
		(net 348)
	)
	(segment
		(start 192.05 136.29038)
		(end 193.25 135.09038)
		(width 0.1)
		(layer "In11.Cu")
		(net 348)
	)
	(segment
		(start 197.57337 132.04)
		(end 200.11 132.04)
		(width 0.1)
		(layer "In11.Cu")
		(net 348)
	)
	(segment
		(start 200.974 131.176)
		(end 204.524 131.176)
		(width 0.1)
		(layer "In11.Cu")
		(net 348)
	)
	(segment
		(start 190.5 139.25)
		(end 192.05 137.7)
		(width 0.1)
		(layer "In11.Cu")
		(net 348)
	)
	(segment
		(start 193.25 135.09038)
		(end 193.25 134.7)
		(width 0.1)
		(layer "In11.Cu")
		(net 348)
	)
	(segment
		(start 196.06038 132.3)
		(end 197.31337 132.3)
		(width 0.1)
		(layer "In11.Cu")
		(net 348)
	)
	(segment
		(start 195.22038 133.14)
		(end 196.06038 132.3)
		(width 0.1)
		(layer "In11.Cu")
		(net 348)
	)
	(segment
		(start 200.11 132.04)
		(end 200.974 131.176)
		(width 0.1)
		(layer "In11.Cu")
		(net 348)
	)
	(segment
		(start 205.2 130.25)
		(end 205.8 130.25)
		(width 0.1)
		(layer "In11.Cu")
		(net 348)
	)
	(segment
		(start 204.974 130.476)
		(end 205.2 130.25)
		(width 0.1)
		(layer "In11.Cu")
		(net 348)
	)
	(segment
		(start 193.25 134.7)
		(end 194.81 133.14)
		(width 0.1)
		(layer "In11.Cu")
		(net 348)
	)
	(segment
		(start 192.174 141.11538)
		(end 191.75862 140.7)
		(width 0.1)
		(layer "In11.Cu")
		(net 348)
	)
	(segment
		(start 192.75 141.65)
		(end 192.5177 141.65)
		(width 0.1)
		(layer "In11.Cu")
		(net 348)
	)
	(segment
		(start 192.5177 141.65)
		(end 192.174 141.3063)
		(width 0.1)
		(layer "In11.Cu")
		(net 348)
	)
	(segment
		(start 197.31337 132.3)
		(end 197.57337 132.04)
		(width 0.1)
		(layer "In11.Cu")
		(net 348)
	)
	(segment
		(start 190.710095 140.7)
		(end 190.5 140.489905)
		(width 0.1)
		(layer "In11.Cu")
		(net 348)
	)
	(segment
		(start 194.81 133.14)
		(end 195.22038 133.14)
		(width 0.1)
		(layer "In11.Cu")
		(net 348)
	)
	(segment
		(start 192.05 137.7)
		(end 192.05 136.29038)
		(width 0.1)
		(layer "In11.Cu")
		(net 348)
	)
	(segment
		(start 204.524 131.176)
		(end 204.974 130.726)
		(width 0.1)
		(layer "In11.Cu")
		(net 348)
	)
	(segment
		(start 205.8 130.25)
		(end 206.1 129.95)
		(width 0.1)
		(layer "In11.Cu")
		(net 348)
	)
	(via
		(at 205.299 135.5)
		(size 0.35)
		(drill 0.15)
		(layers "F.Cu" "B.Cu")
		(remove_unused_layers yes)
		(keep_end_layers yes)
		(zone_layer_connections)
		(net 349)
	)
	(via
		(at 221.9 120.9)
		(size 0.35)
		(drill 0.15)
		(layers "F.Cu" "B.Cu")
		(remove_unused_layers yes)
		(keep_end_layers yes)
		(zone_layer_connections)
		(net 349)
	)
	(segment
		(start 204.709 131.821)
		(end 204.95 131.58)
		(width 0.09)
		(layer "In9.Cu")
		(net 349)
	)
	(segment
		(start 214.975 127.855)
		(end 216.23 126.6)
		(width 0.09)
		(layer "In9.Cu")
		(net 349)
	)
	(segment
		(start 223.75 121.45)
		(end 222.45 121.45)
		(width 0.09)
		(layer "In9.Cu")
		(net 349)
	)
	(segment
		(start 225.664444 125.835556)
		(end 227.25 124.25)
		(width 0.09)
		(layer "In9.Cu")
		(net 349)
	)
	(segment
		(start 204.179 132.081)
		(end 204.439 131.821)
		(width 0.09)
		(layer "In9.Cu")
		(net 349)
	)
	(segment
		(start 212.839 131.021)
		(end 214.975 128.885)
		(width 0.09)
		(layer "In9.Cu")
		(net 349)
	)
	(segment
		(start 204.95 131.35)
		(end 205.279 131.021)
		(width 0.09)
		(layer "In9.Cu")
		(net 349)
	)
	(segment
		(start 222.135556 125.835556)
		(end 225.664444 125.835556)
		(width 0.09)
		(layer "In9.Cu")
		(net 349)
	)
	(segment
		(start 203.998 132.462)
		(end 204.179 132.281)
		(width 0.09)
		(layer "In9.Cu")
		(net 349)
	)
	(segment
		(start 204.95 131.58)
		(end 204.95 131.35)
		(width 0.09)
		(layer "In9.Cu")
		(net 349)
	)
	(segment
		(start 216.23 126.6)
		(end 218.9 126.6)
		(width 0.09)
		(layer "In9.Cu")
		(net 349)
	)
	(segment
		(start 220.4 125.1)
		(end 221.4 125.1)
		(width 0.09)
		(layer "In9.Cu")
		(net 349)
	)
	(segment
		(start 224.75 122.45)
		(end 223.75 121.45)
		(width 0.09)
		(layer "In9.Cu")
		(net 349)
	)
	(segment
		(start 204.179 132.281)
		(end 204.179 132.081)
		(width 0.09)
		(layer "In9.Cu")
		(net 349)
	)
	(segment
		(start 205.299 135.5)
		(end 205.62 135.179)
		(width 0.09)
		(layer "In9.Cu")
		(net 349)
	)
	(segment
		(start 218.9 126.6)
		(end 220.4 125.1)
		(width 0.09)
		(layer "In9.Cu")
		(net 349)
	)
	(segment
		(start 204.439 131.821)
		(end 204.709 131.821)
		(width 0.09)
		(layer "In9.Cu")
		(net 349)
	)
	(segment
		(start 214.975 128.885)
		(end 214.975 127.855)
		(width 0.09)
		(layer "In9.Cu")
		(net 349)
	)
	(segment
		(start 221.4 125.1)
		(end 222.135556 125.835556)
		(width 0.09)
		(layer "In9.Cu")
		(net 349)
	)
	(segment
		(start 204.318892 133.629999)
		(end 203.998 133.309107)
		(width 0.09)
		(layer "In9.Cu")
		(net 349)
	)
	(segment
		(start 205.62 133.817451)
		(end 205.432549 133.63)
		(width 0.09)
		(layer "In9.Cu")
		(net 349)
	)
	(segment
		(start 222.45 121.45)
		(end 221.9 120.9)
		(width 0.09)
		(layer "In9.Cu")
		(net 349)
	)
	(segment
		(start 205.279 131.021)
		(end 212.839 131.021)
		(width 0.09)
		(layer "In9.Cu")
		(net 349)
	)
	(segment
		(start 227.25 123.2)
		(end 226.5 122.45)
		(width 0.09)
		(layer "In9.Cu")
		(net 349)
	)
	(segment
		(start 227.25 124.25)
		(end 227.25 123.2)
		(width 0.09)
		(layer "In9.Cu")
		(net 349)
	)
	(segment
		(start 205.62 135.179)
		(end 205.62 133.817451)
		(width 0.09)
		(layer "In9.Cu")
		(net 349)
	)
	(segment
		(start 203.998 133.309107)
		(end 203.998 132.462)
		(width 0.09)
		(layer "In9.Cu")
		(net 349)
	)
	(segment
		(start 226.5 122.45)
		(end 224.75 122.45)
		(width 0.09)
		(layer "In9.Cu")
		(net 349)
	)
	(segment
		(start 205.432549 133.63)
		(end 204.318892 133.629999)
		(width 0.09)
		(layer "In9.Cu")
		(net 349)
	)
	(segment
		(start 191.8 122.25)
		(end 193.265025 122.25)
		(width 0.15)
		(layer "F.Cu")
		(net 350)
	)
	(segment
		(start 191.6 122.45)
		(end 191.8 122.25)
		(width 0.15)
		(layer "F.Cu")
		(net 350)
	)
	(segment
		(start 193.865025 121.65)
		(end 193.95 121.65)
		(width 0.15)
		(layer "F.Cu")
		(net 350)
	)
	(segment
		(start 193.265025 122.25)
		(end 193.865025 121.65)
		(width 0.15)
		(layer "F.Cu")
		(net 350)
	)
	(segment
		(start 204.9 141.75)
		(end 204.9 140.699)
		(width 0.1)
		(layer "F.Cu")
		(net 350)
	)
	(segment
		(start 203.7 141.9)
		(end 204.75 141.9)
		(width 0.1)
		(layer "F.Cu")
		(net 350)
	)
	(segment
		(start 204.9 140.699)
		(end 205.299 140.3)
		(width 0.1)
		(layer "F.Cu")
		(net 350)
	)
	(segment
		(start 204.75 141.9)
		(end 204.9 141.75)
		(width 0.1)
		(layer "F.Cu")
		(net 350)
	)
	(via
		(at 191.6 122.45)
		(size 0.35)
		(drill 0.15)
		(layers "F.Cu" "B.Cu")
		(remove_unused_layers yes)
		(keep_end_layers yes)
		(zone_layer_connections)
		(net 350)
	)
	(via
		(at 203.7 141.9)
		(size 0.35)
		(drill 0.15)
		(layers "F.Cu" "B.Cu")
		(remove_unused_layers yes)
		(keep_end_layers yes)
		(zone_layer_connections)
		(net 350)
	)
	(segment
		(start 195.425 138.225)
		(end 195.425 137.625)
		(width 0.1)
		(layer "In7.Cu")
		(net 350)
	)
	(segment
		(start 203.7 141.9)
		(end 203.3 141.5)
		(width 0.1)
		(layer "In7.Cu")
		(net 350)
	)
	(segment
		(start 198.76438 140.625)
		(end 198.55 140.41062)
		(width 0.1)
		(layer "In7.Cu")
		(net 350)
	)
	(segment
		(start 191 121.85)
		(end 191.6 122.45)
		(width 0.1)
		(layer "In7.Cu")
		(net 350)
	)
	(segment
		(start 190.55 121.85)
		(end 191 121.85)
		(width 0.1)
		(layer "In7.Cu")
		(net 350)
	)
	(segment
		(start 195.425 137.625)
		(end 196.15 136.9)
		(width 0.1)
		(layer "In7.Cu")
		(net 350)
	)
	(segment
		(start 192.5 123.45)
		(end 191.2 123.45)
		(width 0.1)
		(layer "In7.Cu")
		(net 350)
	)
	(segment
		(start 190.35 122.05)
		(end 190.55 121.85)
		(width 0.1)
		(layer "In7.Cu")
		(net 350)
	)
	(segment
		(start 198.2 139.9)
		(end 197.1 139.9)
		(width 0.1)
		(layer "In7.Cu")
		(net 350)
	)
	(segment
		(start 198.55 140.41062)
		(end 198.55 140.25)
		(width 0.1)
		(layer "In7.Cu")
		(net 350)
	)
	(segment
		(start 192.75 124.21062)
		(end 192.75 123.7)
		(width 0.1)
		(layer "In7.Cu")
		(net 350)
	)
	(segment
		(start 198.55 140.25)
		(end 198.2 139.9)
		(width 0.1)
		(layer "In7.Cu")
		(net 350)
	)
	(segment
		(start 196.15 135.8)
		(end 195.65 135.3)
		(width 0.1)
		(layer "In7.Cu")
		(net 350)
	)
	(segment
		(start 195.65 134.9)
		(end 193.7 132.95)
		(width 0.1)
		(layer "In7.Cu")
		(net 350)
	)
	(segment
		(start 193.7 125.16062)
		(end 192.75 124.21062)
		(width 0.1)
		(layer "In7.Cu")
		(net 350)
	)
	(segment
		(start 190.35 122.6)
		(end 190.35 122.05)
		(width 0.1)
		(layer "In7.Cu")
		(net 350)
	)
	(segment
		(start 199.55 141.5)
		(end 199.374 141.324)
		(width 0.1)
		(layer "In7.Cu")
		(net 350)
	)
	(segment
		(start 192.75 123.7)
		(end 192.5 123.45)
		(width 0.1)
		(layer "In7.Cu")
		(net 350)
	)
	(segment
		(start 203.3 141.5)
		(end 199.55 141.5)
		(width 0.1)
		(layer "In7.Cu")
		(net 350)
	)
	(segment
		(start 199.374 141.324)
		(end 199.374 141.11638)
		(width 0.1)
		(layer "In7.Cu")
		(net 350)
	)
	(segment
		(start 191.2 123.45)
		(end 190.35 122.6)
		(width 0.1)
		(layer "In7.Cu")
		(net 350)
	)
	(segment
		(start 197.1 139.9)
		(end 195.425 138.225)
		(width 0.1)
		(layer "In7.Cu")
		(net 350)
	)
	(segment
		(start 193.7 132.95)
		(end 193.7 125.16062)
		(width 0.1)
		(layer "In7.Cu")
		(net 350)
	)
	(segment
		(start 195.65 135.3)
		(end 195.65 134.9)
		(width 0.1)
		(layer "In7.Cu")
		(net 350)
	)
	(segment
		(start 198.88262 140.625)
		(end 198.76438 140.625)
		(width 0.1)
		(layer "In7.Cu")
		(net 350)
	)
	(segment
		(start 199.374 141.11638)
		(end 198.88262 140.625)
		(width 0.1)
		(layer "In7.Cu")
		(net 350)
	)
	(segment
		(start 196.15 136.9)
		(end 196.15 135.8)
		(width 0.1)
		(layer "In7.Cu")
		(net 350)
	)
	(via
		(at 220.59 140.53)
		(size 0.35)
		(drill 0.15)
		(layers "F.Cu" "B.Cu")
		(remove_unused_layers yes)
		(keep_end_layers yes)
		(zone_layer_connections)
		(net 351)
	)
	(via
		(at 206.1 139.495)
		(size 0.35)
		(drill 0.15)
		(layers "F.Cu" "B.Cu")
		(remove_unused_layers yes)
		(keep_end_layers yes)
		(zone_layer_connections)
		(net 351)
	)
	(segment
		(start 220.59 140.53)
		(end 220.59 140.87)
		(width 0.09)
		(layer "B.Cu")
		(net 351)
	)
	(segment
		(start 219.35 139.28)
		(end 217.47 137.4)
		(width 0.09)
		(layer "In7.Cu")
		(net 351)
	)
	(segment
		(start 220.59 140.53)
		(end 220.18 140.12)
		(width 0.09)
		(layer "In7.Cu")
		(net 351)
	)
	(segment
		(start 221.09 140.4)
		(end 221.09 140.74)
		(width 0.09)
		(layer "In7.Cu")
		(net 351)
	)
	(segment
		(start 220.4 139.57)
		(end 220.88 139.57)
		(width 0.09)
		(layer "In7.Cu")
		(net 351)
	)
	(segment
		(start 208.84 137.4)
		(end 208.7 137.4)
		(width 0.09)
		(layer "In7.Cu")
		(net 351)
	)
	(segment
		(start 208.99 137.568023)
		(end 208.99 137.55)
		(width 0.09)
		(layer "In7.Cu")
		(net 351)
	)
	(segment
		(start 220.96 140.87)
		(end 219.56 140.87)
		(width 0.09)
		(layer "In7.Cu")
		(net 351)
	)
	(segment
		(start 220.84 140.1)
		(end 220.84 140.15)
		(width 0.09)
		(layer "In7.Cu")
		(net 351)
	)
	(segment
		(start 221.09 139.78)
		(end 221.09 139.85)
		(width 0.09)
		(layer "In7.Cu")
		(net 351)
	)
	(segment
		(start 221.09 140.74)
		(end 220.96 140.87)
		(width 0.09)
		(layer "In7.Cu")
		(net 351)
	)
	(segment
		(start 220.18 140.12)
		(end 220.18 139.79)
		(width 0.09)
		(layer "In7.Cu")
		(net 351)
	)
	(segment
		(start 217.47 137.4)
		(end 209.44 137.4)
		(width 0.09)
		(layer "In7.Cu")
		(net 351)
	)
	(segment
		(start 206.605 139.495)
		(end 206.1 139.495)
		(width 0.09)
		(layer "In7.Cu")
		(net 351)
	)
	(segment
		(start 220.18 139.79)
		(end 220.4 139.57)
		(width 0.09)
		(layer "In7.Cu")
		(net 351)
	)
	(segment
		(start 208.7 137.4)
		(end 206.605 139.495)
		(width 0.09)
		(layer "In7.Cu")
		(net 351)
	)
	(segment
		(start 219.56 140.87)
		(end 219.35 140.66)
		(width 0.09)
		(layer "In7.Cu")
		(net 351)
	)
	(segment
		(start 220.88 139.57)
		(end 221.09 139.78)
		(width 0.09)
		(layer "In7.Cu")
		(net 351)
	)
	(segment
		(start 209.29 137.55)
		(end 209.29 137.568023)
		(width 0.09)
		(layer "In7.Cu")
		(net 351)
	)
	(segment
		(start 219.35 140.66)
		(end 219.35 139.28)
		(width 0.09)
		(layer "In7.Cu")
		(net 351)
	)
	(arc
		(start 209.14 137.718023)
		(mid 209.033934 137.674089)
		(end 208.99 137.568023)
		(width 0.09)
		(layer "In7.Cu")
		(net 351)
	)
	(arc
		(start 209.44 137.4)
		(mid 209.333934 137.443934)
		(end 209.29 137.55)
		(width 0.09)
		(layer "In7.Cu")
		(net 351)
	)
	(arc
		(start 208.99 137.55)
		(mid 208.946066 137.443934)
		(end 208.84 137.4)
		(width 0.09)
		(layer "In7.Cu")
		(net 351)
	)
	(arc
		(start 220.84 140.15)
		(mid 220.876612 140.238388)
		(end 220.965 140.275)
		(width 0.09)
		(layer "In7.Cu")
		(net 351)
	)
	(arc
		(start 209.29 137.568023)
		(mid 209.246066 137.674089)
		(end 209.14 137.718023)
		(width 0.09)
		(layer "In7.Cu")
		(net 351)
	)
	(arc
		(start 221.09 139.85)
		(mid 221.053388 139.938388)
		(end 220.965 139.975)
		(width 0.09)
		(layer "In7.Cu")
		(net 351)
	)
	(arc
		(start 220.965 140.275)
		(mid 221.053388 140.311612)
		(end 221.09 140.4)
		(width 0.09)
		(layer "In7.Cu")
		(net 351)
	)
	(arc
		(start 220.965 139.975)
		(mid 220.876612 140.011612)
		(end 220.84 140.1)
		(width 0.09)
		(layer "In7.Cu")
		(net 351)
	)
	(via
		(at 206.1 140.3)
		(size 0.35)
		(drill 0.15)
		(layers "F.Cu" "B.Cu")
		(remove_unused_layers yes)
		(keep_end_layers yes)
		(zone_layer_connections)
		(net 352)
	)
	(via
		(at 218.87 140.53)
		(size 0.35)
		(drill 0.15)
		(layers "F.Cu" "B.Cu")
		(remove_unused_layers yes)
		(keep_end_layers yes)
		(zone_layer_connections)
		(net 352)
	)
	(segment
		(start 218.87 140.53)
		(end 218.87 140.87)
		(width 0.09)
		(layer "B.Cu")
		(net 352)
	)
	(segment
		(start 214.71 138.05)
		(end 214.71 138)
		(width 0.09)
		(layer "In7.Cu")
		(net 352)
	)
	(segment
		(start 214.41 138)
		(end 214.41 138.05)
		(width 0.09)
		(layer "In7.Cu")
		(net 352)
	)
	(segment
		(start 216.81 138)
		(end 216.81 138.05)
		(width 0.09)
		(layer "In7.Cu")
		(net 352)
	)
	(segment
		(start 217.556331 138.517455)
		(end 217.743786 138.33)
		(width 0.09)
		(layer "In7.Cu")
		(net 352)
	)
	(segment
		(start 218.99 140.03)
		(end 218.39 140.03)
		(width 0.09)
		(layer "In7.Cu")
		(net 352)
	)
	(segment
		(start 210.545 138.165)
		(end 210.86 137.85)
		(width 0.09)
		(layer "In7.Cu")
		(net 352)
	)
	(segment
		(start 216.21 138)
		(end 216.21 138.05)
		(width 0.09)
		(layer "In7.Cu")
		(net 352)
	)
	(segment
		(start 215.01 138)
		(end 215.01 138.05)
		(width 0.09)
		(layer "In7.Cu")
		(net 352)
	)
	(segment
		(start 217.44 137.85)
		(end 217.515 137.925)
		(width 0.09)
		(layer "In7.Cu")
		(net 352)
	)
	(segment
		(start 218.56 140.9)
		(end 218.79 140.9)
		(width 0.09)
		(layer "In7.Cu")
		(net 352)
	)
	(segment
		(start 218.87 140.82)
		(end 218.87 140.53)
		(width 0.09)
		(layer "In7.Cu")
		(net 352)
	)
	(segment
		(start 218.24 139.25)
		(end 218.24 139.58)
		(width 0.09)
		(layer "In7.Cu")
		(net 352)
	)
	(segment
		(start 206.1 140.295)
		(end 206.475 140.295)
		(width 0.09)
		(layer "In7.Cu")
		(net 352)
	)
	(segment
		(start 218.79 140.9)
		(end 218.87 140.82)
		(width 0.09)
		(layer "In7.Cu")
		(net 352)
	)
	(segment
		(start 208.605 138.165)
		(end 210.545 138.165)
		(width 0.09)
		(layer "In7.Cu")
		(net 352)
	)
	(segment
		(start 217.514999 138.137133)
		(end 217.373578 138.278553)
		(width 0.09)
		(layer "In7.Cu")
		(net 352)
	)
	(segment
		(start 215.91 138.05)
		(end 215.91 138)
		(width 0.09)
		(layer "In7.Cu")
		(net 352)
	)
	(segment
		(start 210.86 137.85)
		(end 214.26 137.85)
		(width 0.09)
		(layer "In7.Cu")
		(net 352)
	)
	(segment
		(start 217.89 139.1)
		(end 218.09 139.1)
		(width 0.09)
		(layer "In7.Cu")
		(net 352)
	)
	(segment
		(start 216.51 138.05)
		(end 216.51 138)
		(width 0.09)
		(layer "In7.Cu")
		(net 352)
	)
	(segment
		(start 218.24 140.58)
		(end 218.56 140.9)
		(width 0.09)
		(layer "In7.Cu")
		(net 352)
	)
	(segment
		(start 218.24 138.61)
		(end 218.24 138.65)
		(width 0.09)
		(layer "In7.Cu")
		(net 352)
	)
	(segment
		(start 217.96 138.33)
		(end 218.24 138.61)
		(width 0.09)
		(layer "In7.Cu")
		(net 352)
	)
	(segment
		(start 215.61 138)
		(end 215.61 138.05)
		(width 0.09)
		(layer "In7.Cu")
		(net 352)
	)
	(segment
		(start 215.31 138.05)
		(end 215.31 138)
		(width 0.09)
		(layer "In7.Cu")
		(net 352)
	)
	(segment
		(start 218.39 139.73)
		(end 218.99 139.73)
		(width 0.09)
		(layer "In7.Cu")
		(net 352)
	)
	(segment
		(start 206.475 140.295)
		(end 208.605 138.165)
		(width 0.09)
		(layer "In7.Cu")
		(net 352)
	)
	(segment
		(start 218.09 138.8)
		(end 217.89 138.8)
		(width 0.09)
		(layer "In7.Cu")
		(net 352)
	)
	(segment
		(start 217.743786 138.33)
		(end 217.747868 138.33)
		(width 0.09)
		(layer "In7.Cu")
		(net 352)
	)
	(segment
		(start 217.11 138.05)
		(end 217.11 138)
		(width 0.09)
		(layer "In7.Cu")
		(net 352)
	)
	(segment
		(start 217.26 137.85)
		(end 217.44 137.85)
		(width 0.09)
		(layer "In7.Cu")
		(net 352)
	)
	(segment
		(start 218.24 140.18)
		(end 218.24 140.58)
		(width 0.09)
		(layer "In7.Cu")
		(net 352)
	)
	(arc
		(start 215.31 138)
		(mid 215.353934 137.893934)
		(end 215.46 137.85)
		(width 0.09)
		(layer "In7.Cu")
		(net 352)
	)
	(arc
		(start 218.24 138.65)
		(mid 218.196066 138.756066)
		(end 218.09 138.8)
		(width 0.09)
		(layer "In7.Cu")
		(net 352)
	)
	(arc
		(start 217.515 137.925)
		(mid 217.558934 138.031067)
		(end 217.514999 138.137133)
		(width 0.09)
		(layer "In7.Cu")
		(net 352)
	)
	(arc
		(start 214.71 138)
		(mid 214.753934 137.893934)
		(end 214.86 137.85)
		(width 0.09)
		(layer "In7.Cu")
		(net 352)
	)
	(arc
		(start 218.99 139.73)
		(mid 219.096066 139.773934)
		(end 219.14 139.88)
		(width 0.09)
		(layer "In7.Cu")
		(net 352)
	)
	(arc
		(start 218.39 140.03)
		(mid 218.283934 140.073934)
		(end 218.24 140.18)
		(width 0.09)
		(layer "In7.Cu")
		(net 352)
	)
	(arc
		(start 215.76 138.2)
		(mid 215.866066 138.156066)
		(end 215.91 138.05)
		(width 0.09)
		(layer "In7.Cu")
		(net 352)
	)
	(arc
		(start 216.21 138.05)
		(mid 216.253934 138.156066)
		(end 216.36 138.2)
		(width 0.09)
		(layer "In7.Cu")
		(net 352)
	)
	(arc
		(start 217.74 138.95)
		(mid 217.783934 139.056066)
		(end 217.89 139.1)
		(width 0.09)
		(layer "In7.Cu")
		(net 352)
	)
	(arc
		(start 217.747868 138.33)
		(mid 217.853934 138.286066)
		(end 217.96 138.33)
		(width 0.09)
		(layer "In7.Cu")
		(net 352)
	)
	(arc
		(start 218.24 139.58)
		(mid 218.283934 139.686066)
		(end 218.39 139.73)
		(width 0.09)
		(layer "In7.Cu")
		(net 352)
	)
	(arc
		(start 217.89 138.8)
		(mid 217.783934 138.843934)
		(end 217.74 138.95)
		(width 0.09)
		(layer "In7.Cu")
		(net 352)
	)
	(arc
		(start 216.81 138.05)
		(mid 216.853934 138.156066)
		(end 216.96 138.2)
		(width 0.09)
		(layer "In7.Cu")
		(net 352)
	)
	(arc
		(start 217.373578 138.278553)
		(mid 217.329644 138.384619)
		(end 217.373578 138.490685)
		(width 0.09)
		(layer "In7.Cu")
		(net 352)
	)
	(arc
		(start 216.66 137.85)
		(mid 216.766066 137.893934)
		(end 216.81 138)
		(width 0.09)
		(layer "In7.Cu")
		(net 352)
	)
	(arc
		(start 217.11 138)
		(mid 217.153934 137.893934)
		(end 217.26 137.85)
		(width 0.09)
		(layer "In7.Cu")
		(net 352)
	)
	(arc
		(start 215.91 138)
		(mid 215.953934 137.893934)
		(end 216.06 137.85)
		(width 0.09)
		(layer "In7.Cu")
		(net 352)
	)
	(arc
		(start 219.14 139.88)
		(mid 219.096066 139.986066)
		(end 218.99 140.03)
		(width 0.09)
		(layer "In7.Cu")
		(net 352)
	)
	(arc
		(start 214.41 138.05)
		(mid 214.453934 138.156066)
		(end 214.56 138.2)
		(width 0.09)
		(layer "In7.Cu")
		(net 352)
	)
	(arc
		(start 216.96 138.2)
		(mid 217.066066 138.156066)
		(end 217.11 138.05)
		(width 0.09)
		(layer "In7.Cu")
		(net 352)
	)
	(arc
		(start 215.01 138.05)
		(mid 215.053934 138.156066)
		(end 215.16 138.2)
		(width 0.09)
		(layer "In7.Cu")
		(net 352)
	)
	(arc
		(start 216.36 138.2)
		(mid 216.466066 138.156066)
		(end 216.51 138.05)
		(width 0.09)
		(layer "In7.Cu")
		(net 352)
	)
	(arc
		(start 215.16 138.2)
		(mid 215.266066 138.156066)
		(end 215.31 138.05)
		(width 0.09)
		(layer "In7.Cu")
		(net 352)
	)
	(arc
		(start 214.86 137.85)
		(mid 214.966066 137.893934)
		(end 215.01 138)
		(width 0.09)
		(layer "In7.Cu")
		(net 352)
	)
	(arc
		(start 216.06 137.85)
		(mid 216.166066 137.893934)
		(end 216.21 138)
		(width 0.09)
		(layer "In7.Cu")
		(net 352)
	)
	(arc
		(start 215.46 137.85)
		(mid 215.566066 137.893934)
		(end 215.61 138)
		(width 0.09)
		(layer "In7.Cu")
		(net 352)
	)
	(arc
		(start 217.373578 138.490685)
		(mid 217.460057 138.533304)
		(end 217.556331 138.517455)
		(width 0.09)
		(layer "In7.Cu")
		(net 352)
	)
	(arc
		(start 218.09 139.1)
		(mid 218.196066 139.143934)
		(end 218.24 139.25)
		(width 0.09)
		(layer "In7.Cu")
		(net 352)
	)
	(arc
		(start 216.51 138)
		(mid 216.553934 137.893934)
		(end 216.66 137.85)
		(width 0.09)
		(layer "In7.Cu")
		(net 352)
	)
	(arc
		(start 215.61 138.05)
		(mid 215.653934 138.156066)
		(end 215.76 138.2)
		(width 0.09)
		(layer "In7.Cu")
		(net 352)
	)
	(arc
		(start 214.26 137.85)
		(mid 214.366066 137.893934)
		(end 214.41 138)
		(width 0.09)
		(layer "In7.Cu")
		(net 352)
	)
	(arc
		(start 214.56 138.2)
		(mid 214.666066 138.156066)
		(end 214.71 138.05)
		(width 0.09)
		(layer "In7.Cu")
		(net 352)
	)
	(via
		(at 205.299 129.901)
		(size 0.35)
		(drill 0.15)
		(layers "F.Cu" "B.Cu")
		(remove_unused_layers yes)
		(keep_end_layers yes)
		(zone_layer_connections)
		(net 353)
	)
	(via
		(at 191.65 141.75)
		(size 0.35)
		(drill 0.15)
		(layers "F.Cu" "B.Cu")
		(remove_unused_layers yes)
		(keep_end_layers yes)
		(zone_layer_connections)
		(net 353)
	)
	(segment
		(start 204.980802 129.901)
		(end 205.299 129.901)
		(width 0.1)
		(layer "In11.Cu")
		(net 353)
	)
	(segment
		(start 203.82262 130.986)
		(end 204.15 130.65862)
		(width 0.1)
		(layer "In11.Cu")
		(net 353)
	)
	(segment
		(start 191.6 137.65962)
		(end 191.6 136.2)
		(width 0.1)
		(layer "In11.Cu")
		(net 353)
	)
	(segment
		(start 197.50835 131.826)
		(end 200.024 131.826)
		(width 0.1)
		(layer "In11.Cu")
		(net 353)
	)
	(segment
		(start 195.05 132.95)
		(end 195.9 132.1)
		(width 0.1)
		(layer "In11.Cu")
		(net 353)
	)
	(segment
		(start 192.95 134.65)
		(end 194.65 132.95)
		(width 0.1)
		(layer "In11.Cu")
		(net 353)
	)
	(segment
		(start 191.6 136.2)
		(end 192.95 134.85)
		(width 0.1)
		(layer "In11.Cu")
		(net 353)
	)
	(segment
		(start 204.15 130.65862)
		(end 204.15 130.55)
		(width 0.1)
		(layer "In11.Cu")
		(net 353)
	)
	(segment
		(start 204.324 130.376)
		(end 204.505802 130.376)
		(width 0.1)
		(layer "In11.Cu")
		(net 353)
	)
	(segment
		(start 204.505802 130.376)
		(end 204.980802 129.901)
		(width 0.1)
		(layer "In11.Cu")
		(net 353)
	)
	(segment
		(start 189.95 139.1)
		(end 190.15962 139.1)
		(width 0.1)
		(layer "In11.Cu")
		(net 353)
	)
	(segment
		(start 200.024 131.826)
		(end 200.864 130.986)
		(width 0.1)
		(layer "In11.Cu")
		(net 353)
	)
	(segment
		(start 195.9 132.1)
		(end 197.23435 132.1)
		(width 0.1)
		(layer "In11.Cu")
		(net 353)
	)
	(segment
		(start 204.15 130.55)
		(end 204.324 130.376)
		(width 0.1)
		(layer "In11.Cu")
		(net 353)
	)
	(segment
		(start 190.15962 139.1)
		(end 191.6 137.65962)
		(width 0.1)
		(layer "In11.Cu")
		(net 353)
	)
	(segment
		(start 192.95 134.85)
		(end 192.95 134.65)
		(width 0.1)
		(layer "In11.Cu")
		(net 353)
	)
	(segment
		(start 194.65 132.95)
		(end 195.05 132.95)
		(width 0.1)
		(layer "In11.Cu")
		(net 353)
	)
	(segment
		(start 197.23435 132.1)
		(end 197.50835 131.826)
		(width 0.1)
		(layer "In11.Cu")
		(net 353)
	)
	(segment
		(start 191.65 141.75)
		(end 190.28938 141.75)
		(width 0.1)
		(layer "In11.Cu")
		(net 353)
	)
	(segment
		(start 200.864 130.986)
		(end 203.82262 130.986)
		(width 0.1)
		(layer "In11.Cu")
		(net 353)
	)
	(segment
		(start 189.7 141.16062)
		(end 189.7 139.35)
		(width 0.1)
		(layer "In11.Cu")
		(net 353)
	)
	(segment
		(start 189.7 139.35)
		(end 189.95 139.1)
		(width 0.1)
		(layer "In11.Cu")
		(net 353)
	)
	(segment
		(start 190.28938 141.75)
		(end 189.7 141.16062)
		(width 0.1)
		(layer "In11.Cu")
		(net 353)
	)
	(via
		(at 219.77 140.53)
		(size 0.35)
		(drill 0.15)
		(layers "F.Cu" "B.Cu")
		(remove_unused_layers yes)
		(keep_end_layers yes)
		(zone_layer_connections)
		(net 354)
	)
	(via
		(at 205.299 138.7)
		(size 0.35)
		(drill 0.15)
		(layers "F.Cu" "B.Cu")
		(remove_unused_layers yes)
		(keep_end_layers yes)
		(zone_layer_connections)
		(net 354)
	)
	(segment
		(start 219.77 140.53)
		(end 219.77 140.87)
		(width 0.09)
		(layer "B.Cu")
		(net 354)
	)
	(segment
		(start 210.711175 137.041176)
		(end 210.711175 137.041175)
		(width 0.09)
		(layer "In7.Cu")
		(net 354)
	)
	(segment
		(start 212.332382 137.162382)
		(end 212.39 137.162382)
		(width 0.09)
		(layer "In7.Cu")
		(net 354)
	)
	(segment
		(start 214.732382 137.162382)
		(end 214.79 137.162382)
		(width 0.09)
		(layer "In7.Cu")
		(net 354)
	)
	(segment
		(start 219.77 138.96)
		(end 219.77 140.53)
		(width 0.09)
		(layer "In7.Cu")
		(net 354)
	)
	(segment
		(start 215.332382 137.162382)
		(end 215.39 137.162382)
		(width 0.09)
		(layer "In7.Cu")
		(net 354)
	)
	(segment
		(start 209.86 137.09)
		(end 210.03 136.92)
		(width 0.09)
		(layer "In7.Cu")
		(net 354)
	)
	(segment
		(start 216.83235 136.92)
		(end 217.73 136.92)
		(width 0.09)
		(layer "In7.Cu")
		(net 354)
	)
	(segment
		(start 219.768897 138.554556)
		(end 219.672791 138.650659)
		(width 0.09)
		(layer "In7.Cu")
		(net 354)
	)
	(segment
		(start 215.632382 136.92)
		(end 215.69 136.92)
		(width 0.09)
		(layer "In7.Cu")
		(net 354)
	)
	(segment
		(start 210.83235 136.92)
		(end 210.89 136.92)
		(width 0.09)
		(layer "In7.Cu")
		(net 354)
	)
	(segment
		(start 218.612132 137.59)
		(end 218.637526 137.564607)
		(width 0.09)
		(layer "In7.Cu")
		(net 354)
	)
	(segment
		(start 206.265 139.095)
		(end 208.27 137.09)
		(width 0.09)
		(layer "In7.Cu")
		(net 354)
	)
	(segment
		(start 208.27 137.09)
		(end 209.86 137.09)
		(width 0.09)
		(layer "In7.Cu")
		(net 354)
	)
	(segment
		(start 214.132382 137.162382)
		(end 214.19 137.162382)
		(width 0.09)
		(layer "In7.Cu")
		(net 354)
	)
	(segment
		(start 216.53235 137.162351)
		(end 216.59 137.162351)
		(width 0.09)
		(layer "In7.Cu")
		(net 354)
	)
	(segment
		(start 219.344633 138.130292)
		(end 219.248527 138.226395)
		(width 0.09)
		(layer "In7.Cu")
		(net 354)
	)
	(segment
		(start 216.711175 137.041176)
		(end 216.711175 137.041175)
		(width 0.09)
		(layer "In7.Cu")
		(net 354)
	)
	(segment
		(start 213.711175 137.041176)
		(end 213.711175 137.041175)
		(width 0.09)
		(layer "In7.Cu")
		(net 354)
	)
	(segment
		(start 219.344632 138.130293)
		(end 219.344633 138.130292)
		(width 0.09)
		(layer "In7.Cu")
		(net 354)
	)
	(segment
		(start 211.73235 137.162351)
		(end 211.79 137.162351)
		(width 0.09)
		(layer "In7.Cu")
		(net 354)
	)
	(segment
		(start 211.43235 136.92)
		(end 211.49 136.92)
		(width 0.09)
		(layer "In7.Cu")
		(net 354)
	)
	(segment
		(start 215.932382 137.162382)
		(end 215.99 137.162382)
		(width 0.09)
		(layer "In7.Cu")
		(net 354)
	)
	(segment
		(start 212.632382 136.92)
		(end 212.69 136.92)
		(width 0.09)
		(layer "In7.Cu")
		(net 354)
	)
	(segment
		(start 213.232382 136.92)
		(end 213.29 136.92)
		(width 0.09)
		(layer "In7.Cu")
		(net 354)
	)
	(segment
		(start 211.011175 137.041175)
		(end 211.011175 137.041176)
		(width 0.09)
		(layer "In7.Cu")
		(net 354)
	)
	(segment
		(start 218.612133 137.589999)
		(end 218.612132 137.59)
		(width 0.09)
		(layer "In7.Cu")
		(net 354)
	)
	(segment
		(start 215.032382 136.92)
		(end 215.09 136.92)
		(width 0.09)
		(layer "In7.Cu")
		(net 354)
	)
	(segment
		(start 205.699 139.095)
		(end 206.265 139.095)
		(width 0.09)
		(layer "In7.Cu")
		(net 354)
	)
	(segment
		(start 211.13235 137.162351)
		(end 211.19 137.162351)
		(width 0.09)
		(layer "In7.Cu")
		(net 354)
	)
	(segment
		(start 218.849657 137.77674)
		(end 218.849658 137.776739)
		(width 0.09)
		(layer "In7.Cu")
		(net 354)
	)
	(segment
		(start 219.036396 138.014264)
		(end 219.132501 137.91816)
		(width 0.09)
		(layer "In7.Cu")
		(net 354)
	)
	(segment
		(start 212.03235 136.92)
		(end 212.09 136.92)
		(width 0.09)
		(layer "In7.Cu")
		(net 354)
	)
	(segment
		(start 219.672791 138.862791)
		(end 219.77 138.96)
		(width 0.09)
		(layer "In7.Cu")
		(net 354)
	)
	(segment
		(start 210.03 136.92)
		(end 210.29 136.92)
		(width 0.09)
		(layer "In7.Cu")
		(net 354)
	)
	(segment
		(start 219.460661 138.438527)
		(end 219.46066 138.438528)
		(width 0.09)
		(layer "In7.Cu")
		(net 354)
	)
	(segment
		(start 216.411175 137.041175)
		(end 216.411175 137.041176)
		(width 0.09)
		(layer "In7.Cu")
		(net 354)
	)
	(segment
		(start 211.311175 137.041176)
		(end 211.311175 137.041175)
		(width 0.09)
		(layer "In7.Cu")
		(net 354)
	)
	(segment
		(start 218.824263 138.014263)
		(end 218.824264 138.014264)
		(width 0.09)
		(layer "In7.Cu")
		(net 354)
	)
	(segment
		(start 214.432382 136.92)
		(end 214.49 136.92)
		(width 0.09)
		(layer "In7.Cu")
		(net 354)
	)
	(segment
		(start 219.46066 138.438528)
		(end 219.556765 138.342424)
		(width 0.09)
		(layer "In7.Cu")
		(net 354)
	)
	(segment
		(start 213.53235 137.162351)
		(end 213.59 137.162351)
		(width 0.09)
		(layer "In7.Cu")
		(net 354)
	)
	(segment
		(start 217.73 136.92)
		(end 218.4 137.59)
		(width 0.09)
		(layer "In7.Cu")
		(net 354)
	)
	(segment
		(start 218.849658 137.776739)
		(end 218.824263 137.802131)
		(width 0.09)
		(layer "In7.Cu")
		(net 354)
	)
	(segment
		(start 216.232382 136.92)
		(end 216.29 136.92)
		(width 0.09)
		(layer "In7.Cu")
		(net 354)
	)
	(segment
		(start 211.611175 137.041175)
		(end 211.611175 137.041176)
		(width 0.09)
		(layer "In7.Cu")
		(net 354)
	)
	(segment
		(start 213.83235 136.92)
		(end 213.89 136.92)
		(width 0.09)
		(layer "In7.Cu")
		(net 354)
	)
	(segment
		(start 210.411175 137.041175)
		(end 210.411175 137.041176)
		(width 0.09)
		(layer "In7.Cu")
		(net 354)
	)
	(segment
		(start 212.932382 137.162382)
		(end 212.99 137.162382)
		(width 0.09)
		(layer "In7.Cu")
		(net 354)
	)
	(segment
		(start 213.411175 137.041175)
		(end 213.411175 137.041176)
		(width 0.09)
		(layer "In7.Cu")
		(net 354)
	)
	(segment
		(start 210.53235 137.162351)
		(end 210.59 137.162351)
		(width 0.09)
		(layer "In7.Cu")
		(net 354)
	)
	(segment
		(start 211.911175 137.041176)
		(end 211.911175 137.041175)
		(width 0.09)
		(layer "In7.Cu")
		(net 354)
	)
	(segment
		(start 219.768896 138.554557)
		(end 219.768897 138.554556)
		(width 0.09)
		(layer "In7.Cu")
		(net 354)
	)
	(segment
		(start 219.036397 138.014263)
		(end 219.036396 138.014264)
		(width 0.09)
		(layer "In7.Cu")
		(net 354)
	)
	(segment
		(start 219.248527 138.438527)
		(end 219.248528 138.438528)
		(width 0.09)
		(layer "In7.Cu")
		(net 354)
	)
	(segment
		(start 205.299 138.695)
		(end 205.699 139.095)
		(width 0.09)
		(layer "In7.Cu")
		(net 354)
	)
	(arc
		(start 219.132501 137.91816)
		(mid 219.238567 137.874226)
		(end 219.344633 137.91816)
		(width 0.09)
		(layer "In7.Cu")
		(net 354)
	)
	(arc
		(start 216.111191 137.041191)
		(mid 216.146687 136.955496)
		(end 216.232382 136.92)
		(width 0.09)
		(layer "In7.Cu")
		(net 354)
	)
	(arc
		(start 215.811191 137.041191)
		(mid 215.846687 137.126886)
		(end 215.932382 137.162382)
		(width 0.09)
		(layer "In7.Cu")
		(net 354)
	)
	(arc
		(start 212.99 137.162382)
		(mid 213.075695 137.126886)
		(end 213.111191 137.041191)
		(width 0.09)
		(layer "In7.Cu")
		(net 354)
	)
	(arc
		(start 216.29 136.92)
		(mid 216.375684 136.955491)
		(end 216.411175 137.041175)
		(width 0.09)
		(layer "In7.Cu")
		(net 354)
	)
	(arc
		(start 212.811191 137.041191)
		(mid 212.846687 137.126886)
		(end 212.932382 137.162382)
		(width 0.09)
		(layer "In7.Cu")
		(net 354)
	)
	(arc
		(start 216.711175 137.041175)
		(mid 216.746666 136.955491)
		(end 216.83235 136.92)
		(width 0.09)
		(layer "In7.Cu")
		(net 354)
	)
	(arc
		(start 219.672791 138.650659)
		(mid 219.628857 138.756725)
		(end 219.672791 138.862791)
		(width 0.09)
		(layer "In7.Cu")
		(net 354)
	)
	(arc
		(start 211.911175 137.041175)
		(mid 211.946666 136.955491)
		(end 212.03235 136.92)
		(width 0.09)
		(layer "In7.Cu")
		(net 354)
	)
	(arc
		(start 210.59 137.162351)
		(mid 210.675684 137.12686)
		(end 210.711175 137.041176)
		(width 0.09)
		(layer "In7.Cu")
		(net 354)
	)
	(arc
		(start 219.248528 138.438528)
		(mid 219.354596 138.482463)
		(end 219.460661 138.438527)
		(width 0.09)
		(layer "In7.Cu")
		(net 354)
	)
	(arc
		(start 213.411175 137.041176)
		(mid 213.446666 137.12686)
		(end 213.53235 137.162351)
		(width 0.09)
		(layer "In7.Cu")
		(net 354)
	)
	(arc
		(start 218.637526 137.564607)
		(mid 218.743592 137.520673)
		(end 218.849658 137.564607)
		(width 0.09)
		(layer "In7.Cu")
		(net 354)
	)
	(arc
		(start 212.69 136.92)
		(mid 212.775695 136.955496)
		(end 212.811191 137.041191)
		(width 0.09)
		(layer "In7.Cu")
		(net 354)
	)
	(arc
		(start 211.19 137.162351)
		(mid 211.275684 137.12686)
		(end 211.311175 137.041176)
		(width 0.09)
		(layer "In7.Cu")
		(net 354)
	)
	(arc
		(start 213.711175 137.041175)
		(mid 213.746666 136.955491)
		(end 213.83235 136.92)
		(width 0.09)
		(layer "In7.Cu")
		(net 354)
	)
	(arc
		(start 219.248527 138.226395)
		(mid 219.204593 138.332461)
		(end 219.248527 138.438527)
		(width 0.09)
		(layer "In7.Cu")
		(net 354)
	)
	(arc
		(start 219.768897 138.342424)
		(mid 219.81283 138.44849)
		(end 219.768896 138.554557)
		(width 0.09)
		(layer "In7.Cu")
		(net 354)
	)
	(arc
		(start 211.49 136.92)
		(mid 211.575684 136.955491)
		(end 211.611175 137.041175)
		(width 0.09)
		(layer "In7.Cu")
		(net 354)
	)
	(arc
		(start 215.09 136.92)
		(mid 215.175695 136.955496)
		(end 215.211191 137.041191)
		(width 0.09)
		(layer "In7.Cu")
		(net 354)
	)
	(arc
		(start 214.911191 137.041191)
		(mid 214.946687 136.955496)
		(end 215.032382 136.92)
		(width 0.09)
		(layer "In7.Cu")
		(net 354)
	)
	(arc
		(start 214.49 136.92)
		(mid 214.575695 136.955496)
		(end 214.611191 137.041191)
		(width 0.09)
		(layer "In7.Cu")
		(net 354)
	)
	(arc
		(start 218.824264 138.014264)
		(mid 218.930332 138.058199)
		(end 219.036397 138.014263)
		(width 0.09)
		(layer "In7.Cu")
		(net 354)
	)
	(arc
		(start 211.011175 137.041176)
		(mid 211.046666 137.12686)
		(end 211.13235 137.162351)
		(width 0.09)
		(layer "In7.Cu")
		(net 354)
	)
	(arc
		(start 215.99 137.162382)
		(mid 216.075695 137.126886)
		(end 216.111191 137.041191)
		(width 0.09)
		(layer "In7.Cu")
		(net 354)
	)
	(arc
		(start 216.411175 137.041176)
		(mid 216.446666 137.12686)
		(end 216.53235 137.162351)
		(width 0.09)
		(layer "In7.Cu")
		(net 354)
	)
	(arc
		(start 210.711175 137.041175)
		(mid 210.746666 136.955491)
		(end 210.83235 136.92)
		(width 0.09)
		(layer "In7.Cu")
		(net 354)
	)
	(arc
		(start 215.39 137.162382)
		(mid 215.475695 137.126886)
		(end 215.511191 137.041191)
		(width 0.09)
		(layer "In7.Cu")
		(net 354)
	)
	(arc
		(start 219.556765 138.342424)
		(mid 219.662831 138.29849)
		(end 219.768897 138.342424)
		(width 0.09)
		(layer "In7.Cu")
		(net 354)
	)
	(arc
		(start 215.211191 137.041191)
		(mid 215.246687 137.126886)
		(end 215.332382 137.162382)
		(width 0.09)
		(layer "In7.Cu")
		(net 354)
	)
	(arc
		(start 210.411175 137.041176)
		(mid 210.446666 137.12686)
		(end 210.53235 137.162351)
		(width 0.09)
		(layer "In7.Cu")
		(net 354)
	)
	(arc
		(start 212.39 137.162382)
		(mid 212.475695 137.126886)
		(end 212.511191 137.041191)
		(width 0.09)
		(layer "In7.Cu")
		(net 354)
	)
	(arc
		(start 218.849658 137.564607)
		(mid 218.893591 137.670673)
		(end 218.849657 137.77674)
		(width 0.09)
		(layer "In7.Cu")
		(net 354)
	)
	(arc
		(start 218.4 137.59)
		(mid 218.506068 137.633935)
		(end 218.612133 137.589999)
		(width 0.09)
		(layer "In7.Cu")
		(net 354)
	)
	(arc
		(start 214.611191 137.041191)
		(mid 214.646687 137.126886)
		(end 214.732382 137.162382)
		(width 0.09)
		(layer "In7.Cu")
		(net 354)
	)
	(arc
		(start 212.211191 137.041191)
		(mid 212.246687 137.126886)
		(end 212.332382 137.162382)
		(width 0.09)
		(layer "In7.Cu")
		(net 354)
	)
	(arc
		(start 210.89 136.92)
		(mid 210.975684 136.955491)
		(end 211.011175 137.041175)
		(width 0.09)
		(layer "In7.Cu")
		(net 354)
	)
	(arc
		(start 214.311191 137.041191)
		(mid 214.346687 136.955496)
		(end 214.432382 136.92)
		(width 0.09)
		(layer "In7.Cu")
		(net 354)
	)
	(arc
		(start 212.09 136.92)
		(mid 212.175695 136.955496)
		(end 212.211191 137.041191)
		(width 0.09)
		(layer "In7.Cu")
		(net 354)
	)
	(arc
		(start 214.19 137.162382)
		(mid 214.275695 137.126886)
		(end 214.311191 137.041191)
		(width 0.09)
		(layer "In7.Cu")
		(net 354)
	)
	(arc
		(start 213.59 137.162351)
		(mid 213.675684 137.12686)
		(end 213.711175 137.041176)
		(width 0.09)
		(layer "In7.Cu")
		(net 354)
	)
	(arc
		(start 211.611175 137.041176)
		(mid 211.646666 137.12686)
		(end 211.73235 137.162351)
		(width 0.09)
		(layer "In7.Cu")
		(net 354)
	)
	(arc
		(start 213.89 136.92)
		(mid 213.975695 136.955496)
		(end 214.011191 137.041191)
		(width 0.09)
		(layer "In7.Cu")
		(net 354)
	)
	(arc
		(start 214.79 137.162382)
		(mid 214.875695 137.126886)
		(end 214.911191 137.041191)
		(width 0.09)
		(layer "In7.Cu")
		(net 354)
	)
	(arc
		(start 213.111191 137.041191)
		(mid 213.146687 136.955496)
		(end 213.232382 136.92)
		(width 0.09)
		(layer "In7.Cu")
		(net 354)
	)
	(arc
		(start 211.311175 137.041175)
		(mid 211.346666 136.955491)
		(end 211.43235 136.92)
		(width 0.09)
		(layer "In7.Cu")
		(net 354)
	)
	(arc
		(start 216.59 137.162351)
		(mid 216.675684 137.12686)
		(end 216.711175 137.041176)
		(width 0.09)
		(layer "In7.Cu")
		(net 354)
	)
	(arc
		(start 212.511191 137.041191)
		(mid 212.546687 136.955496)
		(end 212.632382 136.92)
		(width 0.09)
		(layer "In7.Cu")
		(net 354)
	)
	(arc
		(start 211.79 137.162351)
		(mid 211.875684 137.12686)
		(end 211.911175 137.041176)
		(width 0.09)
		(layer "In7.Cu")
		(net 354)
	)
	(arc
		(start 210.29 136.92)
		(mid 210.375684 136.955491)
		(end 210.411175 137.041175)
		(width 0.09)
		(layer "In7.Cu")
		(net 354)
	)
	(arc
		(start 215.511191 137.041191)
		(mid 215.546687 136.955496)
		(end 215.632382 136.92)
		(width 0.09)
		(layer "In7.Cu")
		(net 354)
	)
	(arc
		(start 213.29 136.92)
		(mid 213.375684 136.955491)
		(end 213.411175 137.041175)
		(width 0.09)
		(layer "In7.Cu")
		(net 354)
	)
	(arc
		(start 218.824263 137.802131)
		(mid 218.780329 137.908197)
		(end 218.824263 138.014263)
		(width 0.09)
		(layer "In7.Cu")
		(net 354)
	)
	(arc
		(start 215.69 136.92)
		(mid 215.775695 136.955496)
		(end 215.811191 137.041191)
		(width 0.09)
		(layer "In7.Cu")
		(net 354)
	)
	(arc
		(start 214.011191 137.041191)
		(mid 214.046687 137.126886)
		(end 214.132382 137.162382)
		(width 0.09)
		(layer "In7.Cu")
		(net 354)
	)
	(arc
		(start 219.344633 137.91816)
		(mid 219.388566 138.024226)
		(end 219.344632 138.130293)
		(width 0.09)
		(layer "In7.Cu")
		(net 354)
	)
	(via
		(at 205.299 139.495)
		(size 0.35)
		(drill 0.15)
		(layers "F.Cu" "B.Cu")
		(remove_unused_layers yes)
		(keep_end_layers yes)
		(zone_layer_connections)
		(net 355)
	)
	(via
		(at 222.32 140.53)
		(size 0.35)
		(drill 0.15)
		(layers "F.Cu" "B.Cu")
		(remove_unused_layers yes)
		(keep_end_layers yes)
		(zone_layer_connections)
		(net 355)
	)
	(segment
		(start 222.32 140.53)
		(end 222.32 140.86)
		(width 0.09)
		(layer "B.Cu")
		(net 355)
	)
	(segment
		(start 213.169376 136.399375)
		(end 213.169376 136.399376)
		(width 0.09)
		(layer "In7.Cu")
		(net 355)
	)
	(segment
		(start 209.97 136.56)
		(end 211.958752 136.56)
		(width 0.09)
		(layer "In7.Cu")
		(net 355)
	)
	(segment
		(start 213.68 136.238751)
		(end 213.708752 136.238751)
		(width 0.09)
		(layer "In7.Cu")
		(net 355)
	)
	(segment
		(start 219.05 137.26)
		(end 221.41 139.62)
		(width 0.09)
		(layer "In7.Cu")
		(net 355)
	)
	(segment
		(start 209.08769 136.85)
		(end 209.68 136.85)
		(width 0.09)
		(layer "In7.Cu")
		(net 355)
	)
	(segment
		(start 204.9 139.096)
		(end 204.9 138.54)
		(width 0.09)
		(layer "In7.Cu")
		(net 355)
	)
	(segment
		(start 218.52 137.26)
		(end 219.05 137.26)
		(width 0.09)
		(layer "In7.Cu")
		(net 355)
	)
	(segment
		(start 214.03 136.56)
		(end 217.82 136.56)
		(width 0.09)
		(layer "In7.Cu")
		(net 355)
	)
	(segment
		(start 208.145 136.62)
		(end 208.85769 136.62)
		(width 0.09)
		(layer "In7.Cu")
		(net 355)
	)
	(segment
		(start 221.834264 140.044264)
		(end 222.32 140.53)
		(width 0.09)
		(layer "In7.Cu")
		(net 355)
	)
	(segment
		(start 213.33 136.56)
		(end 213.358752 136.56)
		(width 0.09)
		(layer "In7.Cu")
		(net 355)
	)
	(segment
		(start 212.819376 136.399376)
		(end 212.819376 136.399375)
		(width 0.09)
		(layer "In7.Cu")
		(net 355)
	)
	(segment
		(start 212.119376 136.399376)
		(end 212.119376 136.399375)
		(width 0.09)
		(layer "In7.Cu")
		(net 355)
	)
	(segment
		(start 221.622133 140.044263)
		(end 221.622132 140.044264)
		(width 0.09)
		(layer "In7.Cu")
		(net 355)
	)
	(segment
		(start 206.485 138.28)
		(end 208.145 136.62)
		(width 0.09)
		(layer "In7.Cu")
		(net 355)
	)
	(segment
		(start 212.98 136.238751)
		(end 213.008752 136.238751)
		(width 0.09)
		(layer "In7.Cu")
		(net 355)
	)
	(segment
		(start 212.28 136.238751)
		(end 212.308752 136.238751)
		(width 0.09)
		(layer "In7.Cu")
		(net 355)
	)
	(segment
		(start 217.82 136.56)
		(end 218.52 137.26)
		(width 0.09)
		(layer "In7.Cu")
		(net 355)
	)
	(segment
		(start 213.869376 136.399375)
		(end 213.869376 136.399376)
		(width 0.09)
		(layer "In7.Cu")
		(net 355)
	)
	(segment
		(start 209.68 136.85)
		(end 209.97 136.56)
		(width 0.09)
		(layer "In7.Cu")
		(net 355)
	)
	(segment
		(start 212.63 136.56)
		(end 212.658752 136.56)
		(width 0.09)
		(layer "In7.Cu")
		(net 355)
	)
	(segment
		(start 212.469376 136.399375)
		(end 212.469376 136.399376)
		(width 0.09)
		(layer "In7.Cu")
		(net 355)
	)
	(segment
		(start 208.85769 136.62)
		(end 209.08769 136.85)
		(width 0.09)
		(layer "In7.Cu")
		(net 355)
	)
	(segment
		(start 213.519376 136.399376)
		(end 213.519376 136.399375)
		(width 0.09)
		(layer "In7.Cu")
		(net 355)
	)
	(segment
		(start 205.299 139.495)
		(end 204.9 139.096)
		(width 0.09)
		(layer "In7.Cu")
		(net 355)
	)
	(segment
		(start 221.409999 139.832133)
		(end 221.41 139.832132)
		(width 0.09)
		(layer "In7.Cu")
		(net 355)
	)
	(segment
		(start 204.9 138.54)
		(end 205.16 138.28)
		(width 0.09)
		(layer "In7.Cu")
		(net 355)
	)
	(segment
		(start 205.16 138.28)
		(end 206.485 138.28)
		(width 0.09)
		(layer "In7.Cu")
		(net 355)
	)
	(arc
		(start 213.708752 136.238751)
		(mid 213.82233 136.285797)
		(end 213.869376 136.399375)
		(width 0.09)
		(layer "In7.Cu")
		(net 355)
	)
	(arc
		(start 221.41 139.62)
		(mid 221.453934 139.726067)
		(end 221.409999 139.832133)
		(width 0.09)
		(layer "In7.Cu")
		(net 355)
	)
	(arc
		(start 212.308752 136.238751)
		(mid 212.42233 136.285797)
		(end 212.469376 136.399375)
		(width 0.09)
		(layer "In7.Cu")
		(net 355)
	)
	(arc
		(start 211.958752 136.56)
		(mid 212.07233 136.512954)
		(end 212.119376 136.399376)
		(width 0.09)
		(layer "In7.Cu")
		(net 355)
	)
	(arc
		(start 213.169376 136.399376)
		(mid 213.216422 136.512954)
		(end 213.33 136.56)
		(width 0.09)
		(layer "In7.Cu")
		(net 355)
	)
	(arc
		(start 221.41 139.832132)
		(mid 221.366066 139.938198)
		(end 221.41 140.044264)
		(width 0.09)
		(layer "In7.Cu")
		(net 355)
	)
	(arc
		(start 212.658752 136.56)
		(mid 212.77233 136.512954)
		(end 212.819376 136.399376)
		(width 0.09)
		(layer "In7.Cu")
		(net 355)
	)
	(arc
		(start 212.119376 136.399375)
		(mid 212.166422 136.285797)
		(end 212.28 136.238751)
		(width 0.09)
		(layer "In7.Cu")
		(net 355)
	)
	(arc
		(start 221.622132 140.044264)
		(mid 221.728198 140.00033)
		(end 221.834264 140.044264)
		(width 0.09)
		(layer "In7.Cu")
		(net 355)
	)
	(arc
		(start 221.41 140.044264)
		(mid 221.516067 140.088198)
		(end 221.622133 140.044263)
		(width 0.09)
		(layer "In7.Cu")
		(net 355)
	)
	(arc
		(start 213.519376 136.399375)
		(mid 213.566422 136.285797)
		(end 213.68 136.238751)
		(width 0.09)
		(layer "In7.Cu")
		(net 355)
	)
	(arc
		(start 212.469376 136.399376)
		(mid 212.516422 136.512954)
		(end 212.63 136.56)
		(width 0.09)
		(layer "In7.Cu")
		(net 355)
	)
	(arc
		(start 213.358752 136.56)
		(mid 213.47233 136.512954)
		(end 213.519376 136.399376)
		(width 0.09)
		(layer "In7.Cu")
		(net 355)
	)
	(arc
		(start 213.008752 136.238751)
		(mid 213.12233 136.285797)
		(end 213.169376 136.399375)
		(width 0.09)
		(layer "In7.Cu")
		(net 355)
	)
	(arc
		(start 212.819376 136.399375)
		(mid 212.866422 136.285797)
		(end 212.98 136.238751)
		(width 0.09)
		(layer "In7.Cu")
		(net 355)
	)
	(arc
		(start 213.869376 136.399376)
		(mid 213.916422 136.512954)
		(end 214.03 136.56)
		(width 0.09)
		(layer "In7.Cu")
		(net 355)
	)
	(via
		(at 204.499 130.701)
		(size 0.35)
		(drill 0.15)
		(layers "F.Cu" "B.Cu")
		(remove_unused_layers yes)
		(keep_end_layers yes)
		(zone_layer_connections)
		(net 356)
	)
	(via
		(at 188.147 141.398)
		(size 0.35)
		(drill 0.15)
		(layers "F.Cu" "B.Cu")
		(remove_unused_layers yes)
		(keep_end_layers yes)
		(zone_layer_connections)
		(net 356)
	)
	(segment
		(start 201.7 135.3)
		(end 201.7 135.7)
		(width 0.1)
		(layer "In9.Cu")
		(net 356)
	)
	(segment
		(start 202.4 135.9)
		(end 202.505 135.795)
		(width 0.1)
		(layer "In9.Cu")
		(net 356)
	)
	(segment
		(start 203.225 132.775)
		(end 203.225 133.325)
		(width 0.1)
		(layer "In9.Cu")
		(net 356)
	)
	(segment
		(start 204.23 130.97)
		(end 203.77038 130.97)
		(width 0.1)
		(layer "In9.Cu")
		(net 356)
	)
	(segment
		(start 199.235 138.06332)
		(end 199.235 137.515)
		(width 0.1)
		(layer "In9.Cu")
		(net 356)
	)
	(segment
		(start 199.038348 136.816)
		(end 198.566 136.816)
		(width 0.1)
		(layer "In9.Cu")
		(net 356)
	)
	(segment
		(start 188.147 139.353)
		(end 188.147 141.398)
		(width 0.1)
		(layer "In9.Cu")
		(net 356)
	)
	(segment
		(start 199.235 137.515)
		(end 199.35 137.4)
		(width 0.1)
		(layer "In9.Cu")
		(net 356)
	)
	(segment
		(start 201.7 135.7)
		(end 201.9 135.9)
		(width 0.1)
		(layer "In9.Cu")
		(net 356)
	)
	(segment
		(start 203.225 131.51538)
		(end 203.225 131.825)
		(width 0.1)
		(layer "In9.Cu")
		(net 356)
	)
	(segment
		(start 198.566 136.816)
		(end 198.11 136.36)
		(width 0.1)
		(layer "In9.Cu")
		(net 356)
	)
	(segment
		(start 203.225 133.325)
		(end 202.45 134.1)
		(width 0.1)
		(layer "In9.Cu")
		(net 356)
	)
	(segment
		(start 204.50962 135.9)
		(end 204.85 136.24038)
		(width 0.1)
		(layer "In9.Cu")
		(net 356)
	)
	(segment
		(start 202.505 135.795)
		(end 203.445 135.795)
		(width 0.1)
		(layer "In9.Cu")
		(net 356)
	)
	(segment
		(start 198.11 135.818378)
		(end 197.741622 135.45)
		(width 0.1)
		(layer "In9.Cu")
		(net 356)
	)
	(segment
		(start 189.875 134.35)
		(end 188.85 135.375)
		(width 0.1)
		(layer "In9.Cu")
		(net 356)
	)
	(segment
		(start 195.6 134.94038)
		(end 195.00962 134.35)
		(width 0.1)
		(layer "In9.Cu")
		(net 356)
	)
	(segment
		(start 202.45 134.9)
		(end 202.25 135.1)
		(width 0.1)
		(layer "In9.Cu")
		(net 356)
	)
	(segment
		(start 197.741622 135.45)
		(end 195.9 135.45)
		(width 0.1)
		(layer "In9.Cu")
		(net 356)
	)
	(segment
		(start 203 132.05)
		(end 203 132.55)
		(width 0.1)
		(layer "In9.Cu")
		(net 356)
	)
	(segment
		(start 200.27168 139.1)
		(end 199.235 138.06332)
		(width 0.1)
		(layer "In9.Cu")
		(net 356)
	)
	(segment
		(start 203.77038 130.97)
		(end 203.225 131.51538)
		(width 0.1)
		(layer "In9.Cu")
		(net 356)
	)
	(segment
		(start 201.9 135.9)
		(end 202.4 135.9)
		(width 0.1)
		(layer "In9.Cu")
		(net 356)
	)
	(segment
		(start 202.45 134.1)
		(end 202.45 134.9)
		(width 0.1)
		(layer "In9.Cu")
		(net 356)
	)
	(segment
		(start 199.35 137.4)
		(end 199.35 137.127652)
		(width 0.1)
		(layer "In9.Cu")
		(net 356)
	)
	(segment
		(start 204.55862 139.1)
		(end 200.27168 139.1)
		(width 0.1)
		(layer "In9.Cu")
		(net 356)
	)
	(segment
		(start 198.11 136.36)
		(end 198.11 135.818378)
		(width 0.1)
		(layer "In9.Cu")
		(net 356)
	)
	(segment
		(start 195.9 135.45)
		(end 195.6 135.15)
		(width 0.1)
		(layer "In9.Cu")
		(net 356)
	)
	(segment
		(start 204.85 138.80862)
		(end 204.55862 139.1)
		(width 0.1)
		(layer "In9.Cu")
		(net 356)
	)
	(segment
		(start 203 132.55)
		(end 203.225 132.775)
		(width 0.1)
		(layer "In9.Cu")
		(net 356)
	)
	(segment
		(start 203.55 135.9)
		(end 204.50962 135.9)
		(width 0.1)
		(layer "In9.Cu")
		(net 356)
	)
	(segment
		(start 188.85 135.375)
		(end 188.85 138.65)
		(width 0.1)
		(layer "In9.Cu")
		(net 356)
	)
	(segment
		(start 188.85 138.65)
		(end 188.147 139.353)
		(width 0.1)
		(layer "In9.Cu")
		(net 356)
	)
	(segment
		(start 202.25 135.1)
		(end 201.9 135.1)
		(width 0.1)
		(layer "In9.Cu")
		(net 356)
	)
	(segment
		(start 199.35 137.127652)
		(end 199.038348 136.816)
		(width 0.1)
		(layer "In9.Cu")
		(net 356)
	)
	(segment
		(start 195.6 135.15)
		(end 195.6 134.94038)
		(width 0.1)
		(layer "In9.Cu")
		(net 356)
	)
	(segment
		(start 201.9 135.1)
		(end 201.7 135.3)
		(width 0.1)
		(layer "In9.Cu")
		(net 356)
	)
	(segment
		(start 204.85 136.24038)
		(end 204.85 138.80862)
		(width 0.1)
		(layer "In9.Cu")
		(net 356)
	)
	(segment
		(start 195.00962 134.35)
		(end 189.875 134.35)
		(width 0.1)
		(layer "In9.Cu")
		(net 356)
	)
	(segment
		(start 203.445 135.795)
		(end 203.55 135.9)
		(width 0.1)
		(layer "In9.Cu")
		(net 356)
	)
	(segment
		(start 204.499 130.701)
		(end 204.23 130.97)
		(width 0.1)
		(layer "In9.Cu")
		(net 356)
	)
	(segment
		(start 203.225 131.825)
		(end 203 132.05)
		(width 0.1)
		(layer "In9.Cu")
		(net 356)
	)
	(via
		(at 222.84 140.56)
		(size 0.35)
		(drill 0.15)
		(layers "F.Cu" "B.Cu")
		(remove_unused_layers yes)
		(keep_end_layers yes)
		(zone_layer_connections)
		(net 358)
	)
	(via
		(at 204.499 138.7)
		(size 0.35)
		(drill 0.15)
		(layers "F.Cu" "B.Cu")
		(remove_unused_layers yes)
		(keep_end_layers yes)
		(zone_layer_connections)
		(net 358)
	)
	(segment
		(start 223.14 140.86)
		(end 223.22 140.86)
		(width 0.09)
		(layer "B.Cu")
		(net 358)
	)
	(segment
		(start 222.84 140.56)
		(end 223.14 140.86)
		(width 0.09)
		(layer "B.Cu")
		(net 358)
	)
	(segment
		(start 221.96 141.44)
		(end 218.24 141.44)
		(width 0.09)
		(layer "In7.Cu")
		(net 358)
	)
	(segment
		(start 215.675 138.875)
		(end 209.515381 138.875)
		(width 0.09)
		(layer "In7.Cu")
		(net 358)
	)
	(segment
		(start 204.63362 139.975)
		(end 204.36438 139.975)
		(width 0.09)
		(layer "In7.Cu")
		(net 358)
	)
	(segment
		(start 209.515381 138.875)
		(end 206.964381 141.426)
		(width 0.09)
		(layer "In7.Cu")
		(net 358)
	)
	(segment
		(start 206.964381 141.426)
		(end 205.96538 141.426)
		(width 0.09)
		(layer "In7.Cu")
		(net 358)
	)
	(segment
		(start 204.174 139.025)
		(end 204.499 138.7)
		(width 0.09)
		(layer "In7.Cu")
		(net 358)
	)
	(segment
		(start 204.36438 139.975)
		(end 204.174 139.78462)
		(width 0.09)
		(layer "In7.Cu")
		(net 358)
	)
	(segment
		(start 218.24 141.44)
		(end 215.675 138.875)
		(width 0.09)
		(layer "In7.Cu")
		(net 358)
	)
	(segment
		(start 205.775 141.11638)
		(end 204.63362 139.975)
		(width 0.09)
		(layer "In7.Cu")
		(net 358)
	)
	(segment
		(start 204.174 139.78462)
		(end 204.174 139.025)
		(width 0.09)
		(layer "In7.Cu")
		(net 358)
	)
	(segment
		(start 205.96538 141.426)
		(end 205.775 141.23562)
		(width 0.09)
		(layer "In7.Cu")
		(net 358)
	)
	(segment
		(start 222.84 140.56)
		(end 221.96 141.44)
		(width 0.09)
		(layer "In7.Cu")
		(net 358)
	)
	(segment
		(start 205.775 141.23562)
		(end 205.775 141.11638)
		(width 0.09)
		(layer "In7.Cu")
		(net 358)
	)
	(via
		(at 204.499 139.495)
		(size 0.35)
		(drill 0.15)
		(layers "F.Cu" "B.Cu")
		(remove_unused_layers yes)
		(keep_end_layers yes)
		(zone_layer_connections)
		(net 374)
	)
	(via
		(at 221.49 140.53)
		(size 0.35)
		(drill 0.15)
		(layers "F.Cu" "B.Cu")
		(remove_unused_layers yes)
		(keep_end_layers yes)
		(zone_layer_connections)
		(net 374)
	)
	(segment
		(start 221.49 140.53)
		(end 221.49 140.87)
		(width 0.09)
		(layer "B.Cu")
		(net 374)
	)
	(segment
		(start 217.48 139.58)
		(end 217.9 140)
		(width 0.09)
		(layer "In7.Cu")
		(net 374)
	)
	(segment
		(start 205.725 140.535)
		(end 205.9 140.71)
		(width 0.09)
		(layer "In7.Cu")
		(net 374)
	)
	(segment
		(start 210.89 138.53)
		(end 211.15 138.27)
		(width 0.09)
		(layer "In7.Cu")
		(net 374)
	)
	(segment
		(start 217.9 140)
		(end 217.9 140.7)
		(width 0.09)
		(layer "In7.Cu")
		(net 374)
	)
	(segment
		(start 217.05 138.58)
		(end 217.48 139.01)
		(width 0.09)
		(layer "In7.Cu")
		(net 374)
	)
	(segment
		(start 209.03 138.53)
		(end 210.89 138.53)
		(width 0.09)
		(layer "In7.Cu")
		(net 374)
	)
	(segment
		(start 213.78 138.27)
		(end 213.93 138.27)
		(width 0.09)
		(layer "In7.Cu")
		(net 374)
	)
	(segment
		(start 218.34 141.14)
		(end 221.3 141.14)
		(width 0.09)
		(layer "In7.Cu")
		(net 374)
	)
	(segment
		(start 216.62 138.921494)
		(end 216.62 138.73)
		(width 0.09)
		(layer "In7.Cu")
		(net 374)
	)
	(segment
		(start 211.15 138.27)
		(end 211.38 138.27)
		(width 0.09)
		(layer "In7.Cu")
		(net 374)
	)
	(segment
		(start 216.32 138.73)
		(end 216.32 138.921494)
		(width 0.09)
		(layer "In7.Cu")
		(net 374)
	)
	(segment
		(start 205.9 140.71)
		(end 206.85 140.71)
		(width 0.09)
		(layer "In7.Cu")
		(net 374)
	)
	(segment
		(start 213.93 138.27)
		(end 214.24 138.58)
		(width 0.09)
		(layer "In7.Cu")
		(net 374)
	)
	(segment
		(start 204.874 139.87)
		(end 205.56 139.87)
		(width 0.09)
		(layer "In7.Cu")
		(net 374)
	)
	(segment
		(start 205.56 139.87)
		(end 205.725 140.035)
		(width 0.09)
		(layer "In7.Cu")
		(net 374)
	)
	(segment
		(start 214.24 138.58)
		(end 216.17 138.58)
		(width 0.09)
		(layer "In7.Cu")
		(net 374)
	)
	(segment
		(start 221.3 141.14)
		(end 221.49 140.95)
		(width 0.09)
		(layer "In7.Cu")
		(net 374)
	)
	(segment
		(start 216.77 138.58)
		(end 217.05 138.58)
		(width 0.09)
		(layer "In7.Cu")
		(net 374)
	)
	(segment
		(start 205.725 140.035)
		(end 205.725 140.535)
		(width 0.09)
		(layer "In7.Cu")
		(net 374)
	)
	(segment
		(start 204.499 139.495)
		(end 204.874 139.87)
		(width 0.09)
		(layer "In7.Cu")
		(net 374)
	)
	(segment
		(start 221.49 140.95)
		(end 221.49 140.53)
		(width 0.09)
		(layer "In7.Cu")
		(net 374)
	)
	(segment
		(start 217.9 140.7)
		(end 218.34 141.14)
		(width 0.09)
		(layer "In7.Cu")
		(net 374)
	)
	(segment
		(start 206.85 140.71)
		(end 209.03 138.53)
		(width 0.09)
		(layer "In7.Cu")
		(net 374)
	)
	(segment
		(start 217.48 139.01)
		(end 217.48 139.58)
		(width 0.09)
		(layer "In7.Cu")
		(net 374)
	)
	(arc
		(start 216.62 138.73)
		(mid 216.663934 138.623934)
		(end 216.77 138.58)
		(width 0.09)
		(layer "In7.Cu")
		(net 374)
	)
	(arc
		(start 212.28 138.57)
		(mid 212.386066 138.526066)
		(end 212.43 138.42)
		(width 0.09)
		(layer "In7.Cu")
		(net 374)
	)
	(arc
		(start 212.58 138.27)
		(mid 212.686066 138.313934)
		(end 212.73 138.42)
		(width 0.09)
		(layer "In7.Cu")
		(net 374)
	)
	(arc
		(start 213.33 138.42)
		(mid 213.373934 138.526066)
		(end 213.48 138.57)
		(width 0.09)
		(layer "In7.Cu")
		(net 374)
	)
	(arc
		(start 211.98 138.27)
		(mid 212.086066 138.313934)
		(end 212.13 138.42)
		(width 0.09)
		(layer "In7.Cu")
		(net 374)
	)
	(arc
		(start 212.13 138.42)
		(mid 212.173934 138.526066)
		(end 212.28 138.57)
		(width 0.09)
		(layer "In7.Cu")
		(net 374)
	)
	(arc
		(start 213.03 138.42)
		(mid 213.073934 138.313934)
		(end 213.18 138.27)
		(width 0.09)
		(layer "In7.Cu")
		(net 374)
	)
	(arc
		(start 212.43 138.42)
		(mid 212.473934 138.313934)
		(end 212.58 138.27)
		(width 0.09)
		(layer "In7.Cu")
		(net 374)
	)
	(arc
		(start 211.83 138.42)
		(mid 211.873934 138.313934)
		(end 211.98 138.27)
		(width 0.09)
		(layer "In7.Cu")
		(net 374)
	)
	(arc
		(start 216.17 138.58)
		(mid 216.276066 138.623934)
		(end 216.32 138.73)
		(width 0.09)
		(layer "In7.Cu")
		(net 374)
	)
	(arc
		(start 212.88 138.57)
		(mid 212.986066 138.526066)
		(end 213.03 138.42)
		(width 0.09)
		(layer "In7.Cu")
		(net 374)
	)
	(arc
		(start 213.63 138.42)
		(mid 213.673934 138.313934)
		(end 213.78 138.27)
		(width 0.09)
		(layer "In7.Cu")
		(net 374)
	)
	(arc
		(start 213.48 138.57)
		(mid 213.586066 138.526066)
		(end 213.63 138.42)
		(width 0.09)
		(layer "In7.Cu")
		(net 374)
	)
	(arc
		(start 212.73 138.42)
		(mid 212.773934 138.526066)
		(end 212.88 138.57)
		(width 0.09)
		(layer "In7.Cu")
		(net 374)
	)
	(arc
		(start 216.32 138.921494)
		(mid 216.363934 139.02756)
		(end 216.47 139.071494)
		(width 0.09)
		(layer "In7.Cu")
		(net 374)
	)
	(arc
		(start 211.68 138.57)
		(mid 211.786066 138.526066)
		(end 211.83 138.42)
		(width 0.09)
		(layer "In7.Cu")
		(net 374)
	)
	(arc
		(start 213.18 138.27)
		(mid 213.286066 138.313934)
		(end 213.33 138.42)
		(width 0.09)
		(layer "In7.Cu")
		(net 374)
	)
	(arc
		(start 211.53 138.42)
		(mid 211.573934 138.526066)
		(end 211.68 138.57)
		(width 0.09)
		(layer "In7.Cu")
		(net 374)
	)
	(arc
		(start 216.47 139.071494)
		(mid 216.576066 139.02756)
		(end 216.62 138.921494)
		(width 0.09)
		(layer "In7.Cu")
		(net 374)
	)
	(arc
		(start 211.38 138.27)
		(mid 211.486066 138.313934)
		(end 211.53 138.42)
		(width 0.09)
		(layer "In7.Cu")
		(net 374)
	)
	(segment
		(start 209.998 146.348)
		(end 209.625 145.975)
		(width 0.15)
		(layer "F.Cu")
		(net 379)
	)
	(segment
		(start 211 146.348)
		(end 211.333 146.348)
		(width 0.15)
		(layer "F.Cu")
		(net 379)
	)
	(segment
		(start 211.333 146.348)
		(end 211.5 146.515)
		(width 0.15)
		(layer "F.Cu")
		(net 379)
	)
	(segment
		(start 209.625 145.975)
		(end 209.625 143.75)
		(width 0.15)
		(layer "F.Cu")
		(net 379)
	)
	(segment
		(start 209.875 143.5)
		(end 211.6 143.5)
		(width 0.15)
		(layer "F.Cu")
		(net 379)
	)
	(segment
		(start 209.625 143.75)
		(end 209.875 143.5)
		(width 0.15)
		(layer "F.Cu")
		(net 379)
	)
	(segment
		(start 212.45 142.65)
		(end 212.927 142.65)
		(width 0.15)
		(layer "F.Cu")
		(net 379)
	)
	(segment
		(start 211 146.348)
		(end 209.998 146.348)
		(width 0.15)
		(layer "F.Cu")
		(net 379)
	)
	(segment
		(start 211.6 143.5)
		(end 212.45 142.65)
		(width 0.15)
		(layer "F.Cu")
		(net 379)
	)
	(via
		(at 211.5 146.515)
		(size 0.35)
		(drill 0.15)
		(layers "F.Cu" "B.Cu")
		(remove_unused_layers yes)
		(keep_end_layers yes)
		(zone_layer_connections)
		(net 379)
	)
	(via
		(at 228.175 126.349999)
		(size 0.35)
		(drill 0.15)
		(layers "F.Cu" "B.Cu")
		(remove_unused_layers yes)
		(keep_end_layers yes)
		(zone_layer_connections)
		(net 385)
	)
	(segment
		(start 226.15 127.85)
		(end 226.15 128.2)
		(width 0.09)
		(layer "B.Cu")
		(net 385)
	)
	(segment
		(start 228.35 127.6)
		(end 226.4 127.6)
		(width 0.09)
		(layer "B.Cu")
		(net 385)
	)
	(segment
		(start 226.4 127.6)
		(end 226.15 127.85)
		(width 0.09)
		(layer "B.Cu")
		(net 385)
	)
	(segment
		(start 228.65 127.3)
		(end 228.35 127.6)
		(width 0.09)
		(layer "B.Cu")
		(net 385)
	)
	(segment
		(start 228.65 126.824999)
		(end 228.65 127.3)
		(width 0.09)
		(layer "B.Cu")
		(net 385)
	)
	(segment
		(start 228.175 126.349999)
		(end 228.65 126.824999)
		(width 0.09)
		(layer "B.Cu")
		(net 385)
	)
	(segment
		(start 211.0905 132.949)
		(end 209.6925 134.347)
		(width 0.15)
		(layer "F.Cu")
		(net 387)
	)
	(segment
		(start 213.4435 132.949)
		(end 211.0905 132.949)
		(width 0.15)
		(layer "F.Cu")
		(net 387)
	)
	(via
		(at 200.499 126.701)
		(size 0.35)
		(drill 0.15)
		(layers "F.Cu" "B.Cu")
		(remove_unused_layers yes)
		(keep_end_layers yes)
		(zone_layer_connections)
		(net 387)
	)
	(via
		(at 209.6925 134.347)
		(size 0.35)
		(drill 0.15)
		(layers "F.Cu" "B.Cu")
		(remove_unused_layers yes)
		(keep_end_layers yes)
		(zone_layer_connections)
		(net 387)
	)
	(segment
		(start 206.575 127.175)
		(end 207.45 128.05)
		(width 0.09)
		(layer "In2.Cu")
		(net 387)
	)
	(segment
		(start 208.647 134.347)
		(end 209.6925 134.347)
		(width 0.09)
		(layer "In2.Cu")
		(net 387)
	)
	(segment
		(start 200.499 126.701)
		(end 200.973 127.175)
		(width 0.09)
		(layer "In2.Cu")
		(net 387)
	)
	(segment
		(start 200.973 127.175)
		(end 206.575 127.175)
		(width 0.09)
		(layer "In2.Cu")
		(net 387)
	)
	(segment
		(start 207.45 128.05)
		(end 207.45 133.15)
		(width 0.09)
		(layer "In2.Cu")
		(net 387)
	)
	(segment
		(start 207.45 133.15)
		(end 208.647 134.347)
		(width 0.09)
		(layer "In2.Cu")
		(net 387)
	)
	(via
		(at 195.55 118.2)
		(size 0.35)
		(drill 0.15)
		(layers "F.Cu" "B.Cu")
		(remove_unused_layers yes)
		(keep_end_layers yes)
		(zone_layer_connections)
		(net 388)
	)
	(via
		(at 195.799722 121.468785)
		(size 0.35)
		(drill 0.15)
		(layers "F.Cu" "B.Cu")
		(remove_unused_layers yes)
		(keep_end_layers yes)
		(zone_layer_connections)
		(net 388)
	)
	(segment
		(start 195.6 118.15)
		(end 196.45 118.15)
		(width 0.15)
		(layer "B.Cu")
		(net 388)
	)
	(segment
		(start 196.45 118.15)
		(end 197.319 119.019)
		(width 0.15)
		(layer "B.Cu")
		(net 388)
	)
	(segment
		(start 197.319 119.019)
		(end 197.319 120.169)
		(width 0.15)
		(layer "B.Cu")
		(net 388)
	)
	(segment
		(start 195.55 118.2)
		(end 195.6 118.15)
		(width 0.15)
		(layer "B.Cu")
		(net 388)
	)
	(segment
		(start 195.55 117.25)
		(end 195.55 117.41)
		(width 0.09)
		(layer "In2.Cu")
		(net 388)
	)
	(segment
		(start 193.93299 120.655001)
		(end 193.932989 120.654999)
		(width 0.09)
		(layer "In2.Cu")
		(net 388)
	)
	(segment
		(start 195.55 117.97)
		(end 195.55 118.2)
		(width 0.09)
		(layer "In2.Cu")
		(net 388)
	)
	(segment
		(start 193.88 118.482593)
		(end 194.126297 118.236297)
		(width 0.09)
		(layer "In2.Cu")
		(net 388)
	)
	(segment
		(start 193.964956 120.623032)
		(end 193.93299 120.655001)
		(width 0.09)
		(layer "In2.Cu")
		(net 388)
	)
	(segment
		(start 195.45 117.15)
		(end 195.55 117.25)
		(width 0.09)
		(layer "In2.Cu")
		(net 388)
	)
	(segment
		(start 194.835 120.955)
		(end 194.835 120.835)
		(width 0.09)
		(layer "In2.Cu")
		(net 388)
	)
	(segment
		(start 194.162947 120.821022)
		(end 194.162945 120.821021)
		(width 0.09)
		(layer "In2.Cu")
		(net 388)
	)
	(segment
		(start 195.01 121.12)
		(end 195 121.12)
		(width 0.09)
		(layer "In2.Cu")
		(net 388)
	)
	(segment
		(start 194.34 121.12)
		(end 194.2 121.12)
		(width 0.09)
		(layer "In2.Cu")
		(net 388)
	)
	(segment
		(start 193.68 119.84)
		(end 193.88 119.64)
		(width 0.09)
		(layer "In2.Cu")
		(net 388)
	)
	(segment
		(start 195.799722 121.468785)
		(end 195.358785 121.468785)
		(width 0.09)
		(layer "In2.Cu")
		(net 388)
	)
	(segment
		(start 195.41 117.55)
		(end 195.04 117.55)
		(width 0.09)
		(layer "In2.Cu")
		(net 388)
	)
	(segment
		(start 194.126297 117.593703)
		(end 194.35 117.37)
		(width 0.09)
		(layer "In2.Cu")
		(net 388)
	)
	(segment
		(start 193.88 119.64)
		(end 193.88 118.482593)
		(width 0.09)
		(layer "In2.Cu")
		(net 388)
	)
	(segment
		(start 194.35 117.37)
		(end 194.73 117.37)
		(width 0.09)
		(layer "In2.Cu")
		(net 388)
	)
	(segment
		(start 194.73 117.37)
		(end 194.95 117.15)
		(width 0.09)
		(layer "In2.Cu")
		(net 388)
	)
	(segment
		(start 194.505 120.835)
		(end 194.505 120.955)
		(width 0.09)
		(layer "In2.Cu")
		(net 388)
	)
	(segment
		(start 194.95 117.15)
		(end 195.45 117.15)
		(width 0.09)
		(layer "In2.Cu")
		(net 388)
	)
	(segment
		(start 193.735 120.655)
		(end 193.68 120.6)
		(width 0.09)
		(layer "In2.Cu")
		(net 388)
	)
	(segment
		(start 195.358785 121.468785)
		(end 195.01 121.12)
		(width 0.09)
		(layer "In2.Cu")
		(net 388)
	)
	(segment
		(start 195.04 117.83)
		(end 195.41 117.83)
		(width 0.09)
		(layer "In2.Cu")
		(net 388)
	)
	(segment
		(start 194.126297 118.236297)
		(end 194.126297 117.593703)
		(width 0.09)
		(layer "In2.Cu")
		(net 388)
	)
	(segment
		(start 194.130978 120.852988)
		(end 194.162947 120.821022)
		(width 0.09)
		(layer "In2.Cu")
		(net 388)
	)
	(segment
		(start 194.2 121.12)
		(end 194.130978 121.050978)
		(width 0.09)
		(layer "In2.Cu")
		(net 388)
	)
	(segment
		(start 193.68 120.6)
		(end 193.68 119.84)
		(width 0.09)
		(layer "In2.Cu")
		(net 388)
	)
	(arc
		(start 194.835 120.835)
		(mid 194.786673 120.718327)
		(end 194.67 120.67)
		(width 0.09)
		(layer "In2.Cu")
		(net 388)
	)
	(arc
		(start 194.9 117.69)
		(mid 194.941005 117.788995)
		(end 195.04 117.83)
		(width 0.09)
		(layer "In2.Cu")
		(net 388)
	)
	(arc
		(start 194.162945 120.821021)
		(mid 194.203951 120.722028)
		(end 194.162946 120.623032)
		(width 0.09)
		(layer "In2.Cu")
		(net 388)
	)
	(arc
		(start 193.932989 120.654999)
		(mid 193.833996 120.696005)
		(end 193.735 120.655)
		(width 0.09)
		(layer "In2.Cu")
		(net 388)
	)
	(arc
		(start 195 121.12)
		(mid 194.883327 121.071673)
		(end 194.835 120.955)
		(width 0.09)
		(layer "In2.Cu")
		(net 388)
	)
	(arc
		(start 194.505 120.955)
		(mid 194.456673 121.071673)
		(end 194.34 121.12)
		(width 0.09)
		(layer "In2.Cu")
		(net 388)
	)
	(arc
		(start 194.67 120.67)
		(mid 194.553327 120.718327)
		(end 194.505 120.835)
		(width 0.09)
		(layer "In2.Cu")
		(net 388)
	)
	(arc
		(start 194.130978 121.050978)
		(mid 194.089973 120.951983)
		(end 194.130978 120.852988)
		(width 0.09)
		(layer "In2.Cu")
		(net 388)
	)
	(arc
		(start 195.55 117.41)
		(mid 195.508995 117.508995)
		(end 195.41 117.55)
		(width 0.09)
		(layer "In2.Cu")
		(net 388)
	)
	(arc
		(start 195.41 117.83)
		(mid 195.508995 117.871005)
		(end 195.55 117.97)
		(width 0.09)
		(layer "In2.Cu")
		(net 388)
	)
	(arc
		(start 194.162946 120.623032)
		(mid 194.063951 120.582027)
		(end 193.964956 120.623032)
		(width 0.09)
		(layer "In2.Cu")
		(net 388)
	)
	(arc
		(start 195.04 117.55)
		(mid 194.941005 117.591005)
		(end 194.9 117.69)
		(width 0.09)
		(layer "In2.Cu")
		(net 388)
	)
	(segment
		(start 178.004 131.216)
		(end 178.4035 130.8915)
		(width 0.174)
		(layer "F.Cu")
		(net 389)
	)
	(segment
		(start 178.004 127.967)
		(end 178.4035 128.2915)
		(width 0.174)
		(layer "F.Cu")
		(net 389)
	)
	(via
		(at 178.4035 130.8915)
		(size 0.35)
		(drill 0.15)
		(layers "F.Cu" "B.Cu")
		(remove_unused_layers yes)
		(keep_end_layers yes)
		(zone_layer_connections)
		(net 389)
	)
	(via
		(at 198.899 124.3)
		(size 0.35)
		(drill 0.15)
		(layers "F.Cu" "B.Cu")
		(remove_unused_layers yes)
		(keep_end_layers yes)
		(zone_layer_connections)
		(net 389)
	)
	(via
		(at 178.4035 128.2915)
		(size 0.35)
		(drill 0.15)
		(layers "F.Cu" "B.Cu")
		(remove_unused_layers yes)
		(keep_end_layers yes)
		(zone_layer_connections)
		(net 389)
	)
	(segment
		(start 178.96 129.08)
		(end 179.11 129.08)
		(width 0.09)
		(layer "In9.Cu")
		(net 389)
	)
	(segment
		(start 178.51 129.68)
		(end 179.11 129.68)
		(width 0.09)
		(layer "In9.Cu")
		(net 389)
	)
	(segment
		(start 178.81 128.45)
		(end 178.81 128.93)
		(width 0.09)
		(layer "In9.Cu")
		(net 389)
	)
	(segment
		(start 178.4035 128.2915)
		(end 178.6515 128.2915)
		(width 0.09)
		(layer "In9.Cu")
		(net 389)
	)
	(segment
		(start 178.81 130.715)
		(end 178.6335 130.8915)
		(width 0.09)
		(layer "In9.Cu")
		(net 389)
	)
	(segment
		(start 179.11 129.98)
		(end 178.96 129.98)
		(width 0.09)
		(layer "In9.Cu")
		(net 389)
	)
	(segment
		(start 178.6335 130.8915)
		(end 178.4035 130.8915)
		(width 0.09)
		(layer "In9.Cu")
		(net 389)
	)
	(segment
		(start 178.81 130.13)
		(end 178.81 130.715)
		(width 0.09)
		(layer "In9.Cu")
		(net 389)
	)
	(segment
		(start 179.11 129.38)
		(end 178.51 129.38)
		(width 0.09)
		(layer "In9.Cu")
		(net 389)
	)
	(segment
		(start 178.6515 128.2915)
		(end 178.81 128.45)
		(width 0.09)
		(layer "In9.Cu")
		(net 389)
	)
	(arc
		(start 179.11 129.68)
		(mid 179.216066 129.723934)
		(end 179.26 129.83)
		(width 0.09)
		(layer "In9.Cu")
		(net 389)
	)
	(arc
		(start 178.36 129.53)
		(mid 178.403934 129.636066)
		(end 178.51 129.68)
		(width 0.09)
		(layer "In9.Cu")
		(net 389)
	)
	(arc
		(start 179.11 129.08)
		(mid 179.216066 129.123934)
		(end 179.26 129.23)
		(width 0.09)
		(layer "In9.Cu")
		(net 389)
	)
	(arc
		(start 179.26 129.83)
		(mid 179.216066 129.936066)
		(end 179.11 129.98)
		(width 0.09)
		(layer "In9.Cu")
		(net 389)
	)
	(arc
		(start 178.51 129.38)
		(mid 178.403934 129.423934)
		(end 178.36 129.53)
		(width 0.09)
		(layer "In9.Cu")
		(net 389)
	)
	(arc
		(start 178.96 129.98)
		(mid 178.853934 130.023934)
		(end 178.81 130.13)
		(width 0.09)
		(layer "In9.Cu")
		(net 389)
	)
	(arc
		(start 178.81 128.93)
		(mid 178.853934 129.036066)
		(end 178.96 129.08)
		(width 0.09)
		(layer "In9.Cu")
		(net 389)
	)
	(arc
		(start 179.26 129.23)
		(mid 179.216066 129.336066)
		(end 179.11 129.38)
		(width 0.09)
		(layer "In9.Cu")
		(net 389)
	)
	(segment
		(start 181.2795 124.25788)
		(end 181.46988 124.0675)
		(width 0.09)
		(layer "In11.Cu")
		(net 389)
	)
	(segment
		(start 178.8785 126.3525)
		(end 178.8785 126.20588)
		(width 0.09)
		(layer "In11.Cu")
		(net 389)
	)
	(segment
		(start 180.962 124.7175)
		(end 181.2795 124.4)
		(width 0.09)
		(layer "In11.Cu")
		(net 389)
	)
	(segment
		(start 197.5 123.95)
		(end 197.65 124.1)
		(width 0.09)
		(layer "In11.Cu")
		(net 389)
	)
	(segment
		(start 197.825 124.625)
		(end 198.574 124.625)
		(width 0.09)
		(layer "In11.Cu")
		(net 389)
	)
	(segment
		(start 198.574 124.625)
		(end 198.899 124.3)
		(width 0.09)
		(layer "In11.Cu")
		(net 389)
	)
	(segment
		(start 197.65 124.1)
		(end 197.65 124.45)
		(width 0.09)
		(layer "In11.Cu")
		(net 389)
	)
	(segment
		(start 178.4035 128.2035)
		(end 178.0785 127.8785)
		(width 0.09)
		(layer "In11.Cu")
		(net 389)
	)
	(segment
		(start 180.36688 124.7175)
		(end 180.962 124.7175)
		(width 0.09)
		(layer "In11.Cu")
		(net 389)
	)
	(segment
		(start 178.0785 126.85588)
		(end 178.26888 126.6655)
		(width 0.09)
		(layer "In11.Cu")
		(net 389)
	)
	(segment
		(start 178.5655 126.6655)
		(end 178.8785 126.3525)
		(width 0.09)
		(layer "In11.Cu")
		(net 389)
	)
	(segment
		(start 188.23 123.95)
		(end 197.5 123.95)
		(width 0.09)
		(layer "In11.Cu")
		(net 389)
	)
	(segment
		(start 178.0785 127.8785)
		(end 178.0785 126.85588)
		(width 0.09)
		(layer "In11.Cu")
		(net 389)
	)
	(segment
		(start 182.6235 123.4165)
		(end 187.6965 123.4165)
		(width 0.09)
		(layer "In11.Cu")
		(net 389)
	)
	(segment
		(start 178.8785 126.20588)
		(end 180.36688 124.7175)
		(width 0.09)
		(layer "In11.Cu")
		(net 389)
	)
	(segment
		(start 178.26888 126.6655)
		(end 178.5655 126.6655)
		(width 0.09)
		(layer "In11.Cu")
		(net 389)
	)
	(segment
		(start 187.6965 123.4165)
		(end 188.23 123.95)
		(width 0.09)
		(layer "In11.Cu")
		(net 389)
	)
	(segment
		(start 178.4035 128.2915)
		(end 178.4035 128.2035)
		(width 0.09)
		(layer "In11.Cu")
		(net 389)
	)
	(segment
		(start 181.46988 124.0675)
		(end 181.9725 124.0675)
		(width 0.09)
		(layer "In11.Cu")
		(net 389)
	)
	(segment
		(start 181.2795 124.4)
		(end 181.2795 124.25788)
		(width 0.09)
		(layer "In11.Cu")
		(net 389)
	)
	(segment
		(start 197.65 124.45)
		(end 197.825 124.625)
		(width 0.09)
		(layer "In11.Cu")
		(net 389)
	)
	(segment
		(start 181.9725 124.0675)
		(end 182.6235 123.4165)
		(width 0.09)
		(layer "In11.Cu")
		(net 389)
	)
	(segment
		(start 212.9605 132.43)
		(end 213.4435 131.947)
		(width 0.15)
		(layer "F.Cu")
		(net 390)
	)
	(segment
		(start 210.6245 132.43)
		(end 212.9605 132.43)
		(width 0.15)
		(layer "F.Cu")
		(net 390)
	)
	(segment
		(start 209.7075 133.347)
		(end 210.6245 132.43)
		(width 0.15)
		(layer "F.Cu")
		(net 390)
	)
	(via
		(at 209.7075 133.347)
		(size 0.35)
		(drill 0.15)
		(layers "F.Cu" "B.Cu")
		(remove_unused_layers yes)
		(keep_end_layers yes)
		(zone_layer_connections)
		(net 390)
	)
	(via
		(at 197.281824 121.884732)
		(size 0.35)
		(drill 0.15)
		(layers "F.Cu" "B.Cu")
		(remove_unused_layers yes)
		(keep_end_layers yes)
		(zone_layer_connections)
		(net 390)
	)
	(segment
		(start 198.75 123.35)
		(end 197.284732 121.884732)
		(width 0.09)
		(layer "In2.Cu")
		(net 390)
	)
	(segment
		(start 200.32 124.69)
		(end 200.189 124.559)
		(width 0.09)
		(layer "In2.Cu")
		(net 390)
	)
	(segment
		(start 208.2 132.45)
		(end 208.2 125.65)
		(width 0.09)
		(layer "In2.Cu")
		(net 390)
	)
	(segment
		(start 208.2 125.65)
		(end 207.24 124.69)
		(width 0.09)
		(layer "In2.Cu")
		(net 390)
	)
	(segment
		(start 200.189 124.109)
		(end 199.43 123.35)
		(width 0.09)
		(layer "In2.Cu")
		(net 390)
	)
	(segment
		(start 197.284732 121.884732)
		(end 197.281824 121.884732)
		(width 0.09)
		(layer "In2.Cu")
		(net 390)
	)
	(segment
		(start 199.43 123.35)
		(end 198.75 123.35)
		(width 0.09)
		(layer "In2.Cu")
		(net 390)
	)
	(segment
		(start 209.097 133.347)
		(end 208.2 132.45)
		(width 0.09)
		(layer "In2.Cu")
		(net 390)
	)
	(segment
		(start 209.7075 133.347)
		(end 209.097 133.347)
		(width 0.09)
		(layer "In2.Cu")
		(net 390)
	)
	(segment
		(start 200.189 124.559)
		(end 200.189 124.109)
		(width 0.09)
		(layer "In2.Cu")
		(net 390)
	)
	(segment
		(start 207.24 124.69)
		(end 200.32 124.69)
		(width 0.09)
		(layer "In2.Cu")
		(net 390)
	)
	(segment
		(start 212.9445 133.45)
		(end 211.31 133.45)
		(width 0.15)
		(layer "F.Cu")
		(net 391)
	)
	(segment
		(start 211.31 133.45)
		(end 210.65 134.11)
		(width 0.15)
		(layer "F.Cu")
		(net 391)
	)
	(segment
		(start 213.4435 133.949)
		(end 212.9445 133.45)
		(width 0.15)
		(layer "F.Cu")
		(net 391)
	)
	(segment
		(start 210.023 135.347)
		(end 209.6975 135.347)
		(width 0.15)
		(layer "F.Cu")
		(net 391)
	)
	(segment
		(start 210.65 134.11)
		(end 210.65 134.72)
		(width 0.15)
		(layer "F.Cu")
		(net 391)
	)
	(segment
		(start 210.65 134.72)
		(end 210.023 135.347)
		(width 0.15)
		(layer "F.Cu")
		(net 391)
	)
	(via
		(at 209.6975 135.347)
		(size 0.35)
		(drill 0.15)
		(layers "F.Cu" "B.Cu")
		(net 391)
	)
	(segment
		(start 206.16 129.39)
		(end 209.22 132.45)
		(width 0.15)
		(layer "B.Cu")
		(net 391)
	)
	(segment
		(start 200.159 126.959)
		(end 201.1 127.9)
		(width 0.15)
		(layer "B.Cu")
		(net 391)
	)
	(segment
		(start 197.337264 121.459339)
		(end 197.621824 121.743899)
		(width 0.15)
		(layer "B.Cu")
		(net 391)
	)
	(segment
		(start 197.861 126.241)
		(end 199.719833 126.241)
		(width 0.15)
		(layer "B.Cu")
		(net 391)
	)
	(segment
		(start 196.69 123.65)
		(end 196.69 125.55)
		(width 0.15)
		(layer "B.Cu")
		(net 391)
	)
	(segment
		(start 209.22 134.8695)
		(end 209.6975 135.347)
		(width 0.15)
		(layer "B.Cu")
		(net 391)
	)
	(segment
		(start 201.68 128.360833)
		(end 201.979167 128.66)
		(width 0.15)
		(layer "B.Cu")
		(net 391)
	)
	(segment
		(start 197.621824 121.743899)
		(end 197.621824 122.718176)
		(width 0.15)
		(layer "B.Cu")
		(net 391)
	)
	(segment
		(start 201.68 128.18)
		(end 201.68 128.360833)
		(width 0.15)
		(layer "B.Cu")
		(net 391)
	)
	(segment
		(start 201.1 127.9)
		(end 201.4 127.9)
		(width 0.15)
		(layer "B.Cu")
		(net 391)
	)
	(segment
		(start 201.4 127.9)
		(end 201.68 128.18)
		(width 0.15)
		(layer "B.Cu")
		(net 391)
	)
	(segment
		(start 197.6 125.98)
		(end 197.861 126.241)
		(width 0.15)
		(layer "B.Cu")
		(net 391)
	)
	(segment
		(start 196.69 125.55)
		(end 197.12 125.98)
		(width 0.15)
		(layer "B.Cu")
		(net 391)
	)
	(segment
		(start 197.621824 122.718176)
		(end 196.69 123.65)
		(width 0.15)
		(layer "B.Cu")
		(net 391)
	)
	(segment
		(start 200.159 126.680167)
		(end 200.159 126.959)
		(width 0.15)
		(layer "B.Cu")
		(net 391)
	)
	(segment
		(start 209.22 132.45)
		(end 209.22 134.8695)
		(width 0.15)
		(layer "B.Cu")
		(net 391)
	)
	(segment
		(start 201.979167 128.66)
		(end 205.06 128.66)
		(width 0.15)
		(layer "B.Cu")
		(net 391)
	)
	(segment
		(start 197.169381 121.459339)
		(end 197.337264 121.459339)
		(width 0.15)
		(layer "B.Cu")
		(net 391)
	)
	(segment
		(start 205.06 128.66)
		(end 205.79 129.39)
		(width 0.15)
		(layer "B.Cu")
		(net 391)
	)
	(segment
		(start 197.12 125.98)
		(end 197.6 125.98)
		(width 0.15)
		(layer "B.Cu")
		(net 391)
	)
	(segment
		(start 199.719833 126.241)
		(end 200.159 126.680167)
		(width 0.15)
		(layer "B.Cu")
		(net 391)
	)
	(segment
		(start 205.79 129.39)
		(end 206.16 129.39)
		(width 0.15)
		(layer "B.Cu")
		(net 391)
	)
	(segment
		(start 176.404 126.666)
		(end 176.0045 126.9905)
		(width 0.174)
		(layer "F.Cu")
		(net 393)
	)
	(segment
		(start 176.036 132.15)
		(end 175.95 132.15)
		(width 0.174)
		(layer "F.Cu")
		(net 393)
	)
	(segment
		(start 176.403 132.517)
		(end 176.036 132.15)
		(width 0.174)
		(layer "F.Cu")
		(net 393)
	)
	(via
		(at 198.1 124.3)
		(size 0.35)
		(drill 0.15)
		(layers "F.Cu" "B.Cu")
		(remove_unused_layers yes)
		(keep_end_layers yes)
		(zone_layer_connections)
		(net 393)
	)
	(via
		(at 176.0045 126.9905)
		(size 0.35)
		(drill 0.15)
		(layers "F.Cu" "B.Cu")
		(remove_unused_layers yes)
		(keep_end_layers yes)
		(zone_layer_connections)
		(net 393)
	)
	(via
		(at 175.95 132.15)
		(size 0.35)
		(drill 0.15)
		(layers "F.Cu" "B.Cu")
		(remove_unused_layers yes)
		(keep_end_layers yes)
		(zone_layer_connections)
		(net 393)
	)
	(segment
		(start 175.68 127.315)
		(end 175.68 131.88)
		(width 0.09)
		(layer "In9.Cu")
		(net 393)
	)
	(segment
		(start 175.68 131.88)
		(end 175.95 132.15)
		(width 0.09)
		(layer "In9.Cu")
		(net 393)
	)
	(segment
		(start 176.0045 126.9905)
		(end 175.68 127.315)
		(width 0.09)
		(layer "In9.Cu")
		(net 393)
	)
	(segment
		(start 179.33812 124.7175)
		(end 179.06888 124.7175)
		(width 0.09)
		(layer "In11.Cu")
		(net 393)
	)
	(segment
		(start 184.985 122.5965)
		(end 184.985 122.557835)
		(width 0.09)
		(layer "In11.Cu")
		(net 393)
	)
	(segment
		(start 183.935 122.557835)
		(end 183.935 122.5965)
		(width 0.09)
		(layer "In11.Cu")
		(net 393)
	)
	(segment
		(start 180.63812 123.4175)
		(end 179.33812 124.7175)
		(width 0.09)
		(layer "In11.Cu")
		(net 393)
	)
	(segment
		(start 188.965 123.55)
		(end 188.1865 122.7715)
		(width 0.09)
		(layer "In11.Cu")
		(net 393)
	)
	(segment
		(start 188.1865 122.7715)
		(end 185.16 122.7715)
		(width 0.09)
		(layer "In11.Cu")
		(net 393)
	)
	(segment
		(start 197.668198 123.55)
		(end 188.965 123.55)
		(width 0.09)
		(layer "In11.Cu")
		(net 393)
	)
	(segment
		(start 184.635 122.557835)
		(end 184.635 122.5965)
		(width 0.09)
		(layer "In11.Cu")
		(net 393)
	)
	(segment
		(start 198.1 124.3)
		(end 198.1 123.981802)
		(width 0.09)
		(layer "In11.Cu")
		(net 393)
	)
	(segment
		(start 181.9425 123.4175)
		(end 180.63812 123.4175)
		(width 0.09)
		(layer "In11.Cu")
		(net 393)
	)
	(segment
		(start 184.285 122.5965)
		(end 184.285 122.557835)
		(width 0.09)
		(layer "In11.Cu")
		(net 393)
	)
	(segment
		(start 182.5885 122.7715)
		(end 181.9425 123.4175)
		(width 0.09)
		(layer "In11.Cu")
		(net 393)
	)
	(segment
		(start 178.8 124.98638)
		(end 178.8 125.10662)
		(width 0.09)
		(layer "In11.Cu")
		(net 393)
	)
	(segment
		(start 178.8 125.10662)
		(end 177.56562 126.341)
		(width 0.09)
		(layer "In11.Cu")
		(net 393)
	)
	(segment
		(start 177.56562 126.341)
		(end 176.654 126.341)
		(width 0.09)
		(layer "In11.Cu")
		(net 393)
	)
	(segment
		(start 198.1 123.981802)
		(end 197.668198 123.55)
		(width 0.09)
		(layer "In11.Cu")
		(net 393)
	)
	(segment
		(start 179.06888 124.7175)
		(end 178.8 124.98638)
		(width 0.09)
		(layer "In11.Cu")
		(net 393)
	)
	(segment
		(start 182.5885 122.7715)
		(end 183.76 122.7715)
		(width 0.09)
		(layer "In11.Cu")
		(net 393)
	)
	(segment
		(start 176.654 126.341)
		(end 176.0045 126.9905)
		(width 0.09)
		(layer "In11.Cu")
		(net 393)
	)
	(arc
		(start 184.46 122.7715)
		(mid 184.336256 122.720244)
		(end 184.285 122.5965)
		(width 0.09)
		(layer "In11.Cu")
		(net 393)
	)
	(arc
		(start 184.635 122.5965)
		(mid 184.583744 122.720244)
		(end 184.46 122.7715)
		(width 0.09)
		(layer "In11.Cu")
		(net 393)
	)
	(arc
		(start 184.11 122.382835)
		(mid 183.986256 122.434091)
		(end 183.935 122.557835)
		(width 0.09)
		(layer "In11.Cu")
		(net 393)
	)
	(arc
		(start 184.985 122.557835)
		(mid 184.933744 122.434091)
		(end 184.81 122.382835)
		(width 0.09)
		(layer "In11.Cu")
		(net 393)
	)
	(arc
		(start 184.81 122.382835)
		(mid 184.686256 122.434091)
		(end 184.635 122.557835)
		(width 0.09)
		(layer "In11.Cu")
		(net 393)
	)
	(arc
		(start 183.935 122.5965)
		(mid 183.883744 122.720244)
		(end 183.76 122.7715)
		(width 0.09)
		(layer "In11.Cu")
		(net 393)
	)
	(arc
		(start 184.285 122.557835)
		(mid 184.233744 122.434091)
		(end 184.11 122.382835)
		(width 0.09)
		(layer "In11.Cu")
		(net 393)
	)
	(arc
		(start 185.16 122.7715)
		(mid 185.036256 122.720244)
		(end 184.985 122.5965)
		(width 0.09)
		(layer "In11.Cu")
		(net 393)
	)
	(segment
		(start 183.604 132.517)
		(end 184.0035 132.1925)
		(width 0.174)
		(layer "F.Cu")
		(net 394)
	)
	(via
		(at 184.0035 132.1925)
		(size 0.35)
		(drill 0.15)
		(layers "F.Cu" "B.Cu")
		(remove_unused_layers yes)
		(keep_end_layers yes)
		(zone_layer_connections)
		(net 394)
	)
	(via
		(at 198.1 125.101)
		(size 0.35)
		(drill 0.15)
		(layers "F.Cu" "B.Cu")
		(remove_unused_layers yes)
		(keep_end_layers yes)
		(zone_layer_connections)
		(net 394)
	)
	(segment
		(start 198.1 125.3)
		(end 198.1 125.101)
		(width 0.09)
		(layer "In11.Cu")
		(net 394)
	)
	(segment
		(start 184.39 132.579)
		(end 184.39 133)
		(width 0.09)
		(layer "In11.Cu")
		(net 394)
	)
	(segment
		(start 194.313549 131.1)
		(end 194.58 130.833549)
		(width 0.09)
		(layer "In11.Cu")
		(net 394)
	)
	(segment
		(start 189.095 134.436965)
		(end 189.095 133.875)
		(width 0.09)
		(layer "In11.Cu")
		(net 394)
	)
	(segment
		(start 185.945 133.875)
		(end 185.945 134.43698)
		(width 0.09)
		(layer "In11.Cu")
		(net 394)
	)
	(segment
		(start 189.27 133.7)
		(end 190.99 133.7)
		(width 0.09)
		(layer "In11.Cu")
		(net 394)
	)
	(segment
		(start 188.395 134.43698)
		(end 188.395 133.875)
		(width 0.09)
		(layer "In11.Cu")
		(net 394)
	)
	(segment
		(start 195.7 128.64038)
		(end 197.96438 126.376)
		(width 0.09)
		(layer "In11.Cu")
		(net 394)
	)
	(segment
		(start 190.99 133.7)
		(end 192.08 132.61)
		(width 0.09)
		(layer "In11.Cu")
		(net 394)
	)
	(segment
		(start 194.81 130.31)
		(end 195.103549 130.31)
		(width 0.09)
		(layer "In11.Cu")
		(net 394)
	)
	(segment
		(start 195.7 129.35)
		(end 195.7 128.64038)
		(width 0.09)
		(layer "In11.Cu")
		(net 394)
	)
	(segment
		(start 194.047451 131.1)
		(end 194.313549 131.1)
		(width 0.09)
		(layer "In11.Cu")
		(net 394)
	)
	(segment
		(start 186.995 134.43698)
		(end 186.995 133.875)
		(width 0.09)
		(layer "In11.Cu")
		(net 394)
	)
	(segment
		(start 192.29 131.9)
		(end 193.5 131.9)
		(width 0.09)
		(layer "In11.Cu")
		(net 394)
	)
	(segment
		(start 187.695 134.43698)
		(end 187.695 133.875)
		(width 0.09)
		(layer "In11.Cu")
		(net 394)
	)
	(segment
		(start 187.345 133.875)
		(end 187.345 134.43698)
		(width 0.09)
		(layer "In11.Cu")
		(net 394)
	)
	(segment
		(start 198.124 126.376)
		(end 198.425 126.075)
		(width 0.09)
		(layer "In11.Cu")
		(net 394)
	)
	(segment
		(start 184.0035 132.1925)
		(end 184.39 132.579)
		(width 0.09)
		(layer "In11.Cu")
		(net 394)
	)
	(segment
		(start 192.08 132.11)
		(end 192.29 131.9)
		(width 0.09)
		(layer "In11.Cu")
		(net 394)
	)
	(segment
		(start 188.745 133.875)
		(end 188.745 134.436965)
		(width 0.09)
		(layer "In11.Cu")
		(net 394)
	)
	(segment
		(start 184.39 133)
		(end 185.09 133.7)
		(width 0.09)
		(layer "In11.Cu")
		(net 394)
	)
	(segment
		(start 195.3 130.113549)
		(end 195.3 129.75)
		(width 0.09)
		(layer "In11.Cu")
		(net 394)
	)
	(segment
		(start 186.295 134.43698)
		(end 186.295 133.875)
		(width 0.09)
		(layer "In11.Cu")
		(net 394)
	)
	(segment
		(start 193.779 131.368451)
		(end 194.047451 131.1)
		(width 0.09)
		(layer "In11.Cu")
		(net 394)
	)
	(segment
		(start 193.779 131.621)
		(end 193.779 131.368451)
		(width 0.09)
		(layer "In11.Cu")
		(net 394)
	)
	(segment
		(start 198.425 126.075)
		(end 198.425 125.625)
		(width 0.09)
		(layer "In11.Cu")
		(net 394)
	)
	(segment
		(start 197.96438 126.376)
		(end 198.124 126.376)
		(width 0.09)
		(layer "In11.Cu")
		(net 394)
	)
	(segment
		(start 195.3 129.75)
		(end 195.7 129.35)
		(width 0.09)
		(layer "In11.Cu")
		(net 394)
	)
	(segment
		(start 195.103549 130.31)
		(end 195.3 130.113549)
		(width 0.09)
		(layer "In11.Cu")
		(net 394)
	)
	(segment
		(start 186.645 133.875)
		(end 186.645 134.43698)
		(width 0.09)
		(layer "In11.Cu")
		(net 394)
	)
	(segment
		(start 198.425 125.625)
		(end 198.1 125.3)
		(width 0.09)
		(layer "In11.Cu")
		(net 394)
	)
	(segment
		(start 185.09 133.7)
		(end 185.77 133.7)
		(width 0.09)
		(layer "In11.Cu")
		(net 394)
	)
	(segment
		(start 192.08 132.61)
		(end 192.08 132.11)
		(width 0.09)
		(layer "In11.Cu")
		(net 394)
	)
	(segment
		(start 194.58 130.833549)
		(end 194.58 130.54)
		(width 0.09)
		(layer "In11.Cu")
		(net 394)
	)
	(segment
		(start 188.045 133.875)
		(end 188.045 134.43698)
		(width 0.09)
		(layer "In11.Cu")
		(net 394)
	)
	(segment
		(start 194.58 130.54)
		(end 194.81 130.31)
		(width 0.09)
		(layer "In11.Cu")
		(net 394)
	)
	(segment
		(start 193.5 131.9)
		(end 193.779 131.621)
		(width 0.09)
		(layer "In11.Cu")
		(net 394)
	)
	(arc
		(start 186.645 134.43698)
		(mid 186.696256 134.560724)
		(end 186.82 134.61198)
		(width 0.09)
		(layer "In11.Cu")
		(net 394)
	)
	(arc
		(start 187.17 133.7)
		(mid 187.293744 133.751256)
		(end 187.345 133.875)
		(width 0.09)
		(layer "In11.Cu")
		(net 394)
	)
	(arc
		(start 188.745 134.436965)
		(mid 188.796256 134.560709)
		(end 188.92 134.611965)
		(width 0.09)
		(layer "In11.Cu")
		(net 394)
	)
	(arc
		(start 188.045 134.43698)
		(mid 188.096256 134.560724)
		(end 188.22 134.61198)
		(width 0.09)
		(layer "In11.Cu")
		(net 394)
	)
	(arc
		(start 186.295 133.875)
		(mid 186.346256 133.751256)
		(end 186.47 133.7)
		(width 0.09)
		(layer "In11.Cu")
		(net 394)
	)
	(arc
		(start 188.92 134.611965)
		(mid 189.043744 134.560709)
		(end 189.095 134.436965)
		(width 0.09)
		(layer "In11.Cu")
		(net 394)
	)
	(arc
		(start 187.695 133.875)
		(mid 187.746256 133.751256)
		(end 187.87 133.7)
		(width 0.09)
		(layer "In11.Cu")
		(net 394)
	)
	(arc
		(start 188.57 133.7)
		(mid 188.693744 133.751256)
		(end 188.745 133.875)
		(width 0.09)
		(layer "In11.Cu")
		(net 394)
	)
	(arc
		(start 186.47 133.7)
		(mid 186.593744 133.751256)
		(end 186.645 133.875)
		(width 0.09)
		(layer "In11.Cu")
		(net 394)
	)
	(arc
		(start 189.095 133.875)
		(mid 189.146256 133.751256)
		(end 189.27 133.7)
		(width 0.09)
		(layer "In11.Cu")
		(net 394)
	)
	(arc
		(start 185.945 134.43698)
		(mid 185.996256 134.560724)
		(end 186.12 134.61198)
		(width 0.09)
		(layer "In11.Cu")
		(net 394)
	)
	(arc
		(start 188.395 133.875)
		(mid 188.446256 133.751256)
		(end 188.57 133.7)
		(width 0.09)
		(layer "In11.Cu")
		(net 394)
	)
	(arc
		(start 187.52 134.61198)
		(mid 187.643744 134.560724)
		(end 187.695 134.43698)
		(width 0.09)
		(layer "In11.Cu")
		(net 394)
	)
	(arc
		(start 185.77 133.7)
		(mid 185.893744 133.751256)
		(end 185.945 133.875)
		(width 0.09)
		(layer "In11.Cu")
		(net 394)
	)
	(arc
		(start 186.995 133.875)
		(mid 187.046256 133.751256)
		(end 187.17 133.7)
		(width 0.09)
		(layer "In11.Cu")
		(net 394)
	)
	(arc
		(start 186.12 134.61198)
		(mid 186.243744 134.560724)
		(end 186.295 134.43698)
		(width 0.09)
		(layer "In11.Cu")
		(net 394)
	)
	(arc
		(start 188.22 134.61198)
		(mid 188.343744 134.560724)
		(end 188.395 134.43698)
		(width 0.09)
		(layer "In11.Cu")
		(net 394)
	)
	(arc
		(start 187.87 133.7)
		(mid 187.993744 133.751256)
		(end 188.045 133.875)
		(width 0.09)
		(layer "In11.Cu")
		(net 394)
	)
	(arc
		(start 186.82 134.61198)
		(mid 186.943744 134.560724)
		(end 186.995 134.43698)
		(width 0.09)
		(layer "In11.Cu")
		(net 394)
	)
	(arc
		(start 187.345 134.43698)
		(mid 187.396256 134.560724)
		(end 187.52 134.61198)
		(width 0.09)
		(layer "In11.Cu")
		(net 394)
	)
	(segment
		(start 178.004 131.866)
		(end 178.4035 131.5415)
		(width 0.174)
		(layer "F.Cu")
		(net 395)
	)
	(segment
		(start 178.004 127.316)
		(end 178.4035 127.6405)
		(width 0.174)
		(layer "F.Cu")
		(net 395)
	)
	(via
		(at 178.4035 127.6405)
		(size 0.35)
		(drill 0.15)
		(layers "F.Cu" "B.Cu")
		(remove_unused_layers yes)
		(keep_end_layers yes)
		(zone_layer_connections)
		(net 395)
	)
	(via
		(at 198.1 125.901)
		(size 0.35)
		(drill 0.15)
		(layers "F.Cu" "B.Cu")
		(remove_unused_layers yes)
		(keep_end_layers yes)
		(zone_layer_connections)
		(net 395)
	)
	(via
		(at 178.4035 131.5415)
		(size 0.35)
		(drill 0.15)
		(layers "F.Cu" "B.Cu")
		(remove_unused_layers yes)
		(keep_end_layers yes)
		(zone_layer_connections)
		(net 395)
	)
	(segment
		(start 179.5 128.235)
		(end 179.5 130.96)
		(width 0.09)
		(layer "In9.Cu")
		(net 395)
	)
	(segment
		(start 179.03 127.99)
		(end 179.255 127.99)
		(width 0.09)
		(layer "In9.Cu")
		(net 395)
	)
	(segment
		(start 178.6805 127.6405)
		(end 179.03 127.99)
		(width 0.09)
		(layer "In9.Cu")
		(net 395)
	)
	(segment
		(start 179.255 127.99)
		(end 179.5 128.235)
		(width 0.09)
		(layer "In9.Cu")
		(net 395)
	)
	(segment
		(start 179.5 130.96)
		(end 179.26 131.2)
		(width 0.09)
		(layer "In9.Cu")
		(net 395)
	)
	(segment
		(start 179.05 131.2)
		(end 178.7085 131.5415)
		(width 0.09)
		(layer "In9.Cu")
		(net 395)
	)
	(segment
		(start 178.4035 127.6405)
		(end 178.6805 127.6405)
		(width 0.09)
		(layer "In9.Cu")
		(net 395)
	)
	(segment
		(start 179.26 131.2)
		(end 179.05 131.2)
		(width 0.09)
		(layer "In9.Cu")
		(net 395)
	)
	(segment
		(start 178.7085 131.5415)
		(end 178.4035 131.5415)
		(width 0.09)
		(layer "In9.Cu")
		(net 395)
	)
	(segment
		(start 187.0675 124.0675)
		(end 182.6325 124.0675)
		(width 0.09)
		(layer "In11.Cu")
		(net 395)
	)
	(segment
		(start 182.6325 124.0675)
		(end 181.965758 124.734242)
		(width 0.09)
		(layer "In11.Cu")
		(net 395)
	)
	(segment
		(start 179.64212 126.6655)
		(end 179.06888 126.6655)
		(width 0.09)
		(layer "In11.Cu")
		(net 395)
	)
	(segment
		(start 195.175 124.901)
		(end 195.175 124.551)
		(width 0.09)
		(layer "In11.Cu")
		(net 395)
	)
	(segment
		(start 195.525 124.551)
		(end 195.525 124.901)
		(width 0.09)
		(layer "In11.Cu")
		(net 395)
	)
	(segment
		(start 195.4 125.026)
		(end 195.3 125.026)
		(width 0.09)
		(layer "In11.Cu")
		(net 395)
	)
	(segment
		(start 178.4035 127.5465)
		(end 178.4035 127.6405)
		(width 0.09)
		(layer "In11.Cu")
		(net 395)
	)
	(segment
		(start 187.776 124.776)
		(end 187.0675 124.0675)
		(width 0.09)
		(layer "In11.Cu")
		(net 395)
	)
	(segment
		(start 178.7285 127.2215)
		(end 178.4035 127.5465)
		(width 0.09)
		(layer "In11.Cu")
		(net 395)
	)
	(segment
		(start 194.825 124.551)
		(end 194.825 124.601)
		(width 0.09)
		(layer "In11.Cu")
		(net 395)
	)
	(segment
		(start 192.88 124.776)
		(end 194.65 124.776)
		(width 0.09)
		(layer "In11.Cu")
		(net 395)
	)
	(segment
		(start 187.776 124.776)
		(end 191.988814 124.776)
		(width 0.09)
		(layer "In11.Cu")
		(net 395)
	)
	(segment
		(start 179.06888 126.6655)
		(end 178.7285 127.00588)
		(width 0.09)
		(layer "In11.Cu")
		(net 395)
	)
	(segment
		(start 196.975 124.776)
		(end 196.75 124.776)
		(width 0.09)
		(layer "In11.Cu")
		(net 395)
	)
	(segment
		(start 181.15 124.924622)
		(end 181.15 125.15762)
		(width 0.09)
		(layer "In11.Cu")
		(net 395)
	)
	(segment
		(start 181.15 125.15762)
		(end 179.64212 126.6655)
		(width 0.09)
		(layer "In11.Cu")
		(net 395)
	)
	(segment
		(start 181.965758 124.734242)
		(end 181.34038 124.734242)
		(width 0.09)
		(layer "In11.Cu")
		(net 395)
	)
	(segment
		(start 198.1 125.901)
		(end 196.975 124.776)
		(width 0.09)
		(layer "In11.Cu")
		(net 395)
	)
	(segment
		(start 196.225 124.551)
		(end 196.225 125.001)
		(width 0.09)
		(layer "In11.Cu")
		(net 395)
	)
	(segment
		(start 192.43 124.634823)
		(end 192.43 124.917186)
		(width 0.09)
		(layer "In11.Cu")
		(net 395)
	)
	(segment
		(start 181.34038 124.734242)
		(end 181.15 124.924622)
		(width 0.09)
		(layer "In11.Cu")
		(net 395)
	)
	(segment
		(start 192.597648 124.493647)
		(end 192.571176 124.493647)
		(width 0.09)
		(layer "In11.Cu")
		(net 395)
	)
	(segment
		(start 196.575 124.601)
		(end 196.575 124.551)
		(width 0.09)
		(layer "In11.Cu")
		(net 395)
	)
	(segment
		(start 192.288814 125.058372)
		(end 192.271186 125.058372)
		(width 0.09)
		(layer "In11.Cu")
		(net 395)
	)
	(segment
		(start 178.7285 127.00588)
		(end 178.7285 127.2215)
		(width 0.09)
		(layer "In11.Cu")
		(net 395)
	)
	(segment
		(start 195.875 125.001)
		(end 195.875 124.551)
		(width 0.09)
		(layer "In11.Cu")
		(net 395)
	)
	(segment
		(start 192.738824 124.634824)
		(end 192.738824 124.634823)
		(width 0.09)
		(layer "In11.Cu")
		(net 395)
	)
	(arc
		(start 196.575 124.551)
		(mid 196.523744 124.427256)
		(end 196.4 124.376)
		(width 0.09)
		(layer "In11.Cu")
		(net 395)
	)
	(arc
		(start 192.88 124.776)
		(mid 192.780173 124.734651)
		(end 192.738824 124.634824)
		(width 0.09)
		(layer "In11.Cu")
		(net 395)
	)
	(arc
		(start 192.738824 124.634823)
		(mid 192.697475 124.534996)
		(end 192.597648 124.493647)
		(width 0.09)
		(layer "In11.Cu")
		(net 395)
	)
	(arc
		(start 195.875 124.551)
		(mid 195.823744 124.427256)
		(end 195.7 124.376)
		(width 0.09)
		(layer "In11.Cu")
		(net 395)
	)
	(arc
		(start 195.175 124.551)
		(mid 195.123744 124.427256)
		(end 195 124.376)
		(width 0.09)
		(layer "In11.Cu")
		(net 395)
	)
	(arc
		(start 192.271186 125.058372)
		(mid 192.171352 125.01702)
		(end 192.13 124.917186)
		(width 0.09)
		(layer "In11.Cu")
		(net 395)
	)
	(arc
		(start 192.43 124.917186)
		(mid 192.388648 125.01702)
		(end 192.288814 125.058372)
		(width 0.09)
		(layer "In11.Cu")
		(net 395)
	)
	(arc
		(start 196.05 125.176)
		(mid 195.926256 125.124744)
		(end 195.875 125.001)
		(width 0.09)
		(layer "In11.Cu")
		(net 395)
	)
	(arc
		(start 196.4 124.376)
		(mid 196.276256 124.427256)
		(end 196.225 124.551)
		(width 0.09)
		(layer "In11.Cu")
		(net 395)
	)
	(arc
		(start 195.525 124.901)
		(mid 195.488388 124.989388)
		(end 195.4 125.026)
		(width 0.09)
		(layer "In11.Cu")
		(net 395)
	)
	(arc
		(start 195.3 125.026)
		(mid 195.211612 124.989388)
		(end 195.175 124.901)
		(width 0.09)
		(layer "In11.Cu")
		(net 395)
	)
	(arc
		(start 192.13 124.917186)
		(mid 192.088648 124.817352)
		(end 191.988814 124.776)
		(width 0.09)
		(layer "In11.Cu")
		(net 395)
	)
	(arc
		(start 195 124.376)
		(mid 194.876256 124.427256)
		(end 194.825 124.551)
		(width 0.09)
		(layer "In11.Cu")
		(net 395)
	)
	(arc
		(start 196.75 124.776)
		(mid 196.626256 124.724744)
		(end 196.575 124.601)
		(width 0.09)
		(layer "In11.Cu")
		(net 395)
	)
	(arc
		(start 196.225 125.001)
		(mid 196.173744 125.124744)
		(end 196.05 125.176)
		(width 0.09)
		(layer "In11.Cu")
		(net 395)
	)
	(arc
		(start 194.825 124.601)
		(mid 194.773744 124.724744)
		(end 194.65 124.776)
		(width 0.09)
		(layer "In11.Cu")
		(net 395)
	)
	(arc
		(start 192.571176 124.493647)
		(mid 192.471349 124.534996)
		(end 192.43 124.634823)
		(width 0.09)
		(layer "In11.Cu")
		(net 395)
	)
	(arc
		(start 195.7 124.376)
		(mid 195.576256 124.427256)
		(end 195.525 124.551)
		(width 0.09)
		(layer "In11.Cu")
		(net 395)
	)
	(via
		(at 182.45 151.565)
		(size 0.35)
		(drill 0.15)
		(layers "F.Cu" "B.Cu")
		(remove_unused_layers yes)
		(keep_end_layers yes)
		(zone_layer_connections)
		(net 398)
	)
	(via
		(at 178.05 143.35)
		(size 0.35)
		(drill 0.15)
		(layers "F.Cu" "B.Cu")
		(remove_unused_layers yes)
		(keep_end_layers yes)
		(zone_layer_connections)
		(net 406)
	)
	(via
		(at 175.275 143.825)
		(size 0.35)
		(drill 0.15)
		(layers "F.Cu" "B.Cu")
		(remove_unused_layers yes)
		(keep_end_layers yes)
		(zone_layer_connections)
		(net 406)
	)
	(via
		(at 175.475 143.4515)
		(size 0.35)
		(drill 0.15)
		(layers "F.Cu" "B.Cu")
		(remove_unused_layers yes)
		(keep_end_layers yes)
		(zone_layer_connections)
		(net 406)
	)
	(via
		(at 175.75 143.8)
		(size 0.35)
		(drill 0.15)
		(layers "F.Cu" "B.Cu")
		(remove_unused_layers yes)
		(keep_end_layers yes)
		(zone_layer_connections)
		(net 406)
	)
	(via
		(at 175.525 144.15)
		(size 0.35)
		(drill 0.15)
		(layers "F.Cu" "B.Cu")
		(remove_unused_layers yes)
		(keep_end_layers yes)
		(zone_layer_connections)
		(net 406)
	)
	(segment
		(start 176.77 144.60125)
		(end 177.37125 144.60125)
		(width 0.1)
		(layer "B.Cu")
		(net 406)
	)
	(segment
		(start 176.62 144.45125)
		(end 176.77 144.60125)
		(width 0.1)
		(layer "B.Cu")
		(net 406)
	)
	(segment
		(start 177.37125 144.60125)
		(end 177.75 144.98)
		(width 0.1)
		(layer "B.Cu")
		(net 406)
	)
	(segment
		(start 176.62 143.98875)
		(end 176.62 144.45125)
		(width 0.1)
		(layer "B.Cu")
		(net 406)
	)
	(segment
		(start 178.05 143.35)
		(end 176.8 143.35)
		(width 0.174)
		(layer "B.Cu")
		(net 406)
	)
	(segment
		(start 176.62 143.53)
		(end 176.62 143.98875)
		(width 0.174)
		(layer "B.Cu")
		(net 406)
	)
	(segment
		(start 176.8 143.35)
		(end 176.62 143.53)
		(width 0.174)
		(layer "B.Cu")
		(net 406)
	)
	(via
		(at 184.975 143.4715)
		(size 0.35)
		(drill 0.15)
		(layers "F.Cu" "B.Cu")
		(remove_unused_layers yes)
		(keep_end_layers yes)
		(zone_layer_connections)
		(net 409)
	)
	(via
		(at 184.65 143.8)
		(size 0.35)
		(drill 0.15)
		(layers "F.Cu" "B.Cu")
		(remove_unused_layers yes)
		(keep_end_layers yes)
		(zone_layer_connections)
		(net 409)
	)
	(via
		(at 185.1 143.9)
		(size 0.35)
		(drill 0.15)
		(layers "F.Cu" "B.Cu")
		(remove_unused_layers yes)
		(keep_end_layers yes)
		(zone_layer_connections)
		(net 409)
	)
	(via
		(at 182.2 143.4)
		(size 0.35)
		(drill 0.15)
		(layers "F.Cu" "B.Cu")
		(remove_unused_layers yes)
		(keep_end_layers yes)
		(zone_layer_connections)
		(net 409)
	)
	(via
		(at 184.759142 144.236567)
		(size 0.35)
		(drill 0.15)
		(layers "F.Cu" "B.Cu")
		(remove_unused_layers yes)
		(keep_end_layers yes)
		(zone_layer_connections)
		(net 409)
	)
	(segment
		(start 182.2 143.4)
		(end 183.175 143.4)
		(width 0.174)
		(layer "B.Cu")
		(net 409)
	)
	(segment
		(start 184.15 144.6)
		(end 183.440589 145.309411)
		(width 0.1)
		(layer "B.Cu")
		(net 409)
	)
	(segment
		(start 183.830025 144.055025)
		(end 184.15 144.375)
		(width 0.1)
		(layer "B.Cu")
		(net 409)
	)
	(segment
		(start 183.175 143.4)
		(end 183.830025 144.055025)
		(width 0.174)
		(layer "B.Cu")
		(net 409)
	)
	(segment
		(start 184.15 144.375)
		(end 184.15 144.6)
		(width 0.1)
		(layer "B.Cu")
		(net 409)
	)
	(segment
		(start 183.440589 145.309411)
		(end 183.259411 145.309411)
		(width 0.1)
		(layer "B.Cu")
		(net 409)
	)
	(segment
		(start 192.523133 148.885)
		(end 191.672151 148.885)
		(width 0.1)
		(layer "B.Cu")
		(net 410)
	)
	(segment
		(start 193.375 149.937202)
		(end 193.74 149.572203)
		(width 0.1)
		(layer "B.Cu")
		(net 410)
	)
	(segment
		(start 193.34332 148.545)
		(end 192.863132 148.545)
		(width 0.1)
		(layer "B.Cu")
		(net 410)
	)
	(segment
		(start 195.991776 150.45)
		(end 193.590006 150.45)
		(width 0.1)
		(layer "B.Cu")
		(net 410)
	)
	(segment
		(start 199.47774 146.964036)
		(end 199.609187 146.964036)
		(width 0.2)
		(layer "B.Cu")
		(net 410)
	)
	(segment
		(start 198.582669 147.859107)
		(end 195.991776 150.45)
		(width 0.1)
		(layer "B.Cu")
		(net 410)
	)
	(segment
		(start 189.011679 150.51)
		(end 188.34568 151.176)
		(width 0.1)
		(layer "B.Cu")
		(net 410)
	)
	(segment
		(start 193.590006 150.45)
		(end 193.375 150.234994)
		(width 0.1)
		(layer "B.Cu")
		(net 410)
	)
	(segment
		(start 190.787732 148.427222)
		(end 190.486053 148.728901)
		(width 0.1)
		(layer "B.Cu")
		(net 410)
	)
	(segment
		(start 198.582669 147.859107)
		(end 199.47774 146.964036)
		(width 0.2)
		(layer "B.Cu")
		(net 410)
	)
	(segment
		(start 190.486053 148.728901)
		(end 190.486053 150.045247)
		(width 0.1)
		(layer "B.Cu")
		(net 410)
	)
	(segment
		(start 191.214373 148.427222)
		(end 190.787732 148.427222)
		(width 0.1)
		(layer "B.Cu")
		(net 410)
	)
	(segment
		(start 193.74 149.572203)
		(end 193.74 148.941679)
		(width 0.1)
		(layer "B.Cu")
		(net 410)
	)
	(segment
		(start 190.0213 150.51)
		(end 189.011679 150.51)
		(width 0.1)
		(layer "B.Cu")
		(net 410)
	)
	(segment
		(start 191.672151 148.885)
		(end 191.214373 148.427222)
		(width 0.1)
		(layer "B.Cu")
		(net 410)
	)
	(segment
		(start 200.918542 151.464458)
		(end 200.921 151.462)
		(width 0.201)
		(layer "B.Cu")
		(net 410)
	)
	(segment
		(start 190.486053 150.045247)
		(end 190.0213 150.51)
		(width 0.1)
		(layer "B.Cu")
		(net 410)
	)
	(segment
		(start 188.34568 151.176)
		(end 186.827 151.176)
		(width 0.1)
		(layer "B.Cu")
		(net 410)
	)
	(segment
		(start 193.375 150.234994)
		(end 193.375 149.937202)
		(width 0.1)
		(layer "B.Cu")
		(net 410)
	)
	(segment
		(start 193.74 148.941679)
		(end 193.34332 148.545)
		(width 0.1)
		(layer "B.Cu")
		(net 410)
	)
	(segment
		(start 192.863132 148.545)
		(end 192.523133 148.885)
		(width 0.1)
		(layer "B.Cu")
		(net 410)
	)
	(segment
		(start 185.325 153.08)
		(end 185.33 153.075)
		(width 0.15)
		(layer "B.Cu")
		(net 411)
	)
	(segment
		(start 193.26462 148.735)
		(end 193.55 149.02038)
		(width 0.1)
		(layer "B.Cu")
		(net 411)
	)
	(segment
		(start 190.676053 150.123947)
		(end 190.676053 148.807602)
		(width 0.1)
		(layer "B.Cu")
		(net 411)
	)
	(segment
		(start 193.185 150.335)
		(end 193.55 150.7)
		(width 0.1)
		(layer "B.Cu")
		(net 411)
	)
	(segment
		(start 186.49 151.915)
		(end 187.00519 151.915)
		(width 0.1)
		(layer "B.Cu")
		(net 411)
	)
	(segment
		(start 189.090379 150.7)
		(end 190.1 150.7)
		(width 0.1)
		(layer "B.Cu")
		(net 411)
	)
	(segment
		(start 190.676053 148.807602)
		(end 190.866433 148.617222)
		(width 0.1)
		(layer "B.Cu")
		(net 411)
	)
	(segment
		(start 193.55 149.02038)
		(end 193.55 149.493502)
		(width 0.1)
		(layer "B.Cu")
		(net 411)
	)
	(segment
		(start 193.55 150.7)
		(end 196.25 150.7)
		(width 0.1)
		(layer "B.Cu")
		(net 411)
	)
	(segment
		(start 193.185 149.858501)
		(end 193.185 150.335)
		(width 0.1)
		(layer "B.Cu")
		(net 411)
	)
	(segment
		(start 192.601833 149.075)
		(end 192.941833 148.735)
		(width 0.1)
		(layer "B.Cu")
		(net 411)
	)
	(segment
		(start 197.560986 150.225)
		(end 197.699139 150.086847)
		(width 0.1)
		(layer "B.Cu")
		(net 411)
	)
	(segment
		(start 190.1 150.7)
		(end 190.676053 150.123947)
		(width 0.1)
		(layer "B.Cu")
		(net 411)
	)
	(segment
		(start 190.866433 148.617222)
		(end 191.135673 148.617222)
		(width 0.1)
		(layer "B.Cu")
		(net 411)
	)
	(segment
		(start 185.325 153.95)
		(end 185.325 153.08)
		(width 0.15)
		(layer "B.Cu")
		(net 411)
	)
	(segment
		(start 193.55 149.493502)
		(end 193.185 149.858501)
		(width 0.1)
		(layer "B.Cu")
		(net 411)
	)
	(segment
		(start 192.941833 148.735)
		(end 193.26462 148.735)
		(width 0.1)
		(layer "B.Cu")
		(net 411)
	)
	(segment
		(start 191.593451 149.075)
		(end 192.601833 149.075)
		(width 0.1)
		(layer "B.Cu")
		(net 411)
	)
	(segment
		(start 187.55419 151.366)
		(end 188.424381 151.366)
		(width 0.1)
		(layer "B.Cu")
		(net 411)
	)
	(segment
		(start 185.33 153.075)
		(end 186.49 151.915)
		(width 0.1)
		(layer "B.Cu")
		(net 411)
	)
	(segment
		(start 187.00519 151.915)
		(end 187.55419 151.366)
		(width 0.1)
		(layer "B.Cu")
		(net 411)
	)
	(segment
		(start 191.135673 148.617222)
		(end 191.593451 149.075)
		(width 0.1)
		(layer "B.Cu")
		(net 411)
	)
	(segment
		(start 188.424381 151.366)
		(end 189.090379 150.7)
		(width 0.1)
		(layer "B.Cu")
		(net 411)
	)
	(segment
		(start 196.25 150.7)
		(end 196.725 150.225)
		(width 0.1)
		(layer "B.Cu")
		(net 411)
	)
	(segment
		(start 196.725 150.225)
		(end 197.560986 150.225)
		(width 0.1)
		(layer "B.Cu")
		(net 411)
	)
	(segment
		(start 212.9435 129.45)
		(end 212.9435 129.95)
		(width 0.15)
		(layer "F.Cu")
		(net 417)
	)
	(segment
		(start 198.1 133.101)
		(end 198.899 133.9)
		(width 0.4)
		(layer "F.Cu")
		(net 417)
	)
	(segment
		(start 199.699 136.301)
		(end 199.699 136.291)
		(width 0.4)
		(layer "F.Cu")
		(net 417)
	)
	(segment
		(start 213.9435 134.949)
		(end 213.9435 135.296)
		(width 0.174)
		(layer "F.Cu")
		(net 417)
	)
	(segment
		(start 182.805 136.417)
		(end 183.2045 136.7415)
		(width 0.174)
		(layer "F.Cu")
		(net 417)
	)
	(segment
		(start 178.804 124.066)
		(end 179.2035 123.7415)
		(width 0.174)
		(layer "F.Cu")
		(net 417)
	)
	(segment
		(start 198.85 145.36)
		(end 198.78 145.43)
		(width 0.2)
		(layer "F.Cu")
		(net 417)
	)
	(segment
		(start 184.405 131.216)
		(end 184.8045 130.8915)
		(width 0.174)
		(layer "F.Cu")
		(net 417)
	)
	(segment
		(start 197.299 135.5)
		(end 197.3 135.5)
		(width 0.4)
		(layer "F.Cu")
		(net 417)
	)
	(segment
		(start 196.5 133.101)
		(end 197.299 133.9)
		(width 0.4)
		(layer "F.Cu")
		(net 417)
	)
	(segment
		(start 198.925312 137.16117)
		(end 198.925312 137.127312)
		(width 0.4)
		(layer "F.Cu")
		(net 417)
	)
	(segment
		(start 209.8 154.6805)
		(end 209.8 154.925)
		(width 0.2)
		(layer "F.Cu")
		(net 417)
	)
	(segment
		(start 184.405 124.066)
		(end 184.8045 123.7415)
		(width 0.174)
		(layer "F.Cu")
		(net 417)
	)
	(segment
		(start 177.658427 147.772745)
		(end 177.535682 147.65)
		(width 0.174)
		(layer "F.Cu")
		(net 417)
	)
	(segment
		(start 177.535682 147.65)
		(end 177.45 147.65)
		(width 0.174)
		(layer "F.Cu")
		(net 417)
	)
	(segment
		(start 181.205 125.367)
		(end 180.8055 125.0425)
		(width 0.174)
		(layer "F.Cu")
		(net 417)
	)
	(segment
		(start 226.095632 142.427508)
		(end 225.177508 142.427508)
		(width 0.1)
		(layer "F.Cu")
		(net 417)
	)
	(segment
		(start 182.004 130.566)
		(end 181.6045 130.2415)
		(width 0.174)
		(layer "F.Cu")
		(net 417)
	)
	(segment
		(start 178.804 125.367)
		(end 179.2035 125.0425)
		(width 0.174)
		(layer "F.Cu")
		(net 417)
	)
	(segment
		(start 191.098 120.47)
		(end 191.018 120.55)
		(width 0.15)
		(layer "F.Cu")
		(net 417)
	)
	(segment
		(start 191.7 147.15)
		(end 192.14 147.15)
		(width 0.15)
		(layer "F.Cu")
		(net 417)
	)
	(segment
		(start 223.8865 140.5535)
		(end 223.92 140.52)
		(width 0.09)
		(layer "F.Cu")
		(net 417)
	)
	(segment
		(start 213.0925 135.497)
		(end 212.9435 135.348)
		(width 0.174)
		(layer "F.Cu")
		(net 417)
	)
	(segment
		(start 196.5 131.501)
		(end 195.7 130.701)
		(width 0.4)
		(layer "F.Cu")
		(net 417)
	)
	(segment
		(start 175.604 125.367)
		(end 175.182647 124.807594)
		(width 0.256)
		(layer "F.Cu")
		(net 417)
	)
	(segment
		(start 196.08 135.12)
		(end 196.5 134.7)
		(width 0.4)
		(layer "F.Cu")
		(net 417)
	)
	(segment
		(start 215.9425 131.947)
		(end 215.7425 131.947)
		(width 0.15)
		(layer "F.Cu")
		(net 417)
	)
	(segment
		(start 183.604 128.617)
		(end 184.0035 128.9415)
		(width 0.174)
		(layer "F.Cu")
		(net 417)
	)
	(segment
		(start 213.4435 131.45)
		(end 213.9395 131.45)
		(width 0.174)
		(layer "F.Cu")
		(net 417)
	)
	(segment
		(start 198.1 131.501)
		(end 198.899 132.3)
		(width 0.4)
		(layer "F.Cu")
		(net 417)
	)
	(segment
		(start 181.205 126.666)
		(end 180.8055 126.9905)
		(width 0.174)
		(layer "F.Cu")
		(net 417)
	)
	(segment
		(start 196.499 131.501)
		(end 195.7 132.3)
		(width 0.4)
		(layer "F.Cu")
		(net 417)
	)
	(segment
		(start 214.3 127.6)
		(end 214.3 128.0935)
		(width 0.15)
		(layer "F.Cu")
		(net 417)
	)
	(segment
		(start 215.7425 131.947)
		(end 215.4425 131.647)
		(width 0.15)
		(layer "F.Cu")
		(net 417)
	)
	(segment
		(start 197.3 135.5)
		(end 198.1 134.7)
		(width 0.4)
		(layer "F.Cu")
		(net 417)
	)
	(segment
		(start 194.099 137.901)
		(end 194.099 138.7)
		(width 0.4)
		(layer "F.Cu")
		(net 417)
	)
	(segment
		(start 175.603 132.517)
		(end 175.27 132.85)
		(width 0.174)
		(layer "F.Cu")
		(net 417)
	)
	(segment
		(start 198.899 130.701)
		(end 199.699 129.901)
		(width 0.4)
		(layer "F.Cu")
		(net 417)
	)
	(segment
		(start 181.205 136.417)
		(end 180.8055 136.7415)
		(width 0.174)
		(layer "F.Cu")
		(net 417)
	)
	(segment
		(start 205.649 148.701)
		(end 206.299 148.701)
		(width 0.256)
		(layer "F.Cu")
		(net 417)
	)
	(segment
		(start 176.15 130.313)
		(end 176.403 130.566)
		(width 0.174)
		(layer "F.Cu")
		(net 417)
	)
	(segment
		(start 182.004 128.617)
		(end 181.6045 128.9415)
		(width 0.174)
		(layer "F.Cu")
		(net 417)
	)
	(segment
		(start 196.5 133.101)
		(end 196.499 133.101)
		(width 0.4)
		(layer "F.Cu")
		(net 417)
	)
	(segment
		(start 198.9 133.9)
		(end 199.699 133.101)
		(width 0.4)
		(layer "F.Cu")
		(net 417)
	)
	(segment
		(start 202.1 137.901)
		(end 201.3 137.901)
		(width 0.4)
		(layer "F.Cu")
		(net 417)
	)
	(segment
		(start 210.2 154.2805)
		(end 209.8 154.6805)
		(width 0.2)
		(layer "F.Cu")
		(net 417)
	)
	(segment
		(start 213.9435 134.949)
		(end 213.4435 134.449)
		(width 0.15)
		(layer "F.Cu")
		(net 417)
	)
	(segment
		(start 193.05 120.65)
		(end 192.33 120.65)
		(width 0.15)
		(layer "F.Cu")
		(net 417)
	)
	(segment
		(start 182.004 134.466)
		(end 181.6045 134.7905)
		(width 0.174)
		(layer "F.Cu")
		(net 417)
	)
	(segment
		(start 210.2 154.18)
		(end 210.2 154.2805)
		(width 0.2)
		(layer "F.Cu")
		(net 417)
	)
	(segment
		(start 183.15 128.2915)
		(end 183.1295 128.2915)
		(width 0.174)
		(layer "F.Cu")
		(net 417)
	)
	(segment
		(start 218.8015 141.067)
		(end 218.8015 141.1615)
		(width 0.15)
		(layer "F.Cu")
		(net 417)
	)
	(segment
		(start 225.177508 142.427508)
		(end 224.75 142)
		(width 0.1)
		(layer "F.Cu")
		(net 417)
	)
	(segment
		(start 197.299 132.3)
		(end 197.301 132.3)
		(width 0.4)
		(layer "F.Cu")
		(net 417)
	)
	(segment
		(start 223.3615 141.427)
		(end 223.777284 141.427)
		(width 0.09)
		(layer "F.Cu")
		(net 417)
	)
	(segment
		(start 178.5 137.8375)
		(end 178.4875 137.8375)
		(width 0.1)
		(layer "F.Cu")
		(net 417)
	)
	(segment
		(start 175.604 126.666)
		(end 175.24 126.38)
		(width 0.256)
		(layer "F.Cu")
		(net 417)
	)
	(segment
		(start 214.6935 132.296)
		(end 214.6935 131.7)
		(width 0.174)
		(layer "F.Cu")
		(net 417)
	)
	(segment
		(start 214.3 128.0935)
		(end 213.9435 128.45)
		(width 0.15)
		(layer "F.Cu")
		(net 417)
	)
	(segment
		(start 177.205 136.417)
		(end 176.8055 136.7415)
		(width 0.174)
		(layer "F.Cu")
		(net 417)
	)
	(segment
		(start 210.1965 151.3725)
		(end 209.494501 152.074499)
		(width 0.2)
		(layer "F.Cu")
		(net 417)
	)
	(segment
		(start 182.805 122.766)
		(end 183.2045 122.4415)
		(width 0.174)
		(layer "F.Cu")
		(net 417)
	)
	(segment
		(start 223.7515 142.417)
		(end 223.7515 142.802061)
		(width 0.15)
		(layer "F.Cu")
		(net 417)
	)
	(segment
		(start 183.860904 152.847031)
		(end 183.860904 151.980531)
		(width 0.174)
		(layer "F.Cu")
		(net 417)
	)
	(segment
		(start 198.1 136.301)
		(end 198.1 136.299)
		(width 0.4)
		(layer "F.Cu")
		(net 417)
	)
	(segment
		(start 218.8015 141.1615)
		(end 219.15 141.51)
		(width 0.15)
		(layer "F.Cu")
		(net 417)
	)
	(segment
		(start 192.33 120.65)
		(end 192.15 120.47)
		(width 0.15)
		(layer "F.Cu")
		(net 417)
	)
	(segment
		(start 196.5 137.9)
		(end 197.299 137.101)
		(width 0.4)
		(layer "F.Cu")
		(net 417)
	)
	(segment
		(start 184.405 125.367)
		(end 184.8045 125.0425)
		(width 0.174)
		(layer "F.Cu")
		(net 417)
	)
	(segment
		(start 197.299 137.101)
		(end 197.3 137.101)
		(width 0.4)
		(layer "F.Cu")
		(net 417)
	)
	(segment
		(start 223.7515 142.802061)
		(end 223.216847 143.336714)
		(width 0.15)
		(layer "F.Cu")
		(net 417)
	)
	(segment
		(start 211.536 145.136)
		(end 211.161 145.136)
		(width 0.2)
		(layer "F.Cu")
		(net 417)
	)
	(segment
		(start 223.8865 141.317784)
		(end 223.8865 140.5535)
		(width 0.09)
		(layer "F.Cu")
		(net 417)
	)
	(segment
		(start 197.299 130.701)
		(end 197.3 130.701)
		(width 0.4)
		(layer "F.Cu")
		(net 417)
	)
	(segment
		(start 184.405 127.967)
		(end 184.8045 128.2915)
		(width 0.174)
		(layer "F.Cu")
		(net 417)
	)
	(segment
		(start 176.404 124.717)
		(end 175.604 124.066)
		(width 0.4)
		(layer "F.Cu")
		(net 417)
	)
	(segment
		(start 181.205 133.817)
		(end 180.8055 134.1415)
		(width 0.174)
		(layer "F.Cu")
		(net 417)
	)
	(segment
		(start 211.161 145.136)
		(end 211.125 145.1)
		(width 0.2)
		(layer "F.Cu")
		(net 417)
	)
	(segment
		(start 184.405 132.517)
		(end 184.8045 132.1925)
		(width 0.174)
		(layer "F.Cu")
		(net 417)
	)
	(segment
		(start 184.405 135.117)
		(end 184.8045 135.4415)
		(width 0.174)
		(layer "F.Cu")
		(net 417)
	)
	(segment
		(start 183.604 134.466)
		(end 184.0035 134.7905)
		(width 0.174)
		(layer "F.Cu")
		(net 417)
	)
	(segment
		(start 178.004 134.466)
		(end 178.4035 134.7905)
		(width 0.174)
		(layer "F.Cu")
		(net 417)
	)
	(segment
		(start 214.4435 130.45)
		(end 214.4435 130.698)
		(width 0.174)
		(layer "F.Cu")
		(net 417)
	)
	(segment
		(start 178.005 124.717)
		(end 178.4045 124.3925)
		(width 0.174)
		(layer "F.Cu")
		(net 417)
	)
	(segment
		(start 176.0045 133.5)
		(end 175.6875 133.817)
		(width 0.2)
		(layer "F.Cu")
		(net 417)
	)
	(segment
		(start 198.899 137.101)
		(end 199.699 136.301)
		(width 0.4)
		(layer "F.Cu")
		(net 417)
	)
	(segment
		(start 178.804 135.117)
		(end 179.2035 135.4415)
		(width 0.174)
		(layer "F.Cu")
		(net 417)
	)
	(segment
		(start 178.004 128.617)
		(end 178.4035 128.9415)
		(width 0.174)
		(layer "F.Cu")
		(net 417)
	)
	(segment
		(start 214.6925 130.947)
		(end 215.4425 130.947)
		(width 0.174)
		(layer "F.Cu")
		(net 417)
	)
	(segment
		(start 198.1 137.9)
		(end 198.899 137.101)
		(width 0.4)
		(layer "F.Cu")
		(net 417)
	)
	(segment
		(start 178.804 132.517)
		(end 179.2035 132.1925)
		(width 0.174)
		(layer "F.Cu")
		(net 417)
	)
	(segment
		(start 183.604 130.566)
		(end 184.0035 130.2415)
		(width 0.174)
		(layer "F.Cu")
		(net 417)
	)
	(segment
		(start 198.899 135.5)
		(end 199.699 134.7)
		(width 0.4)
		(layer "F.Cu")
		(net 417)
	)
	(segment
		(start 208.213359 152.020641)
		(end 208.554 151.68)
		(width 0.35)
		(layer "F.Cu")
		(net 417)
	)
	(segment
		(start 195.7 135.5)
		(end 195.7 135.501)
		(width 0.4)
		(layer "F.Cu")
		(net 417)
	)
	(segment
		(start 195.7 135.501)
		(end 196.5 136.301)
		(width 0.4)
		(layer "F.Cu")
		(net 417)
	)
	(segment
		(start 211.498 147.65)
		(end 211.498 148.055)
		(width 0.174)
		(layer "F.Cu")
		(net 417)
	)
	(segment
		(start 182.805 132.517)
		(end 183.2045 132.1925)
		(width 0.174)
		(layer "F.Cu")
		(net 417)
	)
	(segment
		(start 213.9395 131.45)
		(end 213.9425 131.447)
		(width 0.174)
		(layer "F.Cu")
		(net 417)
	)
	(segment
		(start 222.6994 117.1821)
		(end 222.6994 116.7131)
		(width 0.174)
		(layer "F.Cu")
		(net 417)
	)
	(segment
		(start 215.577024 154.382976)
		(end 215.577024 153.9655)
		(width 0.2)
		(layer "F.Cu")
		(net 417)
	)
	(segment
		(start 214.9405 132.949)
		(end 214.9405 132.545)
		(width 0.174)
		(layer "F.Cu")
		(net 417)
	)
	(segment
		(start 214.6925 132.297)
		(end 214.6935 132.296)
		(width 0.174)
		(layer "F.Cu")
		(net 417)
	)
	(segment
		(start 175.603 131.216)
		(end 175.2035 130.8915)
		(width 0.174)
		(layer "F.Cu")
		(net 417)
	)
	(segment
		(start 176.15 128.9)
		(end 176.404 128.646)
		(width 0.174)
		(layer "F.Cu")
		(net 417)
	)
	(segment
		(start 184.405 126.667)
		(end 184.8045 126.9915)
		(width 0.174)
		(layer "F.Cu")
		(net 417)
	)
	(segment
		(start 194.099 137.901)
		(end 194.9 137.901)
		(width 0.4)
		(layer "F.Cu")
		(net 417)
	)
	(segment
		(start 212.127024 154.382976)
		(end 212.127024 153.9655)
		(width 0.2)
		(layer "F.Cu")
		(net 417)
	)
	(segment
		(start 181.205 132.517)
		(end 180.8055 132.1925)
		(width 0.174)
		(layer "F.Cu")
		(net 417)
	)
	(segment
		(start 198.9 132.3)
		(end 199.699 131.501)
		(width 0.4)
		(layer "F.Cu")
		(net 417)
	)
	(segment
		(start 226.55 142.605)
		(end 226.273124 142.605)
		(width 0.1)
		(layer "F.Cu")
		(net 417)
	)
	(segment
		(start 192.15 120.47)
		(end 191.098 120.47)
		(width 0.15)
		(layer "F.Cu")
		(net 417)
	)
	(segment
		(start 197.3 130.701)
		(end 198.1 131.501)
		(width 0.4)
		(layer "F.Cu")
		(net 417)
	)
	(segment
		(start 198.899 133.9)
		(end 198.9 133.9)
		(width 0.4)
		(layer "F.Cu")
		(net 417)
	)
	(segment
		(start 214.4435 130.698)
		(end 214.6925 130.947)
		(width 0.174)
		(layer "F.Cu")
		(net 417)
	)
	(segment
		(start 222.6994 116.7131)
		(end 222.7028 116.7097)
		(width 0.174)
		(layer "F.Cu")
		(net 417)
	)
	(segment
		(start 198.1 134.7)
		(end 198.1 134.701)
		(width 0.4)
		(layer "F.Cu")
		(net 417)
	)
	(segment
		(start 200.05 144.57)
		(end 199.19 145.43)
		(width 0.2)
		(layer "F.Cu")
		(net 417)
	)
	(segment
		(start 198.1 131.5)
		(end 198.899 130.701)
		(width 0.4)
		(layer "F.Cu")
		(net 417)
	)
	(segment
		(start 215.45 154.51)
		(end 215.577024 154.382976)
		(width 0.2)
		(layer "F.Cu")
		(net 417)
	)
	(segment
		(start 176.404 128.646)
		(end 176.404 128.617)
		(width 0.174)
		(layer "F.Cu")
		(net 417)
	)
	(segment
		(start 175.27 132.85)
		(end 175.22 132.85)
		(width 0.174)
		(layer "F.Cu")
		(net 417)
	)
	(segment
		(start 178.804 136.417)
		(end 179.2035 136.7415)
		(width 0.174)
		(layer "F.Cu")
		(net 417)
	)
	(segment
		(start 223.777284 141.427)
		(end 223.8865 141.317784)
		(width 0.09)
		(layer "F.Cu")
		(net 417)
	)
	(segment
		(start 214.9405 132.545)
		(end 214.6925 132.297)
		(width 0.174)
		(layer "F.Cu")
		(net 417)
	)
	(segment
		(start 183.1295 130.8915)
		(end 182.805 131.216)
		(width 0.174)
		(layer "F.Cu")
		(net 417)
	)
	(segment
		(start 182.805 126.666)
		(end 182.4055 126.3415)
		(width 0.174)
		(layer "F.Cu")
		(net 417)
	)
	(segment
		(start 198.1 131.501)
		(end 198.1 131.5)
		(width 0.4)
		(layer "F.Cu")
		(net 417)
	)
	(segment
		(start 200.05 144.41)
		(end 200.05 144.57)
		(width 0.2)
		(layer "F.Cu")
		(net 417)
	)
	(segment
		(start 181.205 124.067)
		(end 180.8055 123.7425)
		(width 0.174)
		(layer "F.Cu")
		(net 417)
	)
	(segment
		(start 178.004 130.566)
		(end 178.4035 130.2415)
		(width 0.174)
		(layer "F.Cu")
		(net 417)
	)
	(segment
		(start 194.39 147.15)
		(end 196.64 147.15)
		(width 0.15)
		(layer "F.Cu")
		(net 417)
	)
	(segment
		(start 196.5 131.501)
		(end 196.499 131.501)
		(width 0.4)
		(layer "F.Cu")
		(net 417)
	)
	(segment
		(start 196.499 133.101)
		(end 195.7 133.9)
		(width 0.4)
		(layer "F.Cu")
		(net 417)
	)
	(segment
		(start 218.6265 145.342)
		(end 218.547 145.342)
		(width 0.177)
		(layer "F.Cu")
		(net 417)
	)
	(segment
		(start 209.494501 152.074499)
		(end 209.494501 152.0945)
		(width 0.2)
		(layer "F.Cu")
		(net 417)
	)
	(segment
		(start 198.925312 137.127312)
		(end 198.899 137.101)
		(width 0.4)
		(layer "F.Cu")
		(net 417)
	)
	(segment
		(start 198.1 136.299)
		(end 198.899 135.5)
		(width 0.4)
		(layer "F.Cu")
		(net 417)
	)
	(segment
		(start 181.205 135.117)
		(end 180.8055 135.4415)
		(width 0.174)
		(layer "F.Cu")
		(net 417)
	)
	(segment
		(start 198.85 144.53)
		(end 198.85 145.36)
		(width 0.2)
		(layer "F.Cu")
		(net 417)
	)
	(segment
		(start 213.9435 135.296)
		(end 213.7425 135.497)
		(width 0.174)
		(layer "F.Cu")
		(net 417)
	)
	(segment
		(start 223.0015 141.067)
		(end 223.3615 141.427)
		(width 0.09)
		(layer "F.Cu")
		(net 417)
	)
	(segment
		(start 223.216847 143.336714)
		(end 222.826888 142.946755)
		(width 0.15)
		(layer "F.Cu")
		(net 417)
	)
	(segment
		(start 212.9435 135.348)
		(end 212.9435 134.949)
		(width 0.174)
		(layer "F.Cu")
		(net 417)
	)
	(segment
		(start 213.4435 132.447)
		(end 213.8425 132.447)
		(width 0.174)
		(layer "F.Cu")
		(net 417)
	)
	(segment
		(start 212 154.51)
		(end 212.127024 154.382976)
		(width 0.2)
		(layer "F.Cu")
		(net 417)
	)
	(segment
		(start 198.1 134.701)
		(end 198.899 135.5)
		(width 0.4)
		(layer "F.Cu")
		(net 417)
	)
	(segment
		(start 192.14 147.15)
		(end 194.39 147.15)
		(width 0.15)
		(layer "F.Cu")
		(net 417)
	)
	(segment
		(start 182.004 124.717)
		(end 181.6045 124.3925)
		(width 0.174)
		(layer "F.Cu")
		(net 417)
	)
	(segment
		(start 183.1295 128.2915)
		(end 182.805 127.967)
		(width 0.174)
		(layer "F.Cu")
		(net 417)
	)
	(segment
		(start 197.299 133.9)
		(end 197.301 133.9)
		(width 0.4)
		(layer "F.Cu")
		(net 417)
	)
	(segment
		(start 178.804 133.817)
		(end 179.2035 134.1415)
		(width 0.174)
		(layer "F.Cu")
		(net 417)
	)
	(segment
		(start 195.7 137.101)
		(end 196.5 136.301)
		(width 0.4)
		(layer "F.Cu")
		(net 417)
	)
	(segment
		(start 226.273124 142.605)
		(end 226.095632 142.427508)
		(width 0.1)
		(layer "F.Cu")
		(net 417)
	)
	(segment
		(start 213.8425 132.447)
		(end 214.0925 132.197)
		(width 0.174)
		(layer "F.Cu")
		(net 417)
	)
	(segment
		(start 184.218404 153.204531)
		(end 183.860904 152.847031)
		(width 0.174)
		(layer "F.Cu")
		(net 417)
	)
	(segment
		(start 208.124226 152.020641)
		(end 208.213359 152.020641)
		(width 0.35)
		(layer "F.Cu")
		(net 417)
	)
	(segment
		(start 197.301 132.3)
		(end 198.1 131.501)
		(width 0.4)
		(layer "F.Cu")
		(net 417)
	)
	(segment
		(start 196.5 131.501)
		(end 197.299 132.3)
		(width 0.4)
		(layer "F.Cu")
		(net 417)
	)
	(segment
		(start 198.1 137.901)
		(end 198.1 137.9)
		(width 0.4)
		(layer "F.Cu")
		(net 417)
	)
	(segment
		(start 177.203 122.766)
		(end 176.8035 122.4415)
		(width 0.174)
		(layer "F.Cu")
		(net 417)
	)
	(segment
		(start 197.3 137.101)
		(end 198.1 137.901)
		(width 0.4)
		(layer "F.Cu")
		(net 417)
	)
	(segment
		(start 198.899 132.3)
		(end 198.9 132.3)
		(width 0.4)
		(layer "F.Cu")
		(net 417)
	)
	(segment
		(start 218.547 145.342)
		(end 218.1 144.895)
		(width 0.177)
		(layer "F.Cu")
		(net 417)
	)
	(segment
		(start 175.604 135.117)
		(end 176.404 134.466)
		(width 0.256)
		(layer "F.Cu")
		(net 417)
	)
	(segment
		(start 219.15 141.51)
		(end 219.15 141.8)
		(width 0.15)
		(layer "F.Cu")
		(net 417)
	)
	(segment
		(start 197.301 133.9)
		(end 198.1 133.101)
		(width 0.4)
		(layer "F.Cu")
		(net 417)
	)
	(segment
		(start 199.699 136.291)
		(end 200.09 135.9)
		(width 0.4)
		(layer "F.Cu")
		(net 417)
	)
	(segment
		(start 176.15 130.25)
		(end 176.15 130.313)
		(width 0.174)
		(layer "F.Cu")
		(net 417)
	)
	(segment
		(start 196.08 135.12)
		(end 195.7 135.5)
		(width 0.4)
		(layer "F.Cu")
		(net 417)
	)
	(segment
		(start 196.5 137.901)
		(end 196.5 137.9)
		(width 0.4)
		(layer "F.Cu")
		(net 417)
	)
	(segment
		(start 210.2 151.3725)
		(end 210.1965 151.3725)
		(width 0.2)
		(layer "F.Cu")
		(net 417)
	)
	(segment
		(start 175.604 127.967)
		(end 175.26 128.35)
		(width 0.256)
		(layer "F.Cu")
		(net 417)
	)
	(segment
		(start 183.604 124.717)
		(end 184.0035 124.3925)
		(width 0.174)
		(layer "F.Cu")
		(net 417)
	)
	(segment
		(start 184.405 133.817)
		(end 184.8045 134.1415)
		(width 0.174)
		(layer "F.Cu")
		(net 417)
	)
	(segment
		(start 213.7425 135.497)
		(end 213.0925 135.497)
		(width 0.174)
		(layer "F.Cu")
		(net 417)
	)
	(segment
		(start 224.75 142)
		(end 224.75 141.8)
		(width 0.1)
		(layer "F.Cu")
		(net 417)
	)
	(segment
		(start 195.7 137.101)
		(end 196.5 137.901)
		(width 0.4)
		(layer "F.Cu")
		(net 417)
	)
	(segment
		(start 218.1 144.895)
		(end 218.1 144.495)
		(width 0.177)
		(layer "F.Cu")
		(net 417)
	)
	(segment
		(start 175.6875 133.817)
		(end 175.604 133.817)
		(width 0.2)
		(layer "F.Cu")
		(net 417)
	)
	(segment
		(start 199.19 145.43)
		(end 198.78 145.43)
		(width 0.2)
		(layer "F.Cu")
		(net 417)
	)
	(segment
		(start 223.6015 142.267)
		(end 223.7515 142.417)
		(width 0.15)
		(layer "F.Cu")
		(net 417)
	)
	(segment
		(start 178.804 126.666)
		(end 179.2035 126.9905)
		(width 0.174)
		(layer "F.Cu")
		(net 417)
	)
	(segment
		(start 178.4875 137.8375)
		(end 178.475 137.825)
		(width 0.1)
		(layer "F.Cu")
		(net 417)
	)
	(segment
		(start 181.75 137.8375)
		(end 180.7 137.8375)
		(width 0.256)
		(layer "F.Cu")
		(net 417)
	)
	(via
		(at 211.69 119.89)
		(size 0.35)
		(drill 0.15)
		(layers "F.Cu" "B.Cu")
		(remove_unused_layers yes)
		(keep_end_layers yes)
		(zone_layer_connections "In1.Cu" "In3.Cu" "In5.Cu" "In8.Cu" "In10.Cu" "In12.Cu")
		(net 417)
	)
	(via
		(at 179.9 141.9375)
		(size 0.35)
		(drill 0.15)
		(layers "F.Cu" "B.Cu")
		(remove_unused_layers yes)
		(keep_end_layers yes)
		(zone_layer_connections "In1.Cu" "In3.Cu" "In4.Cu" "In5.Cu" "In8.Cu" "In10.Cu"
			"In11.Cu" "In12.Cu"
		)
		(net 417)
	)
	(via
		(at 176.0045 134.7905)
		(size 0.35)
		(drill 0.15)
		(layers "F.Cu" "B.Cu")
		(remove_unused_layers yes)
		(keep_end_layers yes)
		(zone_layer_connections "In1.Cu" "In3.Cu" "In5.Cu" "In8.Cu" "In10.Cu" "In12.Cu")
		(net 417)
	)
	(via
		(at 218.85 119.7234)
		(size 0.35)
		(drill 0.15)
		(layers "F.Cu" "B.Cu")
		(remove_unused_layers yes)
		(keep_end_layers yes)
		(zone_layer_connections "In1.Cu" "In3.Cu" "In5.Cu" "In8.Cu" "In10.Cu" "In12.Cu")
		(net 417)
	)
	(via
		(at 215.78 149.24)
		(size 0.35)
		(drill 0.15)
		(layers "F.Cu" "B.Cu")
		(remove_unused_layers yes)
		(keep_end_layers yes)
		(zone_layer_connections "In1.Cu" "In3.Cu" "In5.Cu" "In8.Cu" "In10.Cu" "In12.Cu")
		(net 417)
	)
	(via
		(at 185.41 117.946)
		(size 0.35)
		(drill 0.15)
		(layers "F.Cu" "B.Cu")
		(remove_unused_layers yes)
		(keep_end_layers yes)
		(zone_layer_connections "In1.Cu" "In3.Cu" "In5.Cu" "In8.Cu" "In10.Cu" "In12.Cu")
		(net 417)
	)
	(via
		(at 201.099 148.701)
		(size 0.35)
		(drill 0.15)
		(layers "F.Cu" "B.Cu")
		(remove_unused_layers yes)
		(keep_end_layers yes)
		(zone_layer_connections "In1.Cu" "In3.Cu" "In5.Cu" "In8.Cu" "In10.Cu" "In12.Cu")
		(net 417)
	)
	(via
		(at 197.299 139.5)
		(size 0.35)
		(drill 0.15)
		(layers "F.Cu" "B.Cu")
		(remove_unused_layers yes)
		(keep_end_layers yes)
		(zone_layer_connections "In1.Cu" "In3.Cu" "In5.Cu" "In8.Cu" "In10.Cu" "In12.Cu")
		(net 417)
	)
	(via
		(at 184.8045 134.1415)
		(size 0.35)
		(drill 0.15)
		(layers "F.Cu" "B.Cu")
		(remove_unused_layers yes)
		(keep_end_layers yes)
		(zone_layer_connections "In1.Cu" "In3.Cu" "In5.Cu" "In8.Cu" "In10.Cu" "In12.Cu")
		(net 417)
	)
	(via
		(at 219.132 122.77)
		(size 0.35)
		(drill 0.15)
		(layers "F.Cu" "B.Cu")
		(remove_unused_layers yes)
		(keep_end_layers yes)
		(zone_layer_connections "In1.Cu" "In3.Cu" "In5.Cu" "In8.Cu" "In10.Cu" "In12.Cu")
		(net 417)
	)
	(via
		(at 221.4255 134.8255)
		(size 0.35)
		(drill 0.15)
		(layers "F.Cu" "B.Cu")
		(remove_unused_layers yes)
		(keep_end_layers yes)
		(zone_layer_connections "In1.Cu" "In3.Cu" "In5.Cu" "In8.Cu" "In10.Cu" "In12.Cu")
		(net 417)
	)
	(via
		(at 197.319 153.711)
		(size 0.35)
		(drill 0.15)
		(layers "F.Cu" "B.Cu")
		(remove_unused_layers yes)
		(keep_end_layers yes)
		(free yes)
		(zone_layer_connections "In1.Cu" "In3.Cu" "In5.Cu" "In8.Cu" "In10.Cu" "In12.Cu")
		(net 417)
	)
	(via
		(at 214.554562 143.634)
		(size 0.35)
		(drill 0.15)
		(layers "F.Cu" "B.Cu")
		(remove_unused_layers yes)
		(keep_end_layers yes)
		(zone_layer_connections "In1.Cu" "In3.Cu" "In5.Cu" "In8.Cu" "In10.Cu" "In12.Cu")
		(net 417)
	)
	(via
		(at 218.6 129.65)
		(size 0.35)
		(drill 0.15)
		(layers "F.Cu" "B.Cu")
		(remove_unused_layers yes)
		(keep_end_layers yes)
		(zone_layer_connections "In1.Cu" "In3.Cu" "In5.Cu" "In8.Cu" "In10.Cu" "In12.Cu")
		(net 417)
	)
	(via
		(at 180.775 137.975)
		(size 0.35)
		(drill 0.15)
		(layers "F.Cu" "B.Cu")
		(remove_unused_layers yes)
		(keep_end_layers yes)
		(zone_layer_connections "In1.Cu" "In3.Cu" "In4.Cu" "In5.Cu" "In8.Cu" "In10.Cu"
			"In11.Cu" "In12.Cu"
		)
		(net 417)
	)
	(via
		(at 198.522 155.260999)
		(size 0.35)
		(drill 0.15)
		(layers "F.Cu" "B.Cu")
		(remove_unused_layers yes)
		(keep_end_layers yes)
		(free yes)
		(zone_layer_connections "In1.Cu" "In3.Cu" "In5.Cu" "In8.Cu" "In10.Cu" "In12.Cu")
		(net 417)
	)
	(via
		(at 201.319534 119.302497)
		(size 0.35)
		(drill 0.15)
		(layers "F.Cu" "B.Cu")
		(remove_unused_layers yes)
		(keep_end_layers yes)
		(free yes)
		(zone_layer_connections "In1.Cu" "In3.Cu" "In5.Cu" "In8.Cu" "In10.Cu" "In12.Cu")
		(net 417)
	)
	(via
		(at 209.35 149.45)
		(size 0.35)
		(drill 0.15)
		(layers "F.Cu" "B.Cu")
		(remove_unused_layers yes)
		(keep_end_layers yes)
		(zone_layer_connections "In1.Cu" "In3.Cu" "In5.Cu" "In8.Cu" "In10.Cu" "In12.Cu")
		(net 417)
	)
	(via
		(at 209.316 148.275)
		(size 0.35)
		(drill 0.15)
		(layers "F.Cu" "B.Cu")
		(remove_unused_layers yes)
		(keep_end_layers yes)
		(zone_layer_connections "In1.Cu" "In3.Cu" "In5.Cu" "In8.Cu" "In10.Cu" "In12.Cu")
		(net 417)
	)
	(via
		(at 225.39 138.77)
		(size 0.35)
		(drill 0.15)
		(layers "F.Cu" "B.Cu")
		(remove_unused_layers yes)
		(keep_end_layers yes)
		(zone_layer_connections "In5.Cu" "In8.Cu" "In10.Cu" "In12.Cu")
		(net 417)
	)
	(via
		(at 198.1 141.101)
		(size 0.35)
		(drill 0.15)
		(layers "F.Cu" "B.Cu")
		(remove_unused_layers yes)
		(keep_end_layers yes)
		(zone_layer_connections "In1.Cu" "In3.Cu" "In5.Cu" "In8.Cu" "In10.Cu" "In12.Cu")
		(net 417)
	)
	(via
		(at 222.464 154.325)
		(size 0.35)
		(drill 0.15)
		(layers "F.Cu" "B.Cu")
		(remove_unused_layers yes)
		(keep_end_layers yes)
		(zone_layer_connections "In1.Cu" "In3.Cu" "In5.Cu" "In8.Cu" "In10.Cu" "In12.Cu")
		(net 417)
	)
	(via
		(at 198.5 133.5)
		(size 0.35)
		(drill 0.15)
		(layers "F.Cu" "B.Cu")
		(remove_unused_layers yes)
		(keep_end_layers yes)
		(zone_layer_connections "In1.Cu" "In3.Cu" "In5.Cu" "In8.Cu" "In10.Cu" "In12.Cu")
		(net 417)
	)
	(via
		(at 203.699 146.101)
		(size 0.35)
		(drill 0.15)
		(layers "F.Cu" "B.Cu")
		(remove_unused_layers yes)
		(keep_end_layers yes)
		(zone_layer_connections "In1.Cu" "In3.Cu" "In5.Cu" "In8.Cu" "In10.Cu" "In12.Cu")
		(net 417)
	)
	(via
		(at 222.204331 144.941253)
		(size 0.35)
		(drill 0.15)
		(layers "F.Cu" "B.Cu")
		(remove_unused_layers yes)
		(keep_end_layers yes)
		(zone_layer_connections "In1.Cu" "In3.Cu" "In5.Cu" "In8.Cu" "In10.Cu" "In12.Cu")
		(net 417)
	)
	(via
		(at 193.718542 152.330047)
		(size 0.35)
		(drill 0.15)
		(layers "F.Cu" "B.Cu")
		(remove_unused_layers yes)
		(keep_end_layers yes)
		(free yes)
		(zone_layer_connections "In1.Cu" "In3.Cu" "In5.Cu" "In8.Cu" "In10.Cu" "In12.Cu")
		(net 417)
	)
	(via
		(at 211.498 148.055)
		(size 0.35)
		(drill 0.15)
		(layers "F.Cu" "B.Cu")
		(remove_unused_layers yes)
		(keep_end_layers yes)
		(zone_layer_connections "In1.Cu" "In3.Cu" "In5.Cu" "In8.Cu" "In10.Cu" "In12.Cu")
		(net 417)
	)
	(via
		(at 194.099 137.901)
		(size 0.35)
		(drill 0.15)
		(layers "F.Cu" "B.Cu")
		(remove_unused_layers yes)
		(keep_end_layers yes)
		(zone_layer_connections "In1.Cu" "In3.Cu" "In5.Cu" "In8.Cu" "In10.Cu" "In12.Cu")
		(net 417)
	)
	(via
		(at 202.1 138.7)
		(size 0.35)
		(drill 0.15)
		(layers "F.Cu" "B.Cu")
		(remove_unused_layers yes)
		(keep_end_layers yes)
		(zone_layer_connections "In1.Cu" "In3.Cu" "In5.Cu" "In8.Cu" "In10.Cu" "In12.Cu")
		(net 417)
	)
	(via
		(at 180.8055 136.7415)
		(size 0.35)
		(drill 0.15)
		(layers "F.Cu" "B.Cu")
		(remove_unused_layers yes)
		(keep_end_layers yes)
		(zone_layer_connections "In1.Cu" "In3.Cu" "In5.Cu" "In8.Cu" "In10.Cu" "In12.Cu")
		(net 417)
	)
	(via
		(at 189.25 119.5)
		(size 0.35)
		(drill 0.15)
		(layers "F.Cu" "B.Cu")
		(remove_unused_layers yes)
		(keep_end_layers yes)
		(zone_layer_connections "In1.Cu" "In3.Cu" "In5.Cu" "In8.Cu" "In10.Cu" "In12.Cu")
		(net 417)
	)
	(via
		(at 216.560006 144.793047)
		(size 0.35)
		(drill 0.15)
		(layers "F.Cu" "B.Cu")
		(remove_unused_layers yes)
		(keep_end_layers yes)
		(zone_layer_connections "In1.Cu" "In3.Cu" "In5.Cu" "In8.Cu" "In10.Cu" "In12.Cu")
		(net 417)
	)
	(via
		(at 206.922 116.491063)
		(size 0.35)
		(drill 0.15)
		(layers "F.Cu" "B.Cu")
		(remove_unused_layers yes)
		(keep_end_layers yes)
		(zone_layer_connections "In1.Cu" "In3.Cu" "In5.Cu" "In8.Cu" "In10.Cu" "In12.Cu")
		(net 417)
	)
	(via
		(at 181.410401 149.629531)
		(size 0.35)
		(drill 0.15)
		(layers "F.Cu" "B.Cu")
		(remove_unused_layers yes)
		(keep_end_layers yes)
		(zone_layer_connections "In1.Cu" "In3.Cu" "In4.Cu" "In5.Cu" "In8.Cu" "In10.Cu"
			"In12.Cu"
		)
		(net 417)
	)
	(via
		(at 197.725 135.075)
		(size 0.35)
		(drill 0.15)
		(layers "F.Cu" "B.Cu")
		(remove_unused_layers yes)
		(keep_end_layers yes)
		(zone_layer_connections "In1.Cu" "In3.Cu" "In5.Cu" "In8.Cu" "In10.Cu" "In12.Cu")
		(net 417)
	)
	(via
		(at 202.1 139.5)
		(size 0.35)
		(drill 0.15)
		(layers "F.Cu" "B.Cu")
		(remove_unused_layers yes)
		(keep_end_layers yes)
		(zone_layer_connections "In1.Cu" "In3.Cu" "In5.Cu" "In8.Cu" "In10.Cu" "In12.Cu")
		(net 417)
	)
	(via
		(at 198.899 139.5)
		(size 0.35)
		(drill 0.15)
		(layers "F.Cu" "B.Cu")
		(remove_unused_layers yes)
		(keep_end_layers yes)
		(zone_layer_connections "In1.Cu" "In3.Cu" "In5.Cu" "In8.Cu" "In10.Cu" "In12.Cu")
		(net 417)
	)
	(via
		(at 202.525625 116.55)
		(size 0.35)
		(drill 0.15)
		(layers "F.Cu" "B.Cu")
		(remove_unused_layers yes)
		(keep_end_layers yes)
		(zone_layer_connections "In1.Cu" "In3.Cu" "In5.Cu" "In8.Cu" "In10.Cu" "In12.Cu")
		(net 417)
	)
	(via
		(at 228.02 135.59)
		(size 0.35)
		(drill 0.15)
		(layers "F.Cu" "B.Cu")
		(remove_unused_layers yes)
		(keep_end_layers yes)
		(zone_layer_connections "In5.Cu" "In8.Cu" "In10.Cu" "In12.Cu")
		(net 417)
	)
	(via
		(at 191.7 131.55)
		(size 0.35)
		(drill 0.15)
		(layers "F.Cu" "B.Cu")
		(remove_unused_layers yes)
		(keep_end_layers yes)
		(zone_layer_connections "In1.Cu" "In3.Cu" "In5.Cu" "In8.Cu" "In10.Cu" "In12.Cu")
		(net 417)
	)
	(via
		(at 216.35 122.45)
		(size 0.35)
		(drill 0.15)
		(layers "F.Cu" "B.Cu")
		(remove_unused_layers yes)
		(keep_end_layers yes)
		(zone_layer_connections "In1.Cu" "In3.Cu" "In5.Cu" "In8.Cu" "In10.Cu" "In12.Cu")
		(net 417)
	)
	(via
		(at 184.8045 132.1925)
		(size 0.35)
		(drill 0.15)
		(layers "F.Cu" "B.Cu")
		(remove_unused_layers yes)
		(keep_end_layers yes)
		(zone_layer_connections "In1.Cu" "In3.Cu" "In5.Cu" "In8.Cu" "In10.Cu" "In12.Cu")
		(net 417)
	)
	(via
		(at 201.3 136.301)
		(size 0.35)
		(drill 0.15)
		(layers "F.Cu" "B.Cu")
		(remove_unused_layers yes)
		(keep_end_layers yes)
		(zone_layer_connections "In1.Cu" "In3.Cu" "In5.Cu" "In8.Cu" "In10.Cu" "In12.Cu")
		(net 417)
	)
	(via
		(at 228.27 141.83)
		(size 0.35)
		(drill 0.15)
		(layers "F.Cu" "B.Cu")
		(remove_unused_layers yes)
		(keep_end_layers yes)
		(zone_layer_connections "In3.Cu" "In5.Cu" "In8.Cu" "In10.Cu" "In12.Cu")
		(net 417)
	)
	(via
		(at 209.322 116.491063)
		(size 0.35)
		(drill 0.15)
		(layers "F.Cu" "B.Cu")
		(remove_unused_layers yes)
		(keep_end_layers yes)
		(zone_layer_connections "In1.Cu" "In3.Cu" "In5.Cu" "In8.Cu" "In10.Cu" "In12.Cu")
		(net 417)
	)
	(via
		(at 180.8055 135.4415)
		(size 0.35)
		(drill 0.15)
		(layers "F.Cu" "B.Cu")
		(remove_unused_layers yes)
		(keep_end_layers yes)
		(zone_layer_connections "In1.Cu" "In3.Cu" "In5.Cu" "In8.Cu" "In10.Cu" "In12.Cu")
		(net 417)
	)
	(via
		(at 178.475 137.825)
		(size 0.35)
		(drill 0.15)
		(layers "F.Cu" "B.Cu")
		(remove_unused_layers yes)
		(keep_end_layers yes)
		(zone_layer_connections "In1.Cu" "In3.Cu" "In4.Cu" "In5.Cu" "In8.Cu" "In10.Cu"
			"In11.Cu" "In12.Cu"
		)
		(net 417)
	)
	(via
		(at 191.323458 152.330047)
		(size 0.35)
		(drill 0.15)
		(layers "F.Cu" "B.Cu")
		(remove_unused_layers yes)
		(keep_end_layers yes)
		(free yes)
		(zone_layer_connections "In1.Cu" "In3.Cu" "In5.Cu" "In8.Cu" "In10.Cu" "In12.Cu")
		(net 417)
	)
	(via
		(at 189.55 145.35)
		(size 0.35)
		(drill 0.15)
		(layers "F.Cu" "B.Cu")
		(remove_unused_layers yes)
		(keep_end_layers yes)
		(free yes)
		(zone_layer_connections "In1.Cu" "In3.Cu" "In4.Cu" "In5.Cu" "In8.Cu" "In10.Cu"
			"In12.Cu"
		)
		(net 417)
	)
	(via
		(at 185 141.4515)
		(size 0.35)
		(drill 0.15)
		(layers "F.Cu" "B.Cu")
		(remove_unused_layers yes)
		(keep_end_layers yes)
		(zone_layer_connections "In1.Cu" "In3.Cu" "In4.Cu" "In5.Cu" "In8.Cu" "In10.Cu"
			"In11.Cu" "In12.Cu"
		)
		(net 417)
	)
	(via
		(at 196.5 141.101)
		(size 0.35)
		(drill 0.15)
		(layers "F.Cu" "B.Cu")
		(remove_unused_layers yes)
		(keep_end_layers yes)
		(zone_layer_connections "In1.Cu" "In3.Cu" "In5.Cu" "In8.Cu" "In10.Cu" "In12.Cu")
		(net 417)
	)
	(via
		(at 175.182647 124.807594)
		(size 0.35)
		(drill 0.15)
		(layers "F.Cu" "B.Cu")
		(remove_unused_layers yes)
		(keep_end_layers yes)
		(zone_layer_connections "In1.Cu" "In3.Cu" "In5.Cu" "In8.Cu" "In10.Cu" "In12.Cu")
		(net 417)
	)
	(via
		(at 195.32 116.51)
		(size 0.35)
		(drill 0.15)
		(layers "F.Cu" "B.Cu")
		(remove_unused_layers yes)
		(keep_end_layers yes)
		(zone_layer_connections "In1.Cu" "In3.Cu" "In5.Cu" "In8.Cu" "In10.Cu" "In12.Cu")
		(net 417)
	)
	(via
		(at 213.93 153.73)
		(size 0.35)
		(drill 0.15)
		(layers "F.Cu" "B.Cu")
		(remove_unused_layers yes)
		(keep_end_layers yes)
		(free yes)
		(zone_layer_connections "In1.Cu" "In3.Cu" "In5.Cu" "In8.Cu" "In10.Cu" "In12.Cu")
		(net 417)
	)
	(via
		(at 175.25 141.9375)
		(size 0.35)
		(drill 0.15)
		(layers "F.Cu" "B.Cu")
		(remove_unused_layers yes)
		(keep_end_layers yes)
		(zone_layer_connections "In1.Cu" "In3.Cu" "In4.Cu" "In5.Cu" "In8.Cu" "In10.Cu"
			"In11.Cu" "In12.Cu"
		)
		(net 417)
	)
	(via
		(at 194.099 138.7)
		(size 0.35)
		(drill 0.15)
		(layers "F.Cu" "B.Cu")
		(remove_unused_layers yes)
		(keep_end_layers yes)
		(zone_layer_connections "In1.Cu" "In3.Cu" "In5.Cu" "In8.Cu" "In10.Cu" "In12.Cu")
		(net 417)
	)
	(via
		(at 211.05 141.300001)
		(size 0.35)
		(drill 0.15)
		(layers "F.Cu" "B.Cu")
		(remove_unused_layers yes)
		(keep_end_layers yes)
		(free yes)
		(zone_layer_connections "In1.Cu" "In3.Cu" "In5.Cu" "In8.Cu" "In10.Cu" "In12.Cu")
		(net 417)
	)
	(via
		(at 200.919 153.711)
		(size 0.35)
		(drill 0.15)
		(layers "F.Cu" "B.Cu")
		(remove_unused_layers yes)
		(keep_end_layers yes)
		(free yes)
		(zone_layer_connections "In1.Cu" "In3.Cu" "In5.Cu" "In8.Cu" "In10.Cu" "In12.Cu")
		(net 417)
	)
	(via
		(at 197.299 124.3)
		(size 0.35)
		(drill 0.15)
		(layers "F.Cu" "B.Cu")
		(remove_unused_layers yes)
		(keep_end_layers yes)
		(zone_layer_connections "In1.Cu" "In3.Cu" "In5.Cu" "In8.Cu" "In10.Cu" "In12.Cu")
		(net 417)
	)
	(via
		(at 194.922 155.260999)
		(size 0.35)
		(drill 0.15)
		(layers "F.Cu" "B.Cu")
		(remove_unused_layers yes)
		(keep_end_layers yes)
		(free yes)
		(zone_layer_connections "In1.Cu" "In3.Cu" "In5.Cu" "In8.Cu" "In10.Cu" "In12.Cu")
		(net 417)
	)
	(via
		(at 194.15 130.7)
		(size 0.35)
		(drill 0.15)
		(layers "F.Cu" "B.Cu")
		(remove_unused_layers yes)
		(keep_end_layers yes)
		(zone_layer_connections "In1.Cu" "In3.Cu" "In5.Cu" "In8.Cu" "In10.Cu" "In12.Cu")
		(net 417)
	)
	(via
		(at 192.529439 152.351024)
		(size 0.35)
		(drill 0.15)
		(layers "F.Cu" "B.Cu")
		(remove_unused_layers yes)
		(keep_end_layers yes)
		(free yes)
		(zone_layer_connections "In1.Cu" "In3.Cu" "In5.Cu" "In8.Cu" "In10.Cu" "In12.Cu")
		(net 417)
	)
	(via
		(at 204.499 129.901)
		(size 0.35)
		(drill 0.15)
		(layers "F.Cu" "B.Cu")
		(remove_unused_layers yes)
		(keep_end_layers yes)
		(zone_layer_connections "In1.Cu" "In3.Cu" "In5.Cu" "In8.Cu" "In10.Cu" "In12.Cu")
		(net 417)
	)
	(via
		(at 179.2035 126.9905)
		(size 0.35)
		(drill 0.15)
		(layers "F.Cu" "B.Cu")
		(remove_unused_layers yes)
		(keep_end_layers yes)
		(zone_layer_connections "In1.Cu" "In3.Cu" "In5.Cu" "In8.Cu" "In10.Cu" "In12.Cu")
		(net 417)
	)
	(via
		(at 209.8 154.925)
		(size 0.35)
		(drill 0.15)
		(layers "F.Cu" "B.Cu")
		(remove_unused_layers yes)
		(keep_end_layers yes)
		(zone_layer_connections "In1.Cu" "In3.Cu" "In5.Cu" "In8.Cu" "In10.Cu" "In12.Cu")
		(net 417)
	)
	(via
		(at 199.3 133.5)
		(size 0.35)
		(drill 0.15)
		(layers "F.Cu" "B.Cu")
		(remove_unused_layers yes)
		(keep_end_layers yes)
		(zone_layer_connections "In1.Cu" "In3.Cu" "In5.Cu" "In8.Cu" "In10.Cu" "In12.Cu")
		(net 417)
	)
	(via
		(at 175.912753 124.317247)
		(size 0.35)
		(drill 0.15)
		(layers "F.Cu" "B.Cu")
		(remove_unused_layers yes)
		(keep_end_layers yes)
		(zone_layer_connections "In1.Cu" "In3.Cu" "In5.Cu" "In8.Cu" "In10.Cu" "In12.Cu")
		(net 417)
	)
	(via
		(at 220.927091 143.117564)
		(size 0.35)
		(drill 0.15)
		(layers "F.Cu" "B.Cu")
		(remove_unused_layers yes)
		(keep_end_layers yes)
		(zone_layer_connections "In1.Cu" "In3.Cu" "In5.Cu" "In8.Cu" "In10.Cu" "In12.Cu")
		(net 417)
	)
	(via
		(at 180.8055 132.1925)
		(size 0.35)
		(drill 0.15)
		(layers "F.Cu" "B.Cu")
		(remove_unused_layers yes)
		(keep_end_layers yes)
		(zone_layer_connections "In1.Cu" "In3.Cu" "In5.Cu" "In8.Cu" "In10.Cu" "In12.Cu")
		(net 417)
	)
	(via
		(at 224.33 148.33)
		(size 0.35)
		(drill 0.15)
		(layers "F.Cu" "B.Cu")
		(remove_unused_layers yes)
		(keep_end_layers yes)
		(zone_layer_connections "In1.Cu" "In3.Cu" "In5.Cu" "In8.Cu" "In10.Cu" "In12.Cu")
		(net 417)
	)
	(via
		(at 175.2035 130.8915)
		(size 0.35)
		(drill 0.15)
		(layers "F.Cu" "B.Cu")
		(remove_unused_layers yes)
		(keep_end_layers yes)
		(zone_layer_connections "In1.Cu" "In3.Cu" "In5.Cu" "In8.Cu" "In10.Cu" "In12.Cu")
		(net 417)
	)
	(via
		(at 190.124458 152.329047)
		(size 0.35)
		(drill 0.15)
		(layers "F.Cu" "B.Cu")
		(remove_unused_layers yes)
		(keep_end_layers yes)
		(free yes)
		(zone_layer_connections "In1.Cu" "In3.Cu" "In5.Cu" "In8.Cu" "In10.Cu" "In12.Cu")
		(net 417)
	)
	(via
		(at 215.57256 142.6)
		(size 0.35)
		(drill 0.15)
		(layers "F.Cu" "B.Cu")
		(remove_unused_layers yes)
		(keep_end_layers yes)
		(zone_layer_connections "In1.Cu" "In3.Cu" "In5.Cu" "In8.Cu" "In10.Cu" "In12.Cu")
		(net 417)
	)
	(via
		(at 214.91 148.38)
		(size 0.35)
		(drill 0.15)
		(layers "F.Cu" "B.Cu")
		(remove_unused_layers yes)
		(keep_end_layers yes)
		(zone_layer_connections "In1.Cu" "In3.Cu" "In5.Cu" "In8.Cu" "In10.Cu" "In12.Cu")
		(net 417)
	)
	(via
		(at 208.124226 152.020641)
		(size 0.35)
		(drill 0.15)
		(layers "F.Cu" "B.Cu")
		(remove_unused_layers yes)
		(keep_end_layers yes)
		(zone_layer_connections "In1.Cu" "In3.Cu" "In5.Cu" "In8.Cu" "In10.Cu" "In12.Cu")
		(net 417)
	)
	(via
		(at 221.15 138.8)
		(size 0.35)
		(drill 0.15)
		(layers "F.Cu" "B.Cu")
		(remove_unused_layers yes)
		(keep_end_layers yes)
		(zone_layer_connections "In1.Cu" "In3.Cu" "In5.Cu" "In8.Cu" "In10.Cu" "In12.Cu")
		(net 417)
	)
	(via
		(at 175.75 141.9375)
		(size 0.35)
		(drill 0.15)
		(layers "F.Cu" "B.Cu")
		(remove_unused_layers yes)
		(keep_end_layers yes)
		(zone_layer_connections "In1.Cu" "In3.Cu" "In4.Cu" "In5.Cu" "In8.Cu" "In10.Cu"
			"In11.Cu" "In12.Cu"
		)
		(net 417)
	)
	(via
		(at 214.965 143.634)
		(size 0.35)
		(drill 0.15)
		(layers "F.Cu" "B.Cu")
		(remove_unused_layers yes)
		(keep_end_layers yes)
		(zone_layer_connections "In1.Cu" "In3.Cu" "In5.Cu" "In8.Cu" "In10.Cu" "In12.Cu")
		(net 417)
	)
	(via
		(at 175.26 128.35)
		(size 0.35)
		(drill 0.15)
		(layers "F.Cu" "B.Cu")
		(remove_unused_layers yes)
		(keep_end_layers yes)
		(zone_layer_connections "In1.Cu" "In3.Cu" "In5.Cu" "In8.Cu" "In10.Cu" "In12.Cu")
		(net 417)
	)
	(via
		(at 209.9 141.3)
		(size 0.35)
		(drill 0.15)
		(layers "F.Cu" "B.Cu")
		(remove_unused_layers yes)
		(keep_end_layers yes)
		(free yes)
		(zone_layer_connections "In1.Cu" "In3.Cu" "In5.Cu" "In8.Cu" "In10.Cu" "In12.Cu")
		(net 417)
	)
	(via
		(at 228.43 138.72)
		(size 0.35)
		(drill 0.15)
		(layers "F.Cu" "B.Cu")
		(remove_unused_layers yes)
		(keep_end_layers yes)
		(zone_layer_connections "In5.Cu" "In8.Cu" "In10.Cu" "In12.Cu")
		(net 417)
	)
	(via
		(at 175.25 137.084)
		(size 0.35)
		(drill 0.15)
		(layers "F.Cu" "B.Cu")
		(remove_unused_layers yes)
		(keep_end_layers yes)
		(zone_layer_connections "In1.Cu" "In3.Cu" "In5.Cu" "In8.Cu" "In10.Cu" "In11.Cu"
			"In12.Cu"
		)
		(net 417)
	)
	(via
		(at 210.505048 141.302493)
		(size 0.35)
		(drill 0.15)
		(layers "F.Cu" "B.Cu")
		(remove_unused_layers yes)
		(keep_end_layers yes)
		(free yes)
		(zone_layer_connections "In1.Cu" "In3.Cu" "In5.Cu" "In8.Cu" "In10.Cu" "In12.Cu")
		(net 417)
	)
	(via
		(at 220.84 146.07)
		(size 0.35)
		(drill 0.15)
		(layers "F.Cu" "B.Cu")
		(remove_unused_layers yes)
		(keep_end_layers yes)
		(free yes)
		(zone_layer_connections "In1.Cu" "In3.Cu" "In5.Cu" "In8.Cu" "In10.Cu" "In12.Cu")
		(net 417)
	)
	(via
		(at 217.41 140.1)
		(size 0.35)
		(drill 0.15)
		(layers "F.Cu" "B.Cu")
		(remove_unused_layers yes)
		(keep_end_layers yes)
		(zone_layer_connections "In1.Cu" "In3.Cu" "In5.Cu" "In8.Cu" "In10.Cu" "In12.Cu")
		(net 417)
	)
	(via
		(at 221.204331 144.941253)
		(size 0.35)
		(drill 0.15)
		(layers "F.Cu" "B.Cu")
		(remove_unused_layers yes)
		(keep_end_layers yes)
		(zone_layer_connections "In1.Cu" "In3.Cu" "In5.Cu" "In8.Cu" "In10.Cu" "In12.Cu")
		(net 417)
	)
	(via
		(at 196.0995 137.5005)
		(size 0.35)
		(drill 0.15)
		(layers "F.Cu" "B.Cu")
		(remove_unused_layers yes)
		(keep_end_layers yes)
		(zone_layer_connections "In1.Cu" "In3.Cu" "In5.Cu" "In8.Cu" "In10.Cu" "In12.Cu")
		(net 417)
	)
	(via
		(at 179.2035 135.4415)
		(size 0.35)
		(drill 0.15)
		(layers "F.Cu" "B.Cu")
		(remove_unused_layers yes)
		(keep_end_layers yes)
		(zone_layer_connections "In1.Cu" "In3.Cu" "In5.Cu" "In8.Cu" "In10.Cu" "In12.Cu")
		(net 417)
	)
	(via
		(at 190.45 145.95)
		(size 0.35)
		(drill 0.15)
		(layers "F.Cu" "B.Cu")
		(remove_unused_layers yes)
		(keep_end_layers yes)
		(free yes)
		(zone_layer_connections "In1.Cu" "In3.Cu" "In4.Cu" "In5.Cu" "In8.Cu" "In10.Cu"
			"In12.Cu"
		)
		(net 417)
	)
	(via
		(at 180.202763 147.663922)
		(size 0.35)
		(drill 0.15)
		(layers "F.Cu" "B.Cu")
		(remove_unused_layers yes)
		(keep_end_layers yes)
		(zone_layer_connections "In1.Cu" "In3.Cu" "In4.Cu" "In5.Cu" "In8.Cu" "In10.Cu"
			"In12.Cu"
		)
		(net 417)
	)
	(via
		(at 183.8 151.975)
		(size 0.35)
		(drill 0.15)
		(layers "F.Cu" "B.Cu")
		(remove_unused_layers yes)
		(keep_end_layers yes)
		(zone_layer_connections "In1.Cu" "In3.Cu" "In4.Cu" "In5.Cu" "In8.Cu" "In10.Cu"
			"In12.Cu"
		)
		(net 417)
	)
	(via
		(at 228.9 137.871666)
		(size 0.35)
		(drill 0.15)
		(layers "F.Cu" "B.Cu")
		(remove_unused_layers yes)
		(keep_end_layers yes)
		(zone_layer_connections "In5.Cu" "In8.Cu" "In10.Cu" "In12.Cu")
		(net 417)
	)
	(via
		(at 213.76 148.11)
		(size 0.35)
		(drill 0.15)
		(layers "F.Cu" "B.Cu")
		(remove_unused_layers yes)
		(keep_end_layers yes)
		(zone_layer_connections "In1.Cu" "In3.Cu" "In5.Cu" "In8.Cu" "In10.Cu" "In12.Cu")
		(net 417)
	)
	(via
		(at 189.552493 144.744952)
		(size 0.35)
		(drill 0.15)
		(layers "F.Cu" "B.Cu")
		(remove_unused_layers yes)
		(keep_end_layers yes)
		(free yes)
		(zone_layer_connections "In1.Cu" "In3.Cu" "In4.Cu" "In5.Cu" "In8.Cu" "In10.Cu"
			"In12.Cu"
		)
		(net 417)
	)
	(via
		(at 175.29 122.34)
		(size 0.35)
		(drill 0.15)
		(layers "F.Cu" "B.Cu")
		(remove_unused_layers yes)
		(keep_end_layers yes)
		(zone_layer_connections "In1.Cu" "In3.Cu" "In5.Cu" "In8.Cu" "In10.Cu" "In12.Cu")
		(net 417)
	)
	(via
		(at 196.865 137.535)
		(size 0.35)
		(drill 0.15)
		(layers "F.Cu" "B.Cu")
		(remove_unused_layers yes)
		(keep_end_layers yes)
		(zone_layer_connections "In1.Cu" "In3.Cu" "In5.Cu" "In8.Cu" "In10.Cu" "In12.Cu")
		(net 417)
	)
	(via
		(at 221.29 123.6)
		(size 0.35)
		(drill 0.15)
		(layers "F.Cu" "B.Cu")
		(remove_unused_layers yes)
		(keep_end_layers yes)
		(zone_layer_connections "In1.Cu" "In3.Cu" "In5.Cu" "In8.Cu" "In10.Cu" "In12.Cu")
		(net 417)
	)
	(via
		(at 189.075 151.175)
		(size 0.35)
		(drill 0.15)
		(layers "F.Cu" "B.Cu")
		(remove_unused_layers yes)
		(keep_end_layers yes)
		(zone_layer_connections "In1.Cu" "In3.Cu" "In4.Cu" "In5.Cu" "In8.Cu" "In10.Cu"
			"In12.Cu"
		)
		(net 417)
	)
	(via
		(at 194.908 119.501)
		(size 0.35)
		(drill 0.15)
		(layers "F.Cu" "B.Cu")
		(remove_unused_layers yes)
		(keep_end_layers yes)
		(zone_layer_connections "In1.Cu" "In3.Cu" "In5.Cu" "In8.Cu" "In10.Cu" "In12.Cu")
		(net 417)
	)
	(via
		(at 190.447508 145.405048)
		(size 0.35)
		(drill 0.15)
		(layers "F.Cu" "B.Cu")
		(remove_unused_layers yes)
		(keep_end_layers yes)
		(free yes)
		(zone_layer_connections "In1.Cu" "In3.Cu" "In4.Cu" "In5.Cu" "In8.Cu" "In10.Cu"
			"In12.Cu"
		)
		(net 417)
	)
	(via
		(at 213.9425 131.447)
		(size 0.35)
		(drill 0.15)
		(layers "F.Cu" "B.Cu")
		(remove_unused_layers yes)
		(keep_end_layers yes)
		(zone_layer_connections "In1.Cu" "In3.Cu" "In5.Cu" "In8.Cu" "In10.Cu" "In12.Cu")
		(net 417)
	)
	(via
		(at 222.31 143.94)
		(size 0.35)
		(drill 0.15)
		(layers "F.Cu" "B.Cu")
		(remove_unused_layers yes)
		(keep_end_layers yes)
		(zone_layer_connections "In1.Cu" "In3.Cu" "In5.Cu" "In8.Cu" "In10.Cu" "In12.Cu")
		(net 417)
	)
	(via
		(at 193.299 140.3)
		(size 0.35)
		(drill 0.15)
		(layers "F.Cu" "B.Cu")
		(remove_unused_layers yes)
		(keep_end_layers yes)
		(zone_layer_connections "In1.Cu" "In3.Cu" "In5.Cu" "In8.Cu" "In10.Cu" "In12.Cu")
		(net 417)
	)
	(via
		(at 205.55 141.7)
		(size 0.35)
		(drill 0.15)
		(layers "F.Cu" "B.Cu")
		(remove_unused_layers yes)
		(keep_end_layers yes)
		(zone_layer_connections "In1.Cu" "In3.Cu" "In5.Cu" "In8.Cu" "In10.Cu" "In12.Cu")
		(net 417)
	)
	(via
		(at 196.122 155.260999)
		(size 0.35)
		(drill 0.15)
		(layers "F.Cu" "B.Cu")
		(remove_unused_layers yes)
		(keep_end_layers yes)
		(free yes)
		(zone_layer_connections "In1.Cu" "In3.Cu" "In5.Cu" "In8.Cu" "In10.Cu" "In12.Cu")
		(net 417)
	)
	(via
		(at 200.499 139.5)
		(size 0.35)
		(drill 0.15)
		(layers "F.Cu" "B.Cu")
		(remove_unused_layers yes)
		(keep_end_layers yes)
		(zone_layer_connections "In1.Cu" "In3.Cu" "In5.Cu" "In8.Cu" "In10.Cu" "In12.Cu")
		(net 417)
	)
	(via
		(at 196.118542 152.330047)
		(size 0.35)
		(drill 0.15)
		(layers "F.Cu" "B.Cu")
		(remove_unused_layers yes)
		(keep_end_layers yes)
		(free yes)
		(zone_layer_connections "In1.Cu" "In3.Cu" "In5.Cu" "In8.Cu" "In10.Cu" "In12.Cu")
		(net 417)
	)
	(via
		(at 206.917 155.260999)
		(size 0.35)
		(drill 0.15)
		(layers "F.Cu" "B.Cu")
		(remove_unused_layers yes)
		(keep_end_layers yes)
		(free yes)
		(zone_layer_connections "In1.Cu" "In3.Cu" "In5.Cu" "In8.Cu" "In10.Cu" "In12.Cu")
		(net 417)
	)
	(via
		(at 179.2035 123.7415)
		(size 0.35)
		(drill 0.15)
		(layers "F.Cu" "B.Cu")
		(remove_unused_layers yes)
		(keep_end_layers yes)
		(zone_layer_connections "In1.Cu" "In3.Cu" "In5.Cu" "In8.Cu" "In10.Cu" "In12.Cu")
		(net 417)
	)
	(via
		(at 184.1 153.9)
		(size 0.35)
		(drill 0.15)
		(layers "F.Cu" "B.Cu")
		(remove_unused_layers yes)
		(keep_end_layers yes)
		(zone_layer_connections "In1.Cu" "In3.Cu" "In4.Cu" "In5.Cu" "In8.Cu" "In10.Cu"
			"In12.Cu"
		)
		(net 417)
	)
	(via
		(at 203.699 147.401)
		(size 0.35)
		(drill 0.15)
		(layers "F.Cu" "B.Cu")
		(remove_unused_layers yes)
		(keep_end_layers yes)
		(zone_layer_connections "In1.Cu" "In3.Cu" "In5.Cu" "In8.Cu" "In10.Cu" "In12.Cu")
		(net 417)
	)
	(via
		(at 180.634404 149.204531)
		(size 0.35)
		(drill 0.15)
		(layers "F.Cu" "B.Cu")
		(remove_unused_layers yes)
		(keep_end_layers yes)
		(zone_layer_connections "In1.Cu" "In3.Cu" "In4.Cu" "In5.Cu" "In8.Cu" "In10.Cu"
			"In12.Cu"
		)
		(net 417)
	)
	(via
		(at 181.634404 149.204531)
		(size 0.35)
		(drill 0.15)
		(layers "F.Cu" "B.Cu")
		(remove_unused_layers yes)
		(keep_end_layers yes)
		(zone_layer_connections "In1.Cu" "In3.Cu" "In4.Cu" "In5.Cu" "In8.Cu" "In10.Cu"
			"In12.Cu"
		)
		(net 417)
	)
	(via
		(at 210.5 142.200001)
		(size 0.35)
		(drill 0.15)
		(layers "F.Cu" "B.Cu")
		(remove_unused_layers yes)
		(keep_end_layers yes)
		(free yes)
		(zone_layer_connections "In1.Cu" "In3.Cu" "In5.Cu" "In8.Cu" "In10.Cu" "In12.Cu")
		(net 417)
	)
	(via
		(at 184.8045 125.0425)
		(size 0.35)
		(drill 0.15)
		(layers "F.Cu" "B.Cu")
		(remove_unused_layers yes)
		(keep_end_layers yes)
		(zone_layer_connections "In1.Cu" "In3.Cu" "In5.Cu" "In8.Cu" "In10.Cu" "In12.Cu")
		(net 417)
	)
	(via
		(at 189.299 132.3)
		(size 0.35)
		(drill 0.15)
		(layers "F.Cu" "B.Cu")
		(remove_unused_layers yes)
		(keep_end_layers yes)
		(zone_layer_connections "In1.Cu" "In3.Cu" "In5.Cu" "In8.Cu" "In10.Cu" "In12.Cu")
		(net 417)
	)
	(via
		(at 193.299 141.101)
		(size 0.35)
		(drill 0.15)
		(layers "F.Cu" "B.Cu")
		(remove_unused_layers yes)
		(keep_end_layers yes)
		(zone_layer_connections "In1.Cu" "In3.Cu" "In5.Cu" "In8.Cu" "In10.Cu" "In12.Cu")
		(net 417)
	)
	(via
		(at 228.22 139.77)
		(size 0.35)
		(drill 0.15)
		(layers "F.Cu" "B.Cu")
		(remove_unused_layers yes)
		(keep_end_layers yes)
		(zone_layer_connections "In3.Cu" "In5.Cu" "In8.Cu" "In10.Cu" "In12.Cu")
		(net 417)
	)
	(via
		(at 192.519 153.711)
		(size 0.35)
		(drill 0.15)
		(layers "F.Cu" "B.Cu")
		(remove_unused_layers yes)
		(keep_end_layers yes)
		(free yes)
		(zone_layer_connections "In1.Cu" "In3.Cu" "In5.Cu" "In8.Cu" "In10.Cu" "In12.Cu")
		(net 417)
	)
	(via
		(at 226.91 135.58)
		(size 0.35)
		(drill 0.15)
		(layers "F.Cu" "B.Cu")
		(remove_unused_layers yes)
		(keep_end_layers yes)
		(zone_layer_connections "In5.Cu" "In8.Cu" "In10.Cu" "In12.Cu")
		(net 417)
	)
	(via
		(at 225.78 139.65)
		(size 0.35)
		(drill 0.15)
		(layers "F.Cu" "B.Cu")
		(remove_unused_layers yes)
		(keep_end_layers yes)
		(zone_layer_connections "In1.Cu" "In3.Cu" "In5.Cu" "In8.Cu" "In10.Cu" "In12.Cu")
		(net 417)
	)
	(via
		(at 196.119 153.711)
		(size 0.35)
		(drill 0.15)
		(layers "F.Cu" "B.Cu")
		(remove_unused_layers yes)
		(keep_end_layers yes)
		(free yes)
		(zone_layer_connections "In1.Cu" "In3.Cu" "In5.Cu" "In8.Cu" "In10.Cu" "In12.Cu")
		(net 417)
	)
	(via
		(at 200.09 135.9)
		(size 0.35)
		(drill 0.15)
		(layers "F.Cu" "B.Cu")
		(remove_unused_layers yes)
		(keep_end_layers yes)
		(zone_layer_connections "In1.Cu" "In3.Cu" "In5.Cu" "In8.Cu" "In10.Cu" "In12.Cu")
		(net 417)
	)
	(via
		(at 221.01 117.66)
		(size 0.35)
		(drill 0.15)
		(layers "F.Cu" "B.Cu")
		(remove_unused_layers yes)
		(keep_end_layers yes)
		(zone_layer_connections "In1.Cu" "In3.Cu" "In5.Cu" "In8.Cu" "In10.Cu" "In12.Cu")
		(net 417)
	)
	(via
		(at 180.634404 148.154531)
		(size 0.35)
		(drill 0.15)
		(layers "F.Cu" "B.Cu")
		(remove_unused_layers yes)
		(keep_end_layers yes)
		(zone_layer_connections "In1.Cu" "In3.Cu" "In4.Cu" "In5.Cu" "In8.Cu" "In10.Cu"
			"In12.Cu"
		)
		(net 417)
	)
	(via
		(at 206.921926 119.688357)
		(size 0.35)
		(drill 0.15)
		(layers "F.Cu" "B.Cu")
		(remove_unused_layers yes)
		(keep_end_layers yes)
		(free yes)
		(zone_layer_connections "In1.Cu" "In3.Cu" "In5.Cu" "In8.Cu" "In10.Cu" "In12.Cu")
		(net 417)
	)
	(via
		(at 190.002492 144.444952)
		(size 0.35)
		(drill 0.15)
		(layers "F.Cu" "B.Cu")
		(remove_unused_layers yes)
		(keep_end_layers yes)
		(zone_layer_connections "In1.Cu" "In3.Cu" "In4.Cu" "In5.Cu" "In8.Cu" "In10.Cu"
			"In12.Cu"
		)
		(net 417)
	)
	(via
		(at 194.85 121.43)
		(size 0.35)
		(drill 0.15)
		(layers "F.Cu" "B.Cu")
		(remove_unused_layers yes)
		(keep_end_layers yes)
		(zone_layer_connections "In1.Cu" "In3.Cu" "In5.Cu" "In8.Cu" "In10.Cu" "In12.Cu")
		(net 417)
	)
	(via
		(at 180.604451 142.288215)
		(size 0.35)
		(drill 0.15)
		(layers "F.Cu" "B.Cu")
		(remove_unused_layers yes)
		(keep_end_layers yes)
		(zone_layer_connections "In1.Cu" "In3.Cu" "In4.Cu" "In5.Cu" "In8.Cu" "In10.Cu"
			"In11.Cu" "In12.Cu"
		)
		(net 417)
	)
	(via
		(at 199.1 119.28)
		(size 0.35)
		(drill 0.15)
		(layers "F.Cu" "B.Cu")
		(remove_unused_layers yes)
		(keep_end_layers yes)
		(zone_layer_connections "In1.Cu" "In3.Cu" "In5.Cu" "In8.Cu" "In10.Cu" "In12.Cu")
		(net 417)
	)
	(via
		(at 190.002492 145.044952)
		(size 0.35)
		(drill 0.15)
		(layers "F.Cu" "B.Cu")
		(remove_unused_layers yes)
		(keep_end_layers yes)
		(zone_layer_connections "In1.Cu" "In3.Cu" "In4.Cu" "In5.Cu" "In8.Cu" "In10.Cu"
			"In12.Cu"
		)
		(net 417)
	)
	(via
		(at 193.299 139.5)
		(size 0.35)
		(drill 0.15)
		(layers "F.Cu" "B.Cu")
		(remove_unused_layers yes)
		(keep_end_layers yes)
		(zone_layer_connections "In1.Cu" "In3.Cu" "In5.Cu" "In8.Cu" "In10.Cu" "In12.Cu")
		(net 417)
	)
	(via
		(at 182.6 141.9375)
		(size 0.35)
		(drill 0.15)
		(layers "F.Cu" "B.Cu")
		(remove_unused_layers yes)
		(keep_end_layers yes)
		(zone_layer_connections "In1.Cu" "In3.Cu" "In4.Cu" "In5.Cu" "In8.Cu" "In10.Cu"
			"In11.Cu" "In12.Cu"
		)
		(net 417)
	)
	(via
		(at 179.2035 132.1925)
		(size 0.35)
		(drill 0.15)
		(layers "F.Cu" "B.Cu")
		(remove_unused_layers yes)
		(keep_end_layers yes)
		(zone_layer_connections "In1.Cu" "In3.Cu" "In5.Cu" "In8.Cu" "In10.Cu" "In12.Cu")
		(net 417)
	)
	(via
		(at 181.6045 124.3925)
		(size 0.35)
		(drill 0.15)
		(layers "F.Cu" "B.Cu")
		(remove_unused_layers yes)
		(keep_end_layers yes)
		(zone_layer_connections "In1.Cu" "In3.Cu" "In5.Cu" "In8.Cu" "In10.Cu" "In12.Cu")
		(net 417)
	)
	(via
		(at 221.595 131.6)
		(size 0.35)
		(drill 0.15)
		(layers "F.Cu" "B.Cu")
		(remove_unused_layers yes)
		(keep_end_layers yes)
		(zone_layer_connections "In1.Cu" "In3.Cu" "In5.Cu" "In8.Cu" "In10.Cu" "In12.Cu")
		(net 417)
	)
	(via
		(at 209.341 147.3)
		(size 0.35)
		(drill 0.15)
		(layers "F.Cu" "B.Cu")
		(remove_unused_layers yes)
		(keep_end_layers yes)
		(zone_layer_connections "In1.Cu" "In3.Cu" "In5.Cu" "In8.Cu" "In10.Cu" "In12.Cu")
		(net 417)
	)
	(via
		(at 195.85 127.47)
		(size 0.35)
		(drill 0.15)
		(layers "F.Cu" "B.Cu")
		(remove_unused_layers yes)
		(keep_end_layers yes)
		(zone_layer_connections "In1.Cu" "In3.Cu" "In5.Cu" "In8.Cu" "In10.Cu" "In12.Cu")
		(net 417)
	)
	(via
		(at 195.61 144.45)
		(size 0.35)
		(drill 0.15)
		(layers "F.Cu" "B.Cu")
		(remove_unused_layers yes)
		(keep_end_layers yes)
		(zone_layer_connections "In1.Cu" "In3.Cu" "In5.Cu" "In8.Cu" "In10.Cu" "In12.Cu")
		(net 417)
	)
	(via
		(at 211.125 145.1)
		(size 0.35)
		(drill 0.15)
		(layers "F.Cu" "B.Cu")
		(remove_unused_layers yes)
		(keep_end_layers yes)
		(zone_layer_connections "In1.Cu" "In3.Cu" "In5.Cu" "In8.Cu" "In10.Cu" "In12.Cu")
		(net 417)
	)
	(via
		(at 193.719 153.711)
		(size 0.35)
		(drill 0.15)
		(layers "F.Cu" "B.Cu")
		(remove_unused_layers yes)
		(keep_end_layers yes)
		(free yes)
		(zone_layer_connections "In1.Cu" "In3.Cu" "In5.Cu" "In8.Cu" "In10.Cu" "In12.Cu")
		(net 417)
	)
	(via
		(at 204.522 155.260999)
		(size 0.35)
		(drill 0.15)
		(layers "F.Cu" "B.Cu")
		(remove_unused_layers yes)
		(keep_end_layers yes)
		(free yes)
		(zone_layer_connections "In1.Cu" "In3.Cu" "In5.Cu" "In8.Cu" "In10.Cu" "In12.Cu")
		(net 417)
	)
	(via
		(at 183.15 128.2915)
		(size 0.35)
		(drill 0.15)
		(layers "F.Cu" "B.Cu")
		(remove_unused_layers yes)
		(keep_end_layers yes)
		(zone_layer_connections "In1.Cu" "In3.Cu" "In5.Cu" "In8.Cu" "In10.Cu" "In12.Cu")
		(net 417)
	)
	(via
		(at 210.55 122.9)
		(size 0.35)
		(drill 0.15)
		(layers "F.Cu" "B.Cu")
		(remove_unused_layers yes)
		(keep_end_layers yes)
		(free yes)
		(zone_layer_connections "In1.Cu" "In3.Cu" "In5.Cu" "In8.Cu" "In10.Cu" "In12.Cu")
		(net 417)
	)
	(via
		(at 182.784404 149.604531)
		(size 0.35)
		(drill 0.15)
		(layers "F.Cu" "B.Cu")
		(remove_unused_layers yes)
		(keep_end_layers yes)
		(zone_layer_connections "In1.Cu" "In3.Cu" "In4.Cu" "In5.Cu" "In8.Cu" "In10.Cu"
			"In12.Cu"
		)
		(net 417)
	)
	(via
		(at 209.655048 141.752492)
		(size 0.35)
		(drill 0.15)
		(layers "F.Cu" "B.Cu")
		(remove_unused_layers yes)
		(keep_end_layers yes)
		(zone_layer_connections "In1.Cu" "In3.Cu" "In5.Cu" "In8.Cu" "In10.Cu" "In12.Cu")
		(net 417)
	)
	(via
		(at 201.3 141.101)
		(size 0.35)
		(drill 0.15)
		(layers "F.Cu" "B.Cu")
		(remove_unused_layers yes)
		(keep_end_layers yes)
		(zone_layer_connections "In1.Cu" "In3.Cu" "In5.Cu" "In8.Cu" "In10.Cu" "In12.Cu")
		(net 417)
	)
	(via
		(at 191.7 147.15)
		(size 0.35)
		(drill 0.15)
		(layers "F.Cu" "B.Cu")
		(remove_unused_layers yes)
		(keep_end_layers yes)
		(zone_layer_connections "In1.Cu" "In3.Cu" "In5.Cu" "In8.Cu" "In10.Cu" "In12.Cu")
		(net 417)
	)
	(via
		(at 194.9 141.101)
		(size 0.35)
		(drill 0.15)
		(layers "F.Cu" "B.Cu")
		(remove_unused_layers yes)
		(keep_end_layers yes)
		(zone_layer_connections "In1.Cu" "In3.Cu" "In5.Cu" "In8.Cu" "In10.Cu" "In12.Cu")
		(net 417)
	)
	(via
		(at 222.696369 147.384499)
		(size 0.35)
		(drill 0.15)
		(layers "F.Cu" "B.Cu")
		(remove_unused_layers yes)
		(keep_end_layers yes)
		(zone_layer_connections "In1.Cu" "In3.Cu" "In5.Cu" "In8.Cu" "In10.Cu" "In12.Cu")
		(net 417)
	)
	(via
		(at 190.450001 144.8)
		(size 0.35)
		(drill 0.15)
		(layers "F.Cu" "B.Cu")
		(remove_unused_layers yes)
		(keep_end_layers yes)
		(free yes)
		(zone_layer_connections "In1.Cu" "In3.Cu" "In4.Cu" "In5.Cu" "In8.Cu" "In10.Cu"
			"In12.Cu"
		)
		(net 417)
	)
	(via
		(at 205.299 132.3)
		(size 0.35)
		(drill 0.15)
		(layers "F.Cu" "B.Cu")
		(remove_unused_layers yes)
		(keep_end_layers yes)
		(zone_layer_connections "In1.Cu" "In3.Cu" "In5.Cu" "In8.Cu" "In10.Cu" "In12.Cu")
		(net 417)
	)
	(via
		(at 177.205 126.666)
		(size 0.35)
		(drill 0.15)
		(layers "F.Cu" "B.Cu")
		(remove_unused_layers yes)
		(keep_end_layers yes)
		(zone_layer_connections "In1.Cu" "In3.Cu" "In5.Cu" "In8.Cu" "In10.Cu" "In12.Cu")
		(net 417)
	)
	(via
		(at 225.2 123.9)
		(size 0.35)
		(drill 0.15)
		(layers "F.Cu" "B.Cu")
		(remove_unused_layers yes)
		(keep_end_layers yes)
		(zone_layer_connections "In1.Cu" "In3.Cu" "In5.Cu" "In8.Cu" "In10.Cu" "In12.Cu")
		(net 417)
	)
	(via
		(at 206.1 124.3)
		(size 0.35)
		(drill 0.15)
		(layers "F.Cu" "B.Cu")
		(remove_unused_layers yes)
		(keep_end_layers yes)
		(zone_layer_connections "In1.Cu" "In3.Cu" "In5.Cu" "In8.Cu" "In10.Cu" "In12.Cu")
		(net 417)
	)
	(via
		(at 197.299 138.7)
		(size 0.35)
		(drill 0.15)
		(layers "F.Cu" "B.Cu")
		(remove_unused_layers yes)
		(keep_end_layers yes)
		(zone_layer_connections "In1.Cu" "In3.Cu" "In5.Cu" "In8.Cu" "In10.Cu" "In12.Cu")
		(net 417)
	)
	(via
		(at 184.218404 153.204531)
		(size 0.35)
		(drill 0.15)
		(layers "F.Cu" "B.Cu")
		(remove_unused_layers yes)
		(keep_end_layers yes)
		(zone_layer_connections "In1.Cu" "In3.Cu" "In4.Cu" "In5.Cu" "In8.Cu" "In10.Cu"
			"In12.Cu"
		)
		(net 417)
	)
	(via
		(at 184.35 116.95)
		(size 0.35)
		(drill 0.15)
		(layers "F.Cu" "B.Cu")
		(remove_unused_layers yes)
		(keep_end_layers yes)
		(zone_layer_connections "In1.Cu" "In3.Cu" "In5.Cu" "In8.Cu" "In10.Cu" "In12.Cu")
		(net 417)
	)
	(via
		(at 203.049 148.051)
		(size 0.35)
		(drill 0.15)
		(layers "F.Cu" "B.Cu")
		(remove_unused_layers yes)
		(keep_end_layers yes)
		(zone_layer_connections "In1.Cu" "In3.Cu" "In5.Cu" "In8.Cu" "In10.Cu" "In12.Cu")
		(net 417)
	)
	(via
		(at 183.6 141.9375)
		(size 0.35)
		(drill 0.15)
		(layers "F.Cu" "B.Cu")
		(remove_unused_layers yes)
		(keep_end_layers yes)
		(zone_layer_connections "In1.Cu" "In3.Cu" "In4.Cu" "In5.Cu" "In8.Cu" "In10.Cu"
			"In11.Cu" "In12.Cu"
		)
		(net 417)
	)
	(via
		(at 198.1 126.701)
		(size 0.35)
		(drill 0.15)
		(layers "F.Cu" "B.Cu")
		(remove_unused_layers yes)
		(keep_end_layers yes)
		(zone_layer_connections "In1.Cu" "In3.Cu" "In5.Cu" "In8.Cu" "In10.Cu" "In12.Cu")
		(net 417)
	)
	(via
		(at 225.806 146.567)
		(size 0.35)
		(drill 0.15)
		(layers "F.Cu" "B.Cu")
		(remove_unused_layers yes)
		(keep_end_layers yes)
		(zone_layer_connections "In1.Cu" "In3.Cu" "In5.Cu" "In8.Cu" "In10.Cu" "In12.Cu")
		(net 417)
	)
	(via
		(at 191.031053 150.262222)
		(size 0.35)
		(drill 0.15)
		(layers "F.Cu" "B.Cu")
		(remove_unused_layers yes)
		(keep_end_layers yes)
		(free yes)
		(zone_layer_connections "In1.Cu" "In3.Cu" "In5.Cu" "In8.Cu" "In10.Cu" "In12.Cu")
		(net 417)
	)
	(via
		(at 210.805048 141.752492)
		(size 0.35)
		(drill 0.15)
		(layers "F.Cu" "B.Cu")
		(remove_unused_layers yes)
		(keep_end_layers yes)
		(zone_layer_connections "In1.Cu" "In3.Cu" "In5.Cu" "In8.Cu" "In10.Cu" "In12.Cu")
		(net 417)
	)
	(via
		(at 218.85 121.8)
		(size 0.35)
		(drill 0.15)
		(layers "F.Cu" "B.Cu")
		(remove_unused_layers yes)
		(keep_end_layers yes)
		(zone_layer_connections "In1.Cu" "In3.Cu" "In5.Cu" "In8.Cu" "In10.Cu" "In12.Cu")
		(net 417)
	)
	(via
		(at 184.975 142.5035)
		(size 0.35)
		(drill 0.15)
		(layers "F.Cu" "B.Cu")
		(remove_unused_layers yes)
		(keep_end_layers yes)
		(zone_layer_connections "In1.Cu" "In3.Cu" "In4.Cu" "In5.Cu" "In8.Cu" "In10.Cu"
			"In11.Cu" "In12.Cu"
		)
		(net 417)
	)
	(via
		(at 208.119926 119.688357)
		(size 0.35)
		(drill 0.15)
		(layers "F.Cu" "B.Cu")
		(remove_unused_layers yes)
		(keep_end_layers yes)
		(free yes)
		(zone_layer_connections "In1.Cu" "In3.Cu" "In5.Cu" "In8.Cu" "In10.Cu" "In12.Cu")
		(net 417)
	)
	(via
		(at 176.8055 136.7415)
		(size 0.35)
		(drill 0.15)
		(layers "F.Cu" "B.Cu")
		(remove_unused_layers yes)
		(keep_end_layers yes)
		(zone_layer_connections "In1.Cu" "In3.Cu" "In5.Cu" "In8.Cu" "In10.Cu" "In12.Cu")
		(net 417)
	)
	(via
		(at 195.7 130.701)
		(size 0.35)
		(drill 0.15)
		(layers "F.Cu" "B.Cu")
		(remove_unused_layers yes)
		(keep_end_layers yes)
		(zone_layer_connections "In1.Cu" "In3.Cu" "In5.Cu" "In8.Cu" "In10.Cu" "In12.Cu")
		(net 417)
	)
	(via
		(at 222.826888 142.946755)
		(size 0.35)
		(drill 0.15)
		(layers "F.Cu" "B.Cu")
		(remove_unused_layers yes)
		(keep_end_layers yes)
		(zone_layer_connections "In1.Cu" "In3.Cu" "In5.Cu" "In8.Cu" "In10.Cu" "In12.Cu")
		(net 417)
	)
	(via
		(at 224.1 139.09)
		(size 0.35)
		(drill 0.15)
		(layers "F.Cu" "B.Cu")
		(remove_unused_layers yes)
		(keep_end_layers yes)
		(zone_layer_connections "In1.Cu" "In3.Cu" "In5.Cu" "In8.Cu" "In10.Cu" "In12.Cu")
		(net 417)
	)
	(via
		(at 209.894952 142.197508)
		(size 0.35)
		(drill 0.15)
		(layers "F.Cu" "B.Cu")
		(remove_unused_layers yes)
		(keep_end_layers yes)
		(free yes)
		(zone_layer_connections "In1.Cu" "In3.Cu" "In5.Cu" "In8.Cu" "In10.Cu" "In12.Cu")
		(net 417)
	)
	(via
		(at 184.6 141.9375)
		(size 0.35)
		(drill 0.15)
		(layers "F.Cu" "B.Cu")
		(remove_unused_layers yes)
		(keep_end_layers yes)
		(zone_layer_connections "In1.Cu" "In3.Cu" "In4.Cu" "In5.Cu" "In8.Cu" "In10.Cu"
			"In11.Cu" "In12.Cu"
		)
		(net 417)
	)
	(via
		(at 178.317524 144.162502)
		(size 0.35)
		(drill 0.15)
		(layers "F.Cu" "B.Cu")
		(remove_unused_layers yes)
		(keep_end_layers yes)
		(zone_layer_connections "In1.Cu" "In3.Cu" "In4.Cu" "In5.Cu" "In8.Cu" "In10.Cu"
			"In11.Cu" "In12.Cu"
		)
		(net 417)
	)
	(via
		(at 214.980439 153.749976)
		(size 0.35)
		(drill 0.15)
		(layers "F.Cu" "B.Cu")
		(remove_unused_layers yes)
		(keep_end_layers yes)
		(free yes)
		(zone_layer_connections "In1.Cu" "In3.Cu" "In5.Cu" "In8.Cu" "In10.Cu" "In12.Cu")
		(net 417)
	)
	(via
		(at 183.1295 130.8915)
		(size 0.35)
		(drill 0.15)
		(layers "F.Cu" "B.Cu")
		(remove_unused_layers yes)
		(keep_end_layers yes)
		(zone_layer_connections "In1.Cu" "In3.Cu" "In5.Cu" "In8.Cu" "In10.Cu" "In12.Cu")
		(net 417)
	)
	(via
		(at 213.44 154.48)
		(size 0.35)
		(drill 0.15)
		(layers "F.Cu" "B.Cu")
		(remove_unused_layers yes)
		(keep_end_layers yes)
		(free yes)
		(zone_layer_connections "In1.Cu" "In3.Cu" "In5.Cu" "In8.Cu" "In10.Cu" "In12.Cu")
		(net 417)
	)
	(via
		(at 202.9 133.101)
		(size 0.35)
		(drill 0.15)
		(layers "F.Cu" "B.Cu")
		(remove_unused_layers yes)
		(keep_end_layers yes)
		(zone_layer_connections "In1.Cu" "In3.Cu" "In5.Cu" "In8.Cu" "In10.Cu" "In12.Cu")
		(net 417)
	)
	(via
		(at 175.475 141.4515)
		(size 0.35)
		(drill 0.15)
		(layers "F.Cu" "B.Cu")
		(remove_unused_layers yes)
		(keep_end_layers yes)
		(zone_layer_connections "In1.Cu" "In3.Cu" "In4.Cu" "In5.Cu" "In8.Cu" "In10.Cu"
			"In11.Cu" "In12.Cu"
		)
		(net 417)
	)
	(via
		(at 181.6045 130.2415)
		(size 0.35)
		(drill 0.15)
		(layers "F.Cu" "B.Cu")
		(remove_unused_layers yes)
		(keep_end_layers yes)
		(zone_layer_connections "In1.Cu" "In3.Cu" "In5.Cu" "In8.Cu" "In10.Cu" "In12.Cu")
		(net 417)
	)
	(via
		(at 189.299 141.101)
		(size 0.35)
		(drill 0.15)
		(layers "F.Cu" "B.Cu")
		(remove_unused_layers yes)
		(keep_end_layers yes)
		(zone_layer_connections "In1.Cu" "In3.Cu" "In5.Cu" "In8.Cu" "In10.Cu" "In12.Cu")
		(net 417)
	)
	(via
		(at 180.1 141.4875)
		(size 0.35)
		(drill 0.15)
		(layers "F.Cu" "B.Cu")
		(remove_unused_layers yes)
		(keep_end_layers yes)
		(zone_layer_connections "In1.Cu" "In3.Cu" "In4.Cu" "In5.Cu" "In8.Cu" "In10.Cu"
			"In11.Cu" "In12.Cu"
		)
		(net 417)
	)
	(via
		(at 193.299 128.3)
		(size 0.35)
		(drill 0.15)
		(layers "F.Cu" "B.Cu")
		(remove_unused_layers yes)
		(keep_end_layers yes)
		(zone_layer_connections "In1.Cu" "In3.Cu" "In5.Cu" "In8.Cu" "In10.Cu" "In12.Cu")
		(net 417)
	)
	(via
		(at 209.65 142.65)
		(size 0.35)
		(drill 0.15)
		(layers "F.Cu" "B.Cu")
		(remove_unused_layers yes)
		(keep_end_layers yes)
		(zone_layer_connections "In1.Cu" "In3.Cu" "In5.Cu" "In8.Cu" "In10.Cu" "In12.Cu")
		(net 417)
	)
	(via
		(at 194.330457 149.042472)
		(size 0.35)
		(drill 0.15)
		(layers "F.Cu" "B.Cu")
		(remove_unused_layers yes)
		(keep_end_layers yes)
		(free yes)
		(zone_layer_connections "In1.Cu" "In3.Cu" "In5.Cu" "In8.Cu" "In10.Cu" "In12.Cu")
		(net 417)
	)
	(via
		(at 221.244 153.088)
		(size 0.35)
		(drill 0.15)
		(layers "F.Cu" "B.Cu")
		(remove_unused_layers yes)
		(keep_end_layers yes)
		(zone_layer_connections "In1.Cu" "In3.Cu" "In5.Cu" "In8.Cu" "In10.Cu" "In12.Cu")
		(net 417)
	)
	(via
		(at 210.8 142.65)
		(size 0.35)
		(drill 0.15)
		(layers "F.Cu" "B.Cu")
		(remove_unused_layers yes)
		(keep_end_layers yes)
		(zone_layer_connections "In1.Cu" "In3.Cu" "In5.Cu" "In8.Cu" "In10.Cu" "In12.Cu")
		(net 417)
	)
	(via
		(at 177.205 132.517)
		(size 0.35)
		(drill 0.15)
		(layers "F.Cu" "B.Cu")
		(remove_unused_layers yes)
		(keep_end_layers yes)
		(zone_layer_connections "In1.Cu" "In3.Cu" "In5.Cu" "In8.Cu" "In10.Cu" "In12.Cu")
		(net 417)
	)
	(via
		(at 209.3 141.300001)
		(size 0.35)
		(drill 0.15)
		(layers "F.Cu" "B.Cu")
		(remove_unused_layers yes)
		(keep_end_layers yes)
		(free yes)
		(zone_layer_connections "In1.Cu" "In3.Cu" "In5.Cu" "In8.Cu" "In10.Cu" "In12.Cu")
		(net 417)
	)
	(via
		(at 194.099 139.5)
		(size 0.35)
		(drill 0.15)
		(layers "F.Cu" "B.Cu")
		(remove_unused_layers yes)
		(keep_end_layers yes)
		(zone_layer_connections "In1.Cu" "In3.Cu" "In5.Cu" "In8.Cu" "In10.Cu" "In12.Cu")
		(net 417)
	)
	(via
		(at 191.319 153.711)
		(size 0.35)
		(drill 0.15)
		(layers "F.Cu" "B.Cu")
		(remove_unused_layers yes)
		(keep_end_layers yes)
		(free yes)
		(zone_layer_connections "In1.Cu" "In3.Cu" "In5.Cu" "In8.Cu" "In10.Cu" "In12.Cu")
		(net 417)
	)
	(via
		(at 180.875 141.9375)
		(size 0.35)
		(drill 0.15)
		(layers "F.Cu" "B.Cu")
		(remove_unused_layers yes)
		(keep_end_layers yes)
		(zone_layer_connections "In1.Cu" "In3.Cu" "In4.Cu" "In5.Cu" "In8.Cu" "In10.Cu"
			"In11.Cu" "In12.Cu"
		)
		(net 417)
	)
	(via
		(at 177.75 141.9375)
		(size 0.35)
		(drill 0.15)
		(layers "F.Cu" "B.Cu")
		(remove_unused_layers yes)
		(keep_end_layers yes)
		(zone_layer_connections "In1.Cu" "In3.Cu" "In4.Cu" "In5.Cu" "In8.Cu" "In10.Cu"
			"In11.Cu" "In12.Cu"
		)
		(net 417)
	)
	(via
		(at 203.318542 152.330047)
		(size 0.35)
		(drill 0.15)
		(layers "F.Cu" "B.Cu")
		(remove_unused_layers yes)
		(keep_end_layers yes)
		(free yes)
		(zone_layer_connections "In1.Cu" "In3.Cu" "In5.Cu" "In8.Cu" "In10.Cu" "In12.Cu")
		(net 417)
	)
	(via
		(at 221.839137 126.055686)
		(size 0.35)
		(drill 0.15)
		(layers "F.Cu" "B.Cu")
		(remove_unused_layers yes)
		(keep_end_layers yes)
		(zone_layer_connections "In1.Cu" "In3.Cu" "In5.Cu" "In8.Cu" "In10.Cu" "In12.Cu")
		(net 417)
	)
	(via
		(at 203.322 119.305283)
		(size 0.35)
		(drill 0.15)
		(layers "F.Cu" "B.Cu")
		(remove_unused_layers yes)
		(keep_end_layers yes)
		(free yes)
		(zone_layer_connections "In1.Cu" "In3.Cu" "In5.Cu" "In8.Cu" "In10.Cu" "In12.Cu")
		(net 417)
	)
	(via
		(at 217.35 118.35)
		(size 0.35)
		(drill 0.15)
		(layers "F.Cu" "B.Cu")
		(remove_unused_layers yes)
		(keep_end_layers yes)
		(zone_layer_connections "In1.Cu" "In3.Cu" "In5.Cu" "In8.Cu" "In10.Cu" "In12.Cu")
		(net 417)
	)
	(via
		(at 177.205 131.216)
		(size 0.35)
		(drill 0.15)
		(layers "F.Cu" "B.Cu")
		(remove_unused_layers yes)
		(keep_end_layers yes)
		(zone_layer_connections "In1.Cu" "In3.Cu" "In5.Cu" "In8.Cu" "In10.Cu" "In12.Cu")
		(net 417)
	)
	(via
		(at 189.072 117.791)
		(size 0.35)
		(drill 0.15)
		(layers "F.Cu" "B.Cu")
		(remove_unused_layers yes)
		(keep_end_layers yes)
		(zone_layer_connections "In1.Cu" "In3.Cu" "In5.Cu" "In8.Cu" "In10.Cu" "In12.Cu")
		(net 417)
	)
	(via
		(at 210.205048 141.752492)
		(size 0.35)
		(drill 0.15)
		(layers "F.Cu" "B.Cu")
		(remove_unused_layers yes)
		(keep_end_layers yes)
		(zone_layer_connections "In1.Cu" "In3.Cu" "In5.Cu" "In8.Cu" "In10.Cu" "In12.Cu")
		(net 417)
	)
	(via
		(at 179.648764 141.563557)
		(size 0.35)
		(drill 0.15)
		(layers "F.Cu" "B.Cu")
		(remove_unused_layers yes)
		(keep_end_layers yes)
		(zone_layer_connections "In1.Cu" "In3.Cu" "In4.Cu" "In5.Cu" "In8.Cu" "In10.Cu"
			"In11.Cu" "In12.Cu"
		)
		(net 417)
	)
	(via
		(at 219.15 141.8)
		(size 0.35)
		(drill 0.15)
		(layers "F.Cu" "B.Cu")
		(remove_unused_layers yes)
		(keep_end_layers yes)
		(zone_layer_connections "In1.Cu" "In3.Cu" "In5.Cu" "In8.Cu" "In10.Cu" "In12.Cu")
		(net 417)
	)
	(via
		(at 183.2045 132.1925)
		(size 0.35)
		(drill 0.15)
		(layers "F.Cu" "B.Cu")
		(remove_unused_layers yes)
		(keep_end_layers yes)
		(zone_layer_connections "In1.Cu" "In3.Cu" "In5.Cu" "In8.Cu" "In10.Cu" "In12.Cu")
		(net 417)
	)
	(via
		(at 190.121 155.261999)
		(size 0.35)
		(drill 0.15)
		(layers "F.Cu" "B.Cu")
		(remove_unused_layers yes)
		(keep_end_layers yes)
		(free yes)
		(zone_layer_connections "In1.Cu" "In3.Cu" "In5.Cu" "In8.Cu" "In10.Cu" "In12.Cu")
		(net 417)
	)
	(via
		(at 226.55 142.605)
		(size 0.35)
		(drill 0.15)
		(layers "F.Cu" "B.Cu")
		(remove_unused_layers yes)
		(keep_end_layers yes)
		(zone_layer_connections "In3.Cu" "In5.Cu" "In8.Cu" "In10.Cu" "In12.Cu")
		(net 417)
	)
	(via
		(at 216.34 118.35)
		(size 0.35)
		(drill 0.15)
		(layers "F.Cu" "B.Cu")
		(remove_unused_layers yes)
		(keep_end_layers yes)
		(zone_layer_connections "In1.Cu" "In3.Cu" "In5.Cu" "In8.Cu" "In10.Cu" "In12.Cu")
		(net 417)
	)
	(via
		(at 218.85 120.7)
		(size 0.35)
		(drill 0.15)
		(layers "F.Cu" "B.Cu")
		(remove_unused_layers yes)
		(keep_end_layers yes)
		(zone_layer_connections "In1.Cu" "In3.Cu" "In5.Cu" "In8.Cu" "In10.Cu" "In12.Cu")
		(net 417)
	)
	(via
		(at 217.361 122.45)
		(size 0.35)
		(drill 0.15)
		(layers "F.Cu" "B.Cu")
		(remove_unused_layers yes)
		(keep_end_layers yes)
		(zone_layer_connections "In1.Cu" "In3.Cu" "In5.Cu" "In8.Cu" "In10.Cu" "In12.Cu")
		(net 417)
	)
	(via
		(at 224.85 137.863332)
		(size 0.35)
		(drill 0.15)
		(layers "F.Cu" "B.Cu")
		(remove_unused_layers yes)
		(keep_end_layers yes)
		(zone_layer_connections "In1.Cu" "In3.Cu" "In5.Cu" "In8.Cu" "In10.Cu" "In12.Cu")
		(net 417)
	)
	(via
		(at 196.11 133.48)
		(size 0.35)
		(drill 0.15)
		(layers "F.Cu" "B.Cu")
		(remove_unused_layers yes)
		(keep_end_layers yes)
		(zone_layer_connections "In1.Cu" "In3.Cu" "In5.Cu" "In8.Cu" "In10.Cu" "In12.Cu")
		(net 417)
	)
	(via
		(at 212 154.51)
		(size 0.35)
		(drill 0.15)
		(layers "F.Cu" "B.Cu")
		(remove_unused_layers yes)
		(keep_end_layers yes)
		(free yes)
		(zone_layer_connections "In1.Cu" "In3.Cu" "In5.Cu" "In8.Cu" "In10.Cu" "In12.Cu")
		(net 417)
	)
	(via
		(at 203.699 127.5)
		(size 0.35)
		(drill 0.15)
		(layers "F.Cu" "B.Cu")
		(remove_unused_layers yes)
		(keep_end_layers yes)
		(zone_layer_connections "In1.Cu" "In3.Cu" "In5.Cu" "In8.Cu" "In10.Cu" "In12.Cu")
		(net 417)
	)
	(via
		(at 223.92 140.52)
		(size 0.35)
		(drill 0.15)
		(layers "F.Cu" "B.Cu")
		(remove_unused_layers yes)
		(keep_end_layers yes)
		(zone_layer_connections "In1.Cu" "In3.Cu" "In5.Cu" "In8.Cu" "In10.Cu" "In12.Cu")
		(net 417)
	)
	(via
		(at 192.499 125.901)
		(size 0.35)
		(drill 0.15)
		(layers "F.Cu" "B.Cu")
		(remove_unused_layers yes)
		(keep_end_layers yes)
		(zone_layer_connections "In1.Cu" "In3.Cu" "In5.Cu" "In8.Cu" "In10.Cu" "In12.Cu")
		(net 417)
	)
	(via
		(at 225.806 145.367)
		(size 0.35)
		(drill 0.15)
		(layers "F.Cu" "B.Cu")
		(remove_unused_layers yes)
		(keep_end_layers yes)
		(zone_layer_connections "In1.Cu" "In3.Cu" "In5.Cu" "In8.Cu" "In10.Cu" "In12.Cu")
		(net 417)
	)
	(via
		(at 215.4425 130.947)
		(size 0.35)
		(drill 0.15)
		(layers "F.Cu" "B.Cu")
		(remove_unused_layers yes)
		(keep_end_layers yes)
		(zone_layer_connections "In1.Cu" "In3.Cu" "In5.Cu" "In8.Cu" "In10.Cu" "In12.Cu")
		(net 417)
	)
	(via
		(at 190.9 137.101)
		(size 0.35)
		(drill 0.15)
		(layers "F.Cu" "B.Cu")
		(remove_unused_layers yes)
		(keep_end_layers yes)
		(zone_layer_connections "In1.Cu" "In3.Cu" "In5.Cu" "In8.Cu" "In10.Cu" "In12.Cu")
		(net 417)
	)
	(via
		(at 218.925 147.72)
		(size 0.35)
		(drill 0.15)
		(layers "F.Cu" "B.Cu")
		(remove_unused_layers yes)
		(keep_end_layers yes)
		(zone_layer_connections "In1.Cu" "In3.Cu" "In5.Cu" "In8.Cu" "In10.Cu" "In12.Cu")
		(net 417)
	)
	(via
		(at 209.725 119.4)
		(size 0.35)
		(drill 0.15)
		(layers "F.Cu" "B.Cu")
		(remove_unused_layers yes)
		(keep_end_layers yes)
		(zone_layer_connections "In1.Cu" "In3.Cu" "In5.Cu" "In8.Cu" "In10.Cu" "In12.Cu")
		(net 417)
	)
	(via
		(at 184.8045 130.8915)
		(size 0.35)
		(drill 0.15)
		(layers "F.Cu" "B.Cu")
		(remove_unused_layers yes)
		(keep_end_layers yes)
		(zone_layer_connections "In1.Cu" "In3.Cu" "In5.Cu" "In8.Cu" "In10.Cu" "In12.Cu")
		(net 417)
	)
	(via
		(at 212.9325 152.224501)
		(size 0.35)
		(drill 0.15)
		(layers "F.Cu" "B.Cu")
		(remove_unused_layers yes)
		(keep_end_layers yes)
		(zone_layer_connections "In1.Cu" "In3.Cu" "In5.Cu" "In8.Cu" "In10.Cu" "In12.Cu")
		(net 417)
	)
	(via
		(at 192.435076 150.124283)
		(size 0.35)
		(drill 0.15)
		(layers "F.Cu" "B.Cu")
		(remove_unused_layers yes)
		(keep_end_layers yes)
		(free yes)
		(zone_layer_connections "In1.Cu" "In3.Cu" "In5.Cu" "In8.Cu" "In10.Cu" "In12.Cu")
		(net 417)
	)
	(via
		(at 216.85 154.2)
		(size 0.35)
		(drill 0.15)
		(layers "F.Cu" "B.Cu")
		(remove_unused_layers yes)
		(keep_end_layers yes)
		(free yes)
		(zone_layer_connections "In1.Cu" "In3.Cu" "In5.Cu" "In8.Cu" "In10.Cu" "In12.Cu")
		(net 417)
	)
	(via
		(at 215.6 143.65)
		(size 0.35)
		(drill 0.15)
		(layers "F.Cu" "B.Cu")
		(remove_unused_layers yes)
		(keep_end_layers yes)
		(zone_layer_connections "In1.Cu" "In3.Cu" "In5.Cu" "In8.Cu" "In10.Cu" "In12.Cu")
		(net 417)
	)
	(via
		(at 215.5 146.9)
		(size 0.35)
		(drill 0.15)
		(layers "F.Cu" "B.Cu")
		(remove_unused_layers yes)
		(keep_end_layers yes)
		(zone_layer_connections "In1.Cu" "In3.Cu" "In5.Cu" "In8.Cu" "In10.Cu" "In12.Cu")
		(net 417)
	)
	(via
		(at 201.3 128.3)
		(size 0.35)
		(drill 0.15)
		(layers "F.Cu" "B.Cu")
		(remove_unused_layers yes)
		(keep_end_layers yes)
		(zone_layer_connections "In1.Cu" "In3.Cu" "In5.Cu" "In8.Cu" "In10.Cu" "In12.Cu")
		(net 417)
	)
	(via
		(at 192.499 133.9)
		(size 0.35)
		(drill 0.15)
		(layers "F.Cu" "B.Cu")
		(remove_unused_layers yes)
		(keep_end_layers yes)
		(zone_layer_connections "In1.Cu" "In3.Cu" "In5.Cu" "In8.Cu" "In10.Cu" "In12.Cu")
		(net 417)
	)
	(via
		(at 221.52 143.82)
		(size 0.35)
		(drill 0.15)
		(layers "F.Cu" "B.Cu")
		(remove_unused_layers yes)
		(keep_end_layers yes)
		(zone_layer_connections "In1.Cu" "In3.Cu" "In5.Cu" "In8.Cu" "In10.Cu" "In12.Cu")
		(net 417)
	)
	(via
		(at 180.604265 141.585752)
		(size 0.35)
		(drill 0.15)
		(layers "F.Cu" "B.Cu")
		(remove_unused_layers yes)
		(keep_end_layers yes)
		(zone_layer_connections "In1.Cu" "In3.Cu" "In4.Cu" "In5.Cu" "In8.Cu" "In10.Cu"
			"In11.Cu" "In12.Cu"
		)
		(net 417)
	)
	(via
		(at 220.487 151.869)
		(size 0.35)
		(drill 0.15)
		(layers "F.Cu" "B.Cu")
		(remove_unused_layers yes)
		(keep_end_layers yes)
		(zone_layer_connections "In1.Cu" "In3.Cu" "In5.Cu" "In8.Cu" "In10.Cu" "In12.Cu")
		(net 417)
	)
	(via
		(at 193.722 155.260999)
		(size 0.35)
		(drill 0.15)
		(layers "F.Cu" "B.Cu")
		(remove_unused_layers yes)
		(keep_end_layers yes)
		(free yes)
		(zone_layer_connections "In1.Cu" "In3.Cu" "In5.Cu" "In8.Cu" "In10.Cu" "In12.Cu")
		(net 417)
	)
	(via
		(at 179.650002 142.2925)
		(size 0.35)
		(drill 0.15)
		(layers "F.Cu" "B.Cu")
		(remove_unused_layers yes)
		(keep_end_layers yes)
		(zone_layer_connections "In1.Cu" "In3.Cu" "In4.Cu" "In5.Cu" "In8.Cu" "In10.Cu"
			"In11.Cu" "In12.Cu"
		)
		(net 417)
	)
	(via
		(at 226.13 133.275)
		(size 0.35)
		(drill 0.15)
		(layers "F.Cu" "B.Cu")
		(remove_unused_layers yes)
		(keep_end_layers yes)
		(zone_layer_connections "In1.Cu" "In3.Cu" "In5.Cu" "In8.Cu" "In10.Cu" "In12.Cu")
		(net 417)
	)
	(via
		(at 189.5 145.95)
		(size 0.35)
		(drill 0.15)
		(layers "F.Cu" "B.Cu")
		(remove_unused_layers yes)
		(keep_end_layers yes)
		(free yes)
		(zone_layer_connections "In1.Cu" "In3.Cu" "In4.Cu" "In5.Cu" "In8.Cu" "In10.Cu"
			"In12.Cu"
		)
		(net 417)
	)
	(via
		(at 226.2 131.6)
		(size 0.35)
		(drill 0.15)
		(layers "F.Cu" "B.Cu")
		(remove_unused_layers yes)
		(keep_end_layers yes)
		(zone_layer_connections "In1.Cu" "In3.Cu" "In5.Cu" "In8.Cu" "In10.Cu" "In12.Cu")
		(net 417)
	)
	(via
		(at 222.6994 117.1821)
		(size 0.35)
		(drill 0.15)
		(layers "F.Cu" "B.Cu")
		(remove_unused_layers yes)
		(keep_end_layers yes)
		(zone_layer_connections "In1.Cu" "In3.Cu" "In5.Cu" "In8.Cu" "In10.Cu" "In12.Cu")
		(net 417)
	)
	(via
		(at 191.001053 148.942222)
		(size 0.35)
		(drill 0.15)
		(layers "F.Cu" "B.Cu")
		(remove_unused_layers yes)
		(keep_end_layers yes)
		(free yes)
		(zone_layer_connections "In1.Cu" "In3.Cu" "In5.Cu" "In8.Cu" "In10.Cu" "In12.Cu")
		(net 417)
	)
	(via
		(at 202.9 139.5)
		(size 0.35)
		(drill 0.15)
		(layers "F.Cu" "B.Cu")
		(remove_unused_layers yes)
		(keep_end_layers yes)
		(zone_layer_connections "In1.Cu" "In3.Cu" "In5.Cu" "In8.Cu" "In10.Cu" "In12.Cu")
		(net 417)
	)
	(via
		(at 180.1 142.3875)
		(size 0.35)
		(drill 0.15)
		(layers "F.Cu" "B.Cu")
		(remove_unused_layers yes)
		(keep_end_layers yes)
		(zone_layer_connections "In1.Cu" "In3.Cu" "In4.Cu" "In5.Cu" "In8.Cu" "In10.Cu"
			"In11.Cu" "In12.Cu"
		)
		(net 417)
	)
	(via
		(at 221.834 153.419)
		(size 0.35)
		(drill 0.15)
		(layers "F.Cu" "B.Cu")
		(remove_unused_layers yes)
		(keep_end_layers yes)
		(zone_layer_connections "In1.Cu" "In3.Cu" "In5.Cu" "In8.Cu" "In10.Cu" "In12.Cu")
		(net 417)
	)
	(via
		(at 213.7 149.05)
		(size 0.35)
		(drill 0.15)
		(layers "F.Cu" "B.Cu")
		(remove_unused_layers yes)
		(keep_end_layers yes)
		(zone_layer_connections "In1.Cu" "In3.Cu" "In5.Cu" "In8.Cu" "In10.Cu" "In12.Cu")
		(net 417)
	)
	(via
		(at 196.522 116.5)
		(size 0.35)
		(drill 0.15)
		(layers "F.Cu" "B.Cu")
		(remove_unused_layers yes)
		(keep_end_layers yes)
		(zone_layer_connections "In1.Cu" "In3.Cu" "In5.Cu" "In8.Cu" "In10.Cu" "In12.Cu")
		(net 417)
	)
	(via
		(at 209.322926 119.688357)
		(size 0.35)
		(drill 0.15)
		(layers "F.Cu" "B.Cu")
		(remove_unused_layers yes)
		(keep_end_layers yes)
		(free yes)
		(zone_layer_connections "In1.Cu" "In3.Cu" "In5.Cu" "In8.Cu" "In10.Cu" "In12.Cu")
		(net 417)
	)
	(via
		(at 211.1 142.2)
		(size 0.35)
		(drill 0.15)
		(layers "F.Cu" "B.Cu")
		(remove_unused_layers yes)
		(keep_end_layers yes)
		(free yes)
		(zone_layer_connections "In1.Cu" "In3.Cu" "In5.Cu" "In8.Cu" "In10.Cu" "In12.Cu")
		(net 417)
	)
	(via
		(at 215.015 141.634)
		(size 0.35)
		(drill 0.15)
		(layers "F.Cu" "B.Cu")
		(remove_unused_layers yes)
		(keep_end_layers yes)
		(zone_layer_connections "In1.Cu" "In3.Cu" "In5.Cu" "In8.Cu" "In10.Cu" "In12.Cu")
		(net 417)
	)
	(via
		(at 178.4035 130.2415)
		(size 0.35)
		(drill 0.15)
		(layers "F.Cu" "B.Cu")
		(remove_unused_layers yes)
		(keep_end_layers yes)
		(zone_layer_connections "In1.Cu" "In3.Cu" "In5.Cu" "In8.Cu" "In10.Cu" "In12.Cu")
		(net 417)
	)
	(via
		(at 214.75 121.75)
		(size 0.35)
		(drill 0.15)
		(layers "F.Cu" "B.Cu")
		(remove_unused_layers yes)
		(keep_end_layers yes)
		(zone_layer_connections "In1.Cu" "In3.Cu" "In5.Cu" "In8.Cu" "In10.Cu" "In12.Cu")
		(net 417)
	)
	(via
		(at 199.699 141.101)
		(size 0.35)
		(drill 0.15)
		(layers "F.Cu" "B.Cu")
		(remove_unused_layers yes)
		(keep_end_layers yes)
		(zone_layer_connections "In1.Cu" "In3.Cu" "In5.Cu" "In8.Cu" "In10.Cu" "In12.Cu")
		(net 417)
	)
	(via
		(at 192.522 155.260999)
		(size 0.35)
		(drill 0.15)
		(layers "F.Cu" "B.Cu")
		(remove_unused_layers yes)
		(keep_end_layers yes)
		(free yes)
		(zone_layer_connections "In1.Cu" "In3.Cu" "In5.Cu" "In8.Cu" "In10.Cu" "In12.Cu")
		(net 417)
	)
	(via
		(at 196.64 147.15)
		(size 0.35)
		(drill 0.15)
		(layers "F.Cu" "B.Cu")
		(remove_unused_layers yes)
		(keep_end_layers yes)
		(zone_layer_connections "In1.Cu" "In3.Cu" "In5.Cu" "In8.Cu" "In10.Cu" "In12.Cu")
		(net 417)
	)
	(via
		(at 195.7 139.5)
		(size 0.35)
		(drill 0.15)
		(layers "F.Cu" "B.Cu")
		(remove_unused_layers yes)
		(keep_end_layers yes)
		(zone_layer_connections "In1.Cu" "In3.Cu" "In5.Cu" "In8.Cu" "In10.Cu" "In12.Cu")
		(net 417)
	)
	(via
		(at 223.882 131.587)
		(size 0.35)
		(drill 0.15)
		(layers "F.Cu" "B.Cu")
		(remove_unused_layers yes)
		(keep_end_layers yes)
		(zone_layer_connections "In1.Cu" "In3.Cu" "In5.Cu" "In8.Cu" "In10.Cu" "In12.Cu")
		(net 417)
	)
	(via
		(at 205.719 153.711)
		(size 0.35)
		(drill 0.15)
		(layers "F.Cu" "B.Cu")
		(remove_unused_layers yes)
		(keep_end_layers yes)
		(free yes)
		(zone_layer_connections "In1.Cu" "In3.Cu" "In5.Cu" "In8.Cu" "In10.Cu" "In12.Cu")
		(net 417)
	)
	(via
		(at 211.875 124.75)
		(size 0.35)
		(drill 0.15)
		(layers "F.Cu" "B.Cu")
		(remove_unused_layers yes)
		(keep_end_layers yes)
		(zone_layer_connections "In1.Cu" "In3.Cu" "In5.Cu" "In8.Cu" "In10.Cu" "In12.Cu")
		(net 417)
	)
	(via
		(at 179.2035 134.1415)
		(size 0.35)
		(drill 0.15)
		(layers "F.Cu" "B.Cu")
		(remove_unused_layers yes)
		(keep_end_layers yes)
		(zone_layer_connections "In1.Cu" "In3.Cu" "In5.Cu" "In8.Cu" "In10.Cu" "In12.Cu")
		(net 417)
	)
	(via
		(at 205.722 155.260999)
		(size 0.35)
		(drill 0.15)
		(layers "F.Cu" "B.Cu")
		(remove_unused_layers yes)
		(keep_end_layers yes)
		(free yes)
		(zone_layer_connections "In1.Cu" "In3.Cu" "In5.Cu" "In8.Cu" "In10.Cu" "In12.Cu")
		(net 417)
	)
	(via
		(at 184.8045 126.9915)
		(size 0.35)
		(drill 0.15)
		(layers "F.Cu" "B.Cu")
		(remove_unused_layers yes)
		(keep_end_layers yes)
		(zone_layer_connections "In1.Cu" "In3.Cu" "In5.Cu" "In8.Cu" "In10.Cu" "In12.Cu")
		(net 417)
	)
	(via
		(at 184.8045 128.2915)
		(size 0.35)
		(drill 0.15)
		(layers "F.Cu" "B.Cu")
		(remove_unused_layers yes)
		(keep_end_layers yes)
		(zone_layer_connections "In1.Cu" "In3.Cu" "In5.Cu" "In8.Cu" "In10.Cu" "In12.Cu")
		(net 417)
	)
	(via
		(at 215.9635 129.922)
		(size 0.35)
		(drill 0.15)
		(layers "F.Cu" "B.Cu")
		(remove_unused_layers yes)
		(keep_end_layers yes)
		(zone_layer_connections "In1.Cu" "In3.Cu" "In5.Cu" "In8.Cu" "In10.Cu" "In12.Cu")
		(net 417)
	)
	(via
		(at 228.9 136.91)
		(size 0.35)
		(drill 0.15)
		(layers "F.Cu" "B.Cu")
		(remove_unused_layers yes)
		(keep_end_layers yes)
		(zone_layer_connections "In5.Cu" "In8.Cu" "In10.Cu" "In12.Cu")
		(net 417)
	)
	(via
		(at 214.0925 132.197)
		(size 0.35)
		(drill 0.15)
		(layers "F.Cu" "B.Cu")
		(remove_unused_layers yes)
		(keep_end_layers yes)
		(zone_layer_connections "In1.Cu" "In3.Cu" "In5.Cu" "In8.Cu" "In10.Cu" "In12.Cu")
		(net 417)
	)
	(via
		(at 200.449 148.701)
		(size 0.35)
		(drill 0.15)
		(layers "F.Cu" "B.Cu")
		(remove_unused_layers yes)
		(keep_end_layers yes)
		(zone_layer_connections "In1.Cu" "In3.Cu" "In5.Cu" "In8.Cu" "In10.Cu" "In12.Cu")
		(net 417)
	)
	(via
		(at 206.921049 117.943594)
		(size 0.35)
		(drill 0.15)
		(layers "F.Cu" "B.Cu")
		(remove_unused_layers yes)
		(keep_end_layers yes)
		(free yes)
		(zone_layer_connections "In1.Cu" "In3.Cu" "In5.Cu" "In8.Cu" "In10.Cu" "In12.Cu")
		(net 417)
	)
	(via
		(at 212.9435 129.95)
		(size 0.35)
		(drill 0.15)
		(layers "F.Cu" "B.Cu")
		(net 417)
	)
	(via
		(at 193.714626 150.115)
		(size 0.35)
		(drill 0.15)
		(layers "F.Cu" "B.Cu")
		(remove_unused_layers yes)
		(keep_end_layers yes)
		(free yes)
		(zone_layer_connections "In1.Cu" "In3.Cu" "In5.Cu" "In8.Cu" "In10.Cu" "In12.Cu")
		(net 417)
	)
	(via
		(at 180.8055 126.9905)
		(size 0.35)
		(drill 0.15)
		(layers "F.Cu" "B.Cu")
		(remove_unused_layers yes)
		(keep_end_layers yes)
		(zone_layer_connections "In1.Cu" "In3.Cu" "In5.Cu" "In8.Cu" "In10.Cu" "In12.Cu")
		(net 417)
	)
	(via
		(at 219.7 155.25)
		(size 0.35)
		(drill 0.15)
		(layers "F.Cu" "B.Cu")
		(remove_unused_layers yes)
		(keep_end_layers yes)
		(free yes)
		(zone_layer_connections "In1.Cu" "In3.Cu" "In5.Cu" "In8.Cu" "In10.Cu" "In12.Cu")
		(net 417)
	)
	(via
		(at 220.5425 150.775)
		(size 0.35)
		(drill 0.15)
		(layers "F.Cu" "B.Cu")
		(remove_unused_layers yes)
		(keep_end_layers yes)
		(zone_layer_connections "In1.Cu" "In3.Cu" "In5.Cu" "In8.Cu" "In10.Cu" "In12.Cu")
		(net 417)
	)
	(via
		(at 179.2035 125.0425)
		(size 0.35)
		(drill 0.15)
		(layers "F.Cu" "B.Cu")
		(remove_unused_layers yes)
		(keep_end_layers yes)
		(zone_layer_connections "In1.Cu" "In3.Cu" "In5.Cu" "In8.Cu" "In10.Cu" "In12.Cu")
		(net 417)
	)
	(via
		(at 181.859404 149.629531)
		(size 0.35)
		(drill 0.15)
		(layers "F.Cu" "B.Cu")
		(remove_unused_layers yes)
		(keep_end_layers yes)
		(zone_layer_connections "In1.Cu" "In3.Cu" "In4.Cu" "In5.Cu" "In8.Cu" "In10.Cu"
			"In12.Cu"
		)
		(net 417)
	)
	(via
		(at 224.8015 140.847)
		(size 0.35)
		(drill 0.15)
		(layers "F.Cu" "B.Cu")
		(remove_unused_layers yes)
		(keep_end_layers yes)
		(zone_layer_connections "In1.Cu" "In3.Cu" "In5.Cu" "In8.Cu" "In10.Cu" "In12.Cu")
		(net 417)
	)
	(via
		(at 208.122 116.491063)
		(size 0.35)
		(drill 0.15)
		(layers "F.Cu" "B.Cu")
		(remove_unused_layers yes)
		(keep_end_layers yes)
		(zone_layer_connections "In1.Cu" "In3.Cu" "In5.Cu" "In8.Cu" "In10.Cu" "In12.Cu")
		(net 417)
	)
	(via
		(at 203.319 153.711)
		(size 0.35)
		(drill 0.15)
		(layers "F.Cu" "B.Cu")
		(remove_unused_layers yes)
		(keep_end_layers yes)
		(free yes)
		(zone_layer_connections "In1.Cu" "In3.Cu" "In5.Cu" "In8.Cu" "In10.Cu" "In12.Cu")
		(net 417)
	)
	(via
		(at 194.35 144.45)
		(size 0.35)
		(drill 0.15)
		(layers "F.Cu" "B.Cu")
		(remove_unused_layers yes)
		(keep_end_layers yes)
		(zone_layer_connections "In1.Cu" "In3.Cu" "In5.Cu" "In8.Cu" "In10.Cu" "In12.Cu")
		(net 417)
	)
	(via
		(at 228.28 140.81)
		(size 0.35)
		(drill 0.15)
		(layers "F.Cu" "B.Cu")
		(remove_unused_layers yes)
		(keep_end_layers yes)
		(zone_layer_connections "In3.Cu" "In5.Cu" "In8.Cu" "In10.Cu" "In12.Cu")
		(net 417)
	)
	(via
		(at 182.534404 149.204531)
		(size 0.35)
		(drill 0.15)
		(layers "F.Cu" "B.Cu")
		(remove_unused_layers yes)
		(keep_end_layers yes)
		(zone_layer_connections "In1.Cu" "In3.Cu" "In4.Cu" "In5.Cu" "In8.Cu" "In10.Cu"
			"In12.Cu"
		)
		(net 417)
	)
	(via
		(at 206.1 141.101)
		(size 0.35)
		(drill 0.15)
		(layers "F.Cu" "B.Cu")
		(remove_unused_layers yes)
		(keep_end_layers yes)
		(zone_layer_connections "In1.Cu" "In3.Cu" "In5.Cu" "In8.Cu" "In10.Cu" "In12.Cu")
		(net 417)
	)
	(via
		(at 214.64 117.754)
		(size 0.35)
		(drill 0.15)
		(layers "F.Cu" "B.Cu")
		(remove_unused_layers yes)
		(keep_end_layers yes)
		(zone_layer_connections "In1.Cu" "In3.Cu" "In5.Cu" "In8.Cu" "In10.Cu" "In12.Cu")
		(net 417)
	)
	(via
		(at 184.8045 123.7415)
		(size 0.35)
		(drill 0.15)
		(layers "F.Cu" "B.Cu")
		(remove_unused_layers yes)
		(keep_end_layers yes)
		(zone_layer_connections "In1.Cu" "In3.Cu" "In5.Cu" "In8.Cu" "In10.Cu" "In12.Cu")
		(net 417)
	)
	(via
		(at 192.323689 150.546571)
		(size 0.35)
		(drill 0.15)
		(layers "F.Cu" "B.Cu")
		(remove_unused_layers yes)
		(keep_end_layers yes)
		(free yes)
		(zone_layer_connections "In1.Cu" "In3.Cu" "In5.Cu" "In8.Cu" "In10.Cu" "In12.Cu")
		(net 417)
	)
	(via
		(at 211.79 117.82)
		(size 0.35)
		(drill 0.15)
		(layers "F.Cu" "B.Cu")
		(remove_unused_layers yes)
		(keep_end_layers yes)
		(zone_layer_connections "In1.Cu" "In3.Cu" "In5.Cu" "In8.Cu" "In10.Cu" "In12.Cu")
		(net 417)
	)
	(via
		(at 183.925 151.55)
		(size 0.35)
		(drill 0.15)
		(layers "F.Cu" "B.Cu")
		(remove_unused_layers yes)
		(keep_end_layers yes)
		(zone_layer_connections "In1.Cu" "In3.Cu" "In4.Cu" "In5.Cu" "In8.Cu" "In10.Cu"
			"In12.Cu"
		)
		(net 417)
	)
	(via
		(at 214.6935 131.7)
		(size 0.35)
		(drill 0.15)
		(layers "F.Cu" "B.Cu")
		(remove_unused_layers yes)
		(keep_end_layers yes)
		(zone_layer_connections "In1.Cu" "In3.Cu" "In5.Cu" "In8.Cu" "In10.Cu" "In12.Cu")
		(net 417)
	)
	(via
		(at 180.8055 125.0425)
		(size 0.35)
		(drill 0.15)
		(layers "F.Cu" "B.Cu")
		(remove_unused_layers yes)
		(keep_end_layers yes)
		(zone_layer_connections "In1.Cu" "In3.Cu" "In5.Cu" "In8.Cu" "In10.Cu" "In12.Cu")
		(net 417)
	)
	(via
		(at 190.12 153.71)
		(size 0.35)
		(drill 0.15)
		(layers "F.Cu" "B.Cu")
		(remove_unused_layers yes)
		(keep_end_layers yes)
		(free yes)
		(zone_layer_connections "In1.Cu" "In3.Cu" "In5.Cu" "In8.Cu" "In10.Cu" "In12.Cu")
		(net 417)
	)
	(via
		(at 182.05 119.85)
		(size 0.35)
		(drill 0.15)
		(layers "F.Cu" "B.Cu")
		(remove_unused_layers yes)
		(keep_end_layers yes)
		(zone_layer_connections "In1.Cu" "In3.Cu" "In5.Cu" "In8.Cu" "In10.Cu" "In12.Cu")
		(net 417)
	)
	(via
		(at 212.2 146.85)
		(size 0.35)
		(drill 0.15)
		(layers "F.Cu" "B.Cu")
		(remove_unused_layers yes)
		(keep_end_layers yes)
		(free yes)
		(zone_layer_connections "In1.Cu" "In3.Cu" "In5.Cu" "In8.Cu" "In10.Cu" "In12.Cu")
		(net 417)
	)
	(via
		(at 178.4035 134.7905)
		(size 0.35)
		(drill 0.15)
		(layers "F.Cu" "B.Cu")
		(remove_unused_layers yes)
		(keep_end_layers yes)
		(zone_layer_connections "In1.Cu" "In3.Cu" "In5.Cu" "In8.Cu" "In10.Cu" "In12.Cu")
		(net 417)
	)
	(via
		(at 215.003935 145.300882)
		(size 0.35)
		(drill 0.15)
		(layers "F.Cu" "B.Cu")
		(remove_unused_layers yes)
		(keep_end_layers yes)
		(zone_layer_connections "In1.Cu" "In3.Cu" "In5.Cu" "In8.Cu" "In10.Cu" "In12.Cu")
		(net 417)
	)
	(via
		(at 202.9 140.3)
		(size 0.35)
		(drill 0.15)
		(layers "F.Cu" "B.Cu")
		(remove_unused_layers yes)
		(keep_end_layers yes)
		(zone_layer_connections "In1.Cu" "In3.Cu" "In5.Cu" "In8.Cu" "In10.Cu" "In12.Cu")
		(net 417)
	)
	(via
		(at 202.399 146.101)
		(size 0.35)
		(drill 0.15)
		(layers "F.Cu" "B.Cu")
		(remove_unused_layers yes)
		(keep_end_layers yes)
		(zone_layer_connections "In1.Cu" "In3.Cu" "In5.Cu" "In8.Cu" "In10.Cu" "In12.Cu")
		(net 417)
	)
	(via
		(at 190.45 144.25)
		(size 0.35)
		(drill 0.15)
		(layers "F.Cu" "B.Cu")
		(remove_unused_layers yes)
		(keep_end_layers yes)
		(free yes)
		(zone_layer_connections "In1.Cu" "In3.Cu" "In4.Cu" "In5.Cu" "In8.Cu" "In10.Cu"
			"In12.Cu"
		)
		(net 417)
	)
	(via
		(at 182.084404 149.204531)
		(size 0.35)
		(drill 0.15)
		(layers "F.Cu" "B.Cu")
		(remove_unused_layers yes)
		(keep_end_layers yes)
		(zone_layer_connections "In1.Cu" "In3.Cu" "In4.Cu" "In5.Cu" "In8.Cu" "In10.Cu"
			"In12.Cu"
		)
		(net 417)
	)
	(via
		(at 202.1 130.65)
		(size 0.35)
		(drill 0.15)
		(layers "F.Cu" "B.Cu")
		(remove_unused_layers yes)
		(keep_end_layers yes)
		(zone_layer_connections "In1.Cu" "In3.Cu" "In5.Cu" "In8.Cu" "In10.Cu" "In12.Cu")
		(net 417)
	)
	(via
		(at 221.9 119.9)
		(size 0.35)
		(drill 0.15)
		(layers "F.Cu" "B.Cu")
		(remove_unused_layers yes)
		(keep_end_layers yes)
		(zone_layer_connections "In1.Cu" "In3.Cu" "In5.Cu" "In8.Cu" "In10.Cu" "In12.Cu")
		(net 417)
	)
	(via
		(at 202.117 155.260999)
		(size 0.35)
		(drill 0.15)
		(layers "F.Cu" "B.Cu")
		(remove_unused_layers yes)
		(keep_end_layers yes)
		(free yes)
		(zone_layer_connections "In1.Cu" "In3.Cu" "In5.Cu" "In8.Cu" "In10.Cu" "In12.Cu")
		(net 417)
	)
	(via
		(at 209.72 153.74)
		(size 0.35)
		(drill 0.15)
		(layers "F.Cu" "B.Cu")
		(remove_unused_layers yes)
		(keep_end_layers yes)
		(free yes)
		(zone_layer_connections "In1.Cu" "In3.Cu" "In5.Cu" "In8.Cu" "In10.Cu" "In12.Cu")
		(net 417)
	)
	(via
		(at 206.1 126.701)
		(size 0.35)
		(drill 0.15)
		(layers "F.Cu" "B.Cu")
		(remove_unused_layers yes)
		(keep_end_layers yes)
		(zone_layer_connections "In1.Cu" "In3.Cu" "In5.Cu" "In8.Cu" "In10.Cu" "In12.Cu")
		(net 417)
	)
	(via
		(at 197.322 155.260999)
		(size 0.35)
		(drill 0.15)
		(layers "F.Cu" "B.Cu")
		(remove_unused_layers yes)
		(keep_end_layers yes)
		(free yes)
		(zone_layer_connections "In1.Cu" "In3.Cu" "In5.Cu" "In8.Cu" "In10.Cu" "In12.Cu")
		(net 417)
	)
	(via
		(at 212.038431 121.224779)
		(size 0.35)
		(drill 0.15)
		(layers "F.Cu" "B.Cu")
		(remove_unused_layers yes)
		(keep_end_layers yes)
		(zone_layer_connections "In1.Cu" "In3.Cu" "In5.Cu" "In8.Cu" "In10.Cu" "In12.Cu")
		(net 417)
	)
	(via
		(at 190.9 129.1)
		(size 0.35)
		(drill 0.15)
		(layers "F.Cu" "B.Cu")
		(remove_unused_layers yes)
		(keep_end_layers yes)
		(zone_layer_connections "In1.Cu" "In3.Cu" "In5.Cu" "In8.Cu" "In10.Cu" "In12.Cu")
		(net 417)
	)
	(via
		(at 175.24 126.38)
		(size 0.35)
		(drill 0.15)
		(layers "F.Cu" "B.Cu")
		(remove_unused_layers yes)
		(keep_end_layers yes)
		(zone_layer_connections "In1.Cu" "In3.Cu" "In5.Cu" "In8.Cu" "In10.Cu" "In12.Cu")
		(net 417)
	)
	(via
		(at 215.45 154.51)
		(size 0.35)
		(drill 0.15)
		(layers "F.Cu" "B.Cu")
		(remove_unused_layers yes)
		(keep_end_layers yes)
		(free yes)
		(zone_layer_connections "In1.Cu" "In3.Cu" "In5.Cu" "In8.Cu" "In10.Cu" "In12.Cu")
		(net 417)
	)
	(via
		(at 221.42987 148.395)
		(size 0.35)
		(drill 0.15)
		(layers "F.Cu" "B.Cu")
		(remove_unused_layers yes)
		(keep_end_layers yes)
		(zone_layer_connections "In1.Cu" "In3.Cu" "In5.Cu" "In8.Cu" "In10.Cu" "In12.Cu")
		(net 417)
	)
	(via
		(at 218.85 118.7)
		(size 0.35)
		(drill 0.15)
		(layers "F.Cu" "B.Cu")
		(remove_unused_layers yes)
		(keep_end_layers yes)
		(zone_layer_connections "In1.Cu" "In3.Cu" "In5.Cu" "In8.Cu" "In10.Cu" "In12.Cu")
		(net 417)
	)
	(via
		(at 184.1 141.9375)
		(size 0.35)
		(drill 0.15)
		(layers "F.Cu" "B.Cu")
		(remove_unused_layers yes)
		(keep_end_layers yes)
		(zone_layer_connections "In1.Cu" "In3.Cu" "In4.Cu" "In5.Cu" "In8.Cu" "In10.Cu"
			"In11.Cu" "In12.Cu"
		)
		(net 417)
	)
	(via
		(at 204.499 137.901)
		(size 0.35)
		(drill 0.15)
		(layers "F.Cu" "B.Cu")
		(remove_unused_layers yes)
		(keep_end_layers yes)
		(zone_layer_connections "In1.Cu" "In3.Cu" "In5.Cu" "In8.Cu" "In10.Cu" "In12.Cu")
		(net 417)
	)
	(via
		(at 211.9435 134.449)
		(size 0.35)
		(drill 0.15)
		(layers "F.Cu" "B.Cu")
		(remove_unused_layers yes)
		(keep_end_layers yes)
		(zone_layer_connections "In1.Cu" "In3.Cu" "In5.Cu" "In8.Cu" "In10.Cu" "In12.Cu")
		(net 417)
	)
	(via
		(at 197.7045 137.5055)
		(size 0.35)
		(drill 0.15)
		(layers "F.Cu" "B.Cu")
		(remove_unused_layers yes)
		(keep_end_layers yes)
		(zone_layer_connections "In1.Cu" "In3.Cu" "In5.Cu" "In8.Cu" "In10.Cu" "In12.Cu")
		(net 417)
	)
	(via
		(at 228.77 135.91)
		(size 0.35)
		(drill 0.15)
		(layers "F.Cu" "B.Cu")
		(remove_unused_layers yes)
		(keep_end_layers yes)
		(zone_layer_connections "In5.Cu" "In8.Cu" "In10.Cu" "In12.Cu")
		(net 417)
	)
	(via
		(at 202.9 125.101)
		(size 0.35)
		(drill 0.15)
		(layers "F.Cu" "B.Cu")
		(remove_unused_layers yes)
		(keep_end_layers yes)
		(zone_layer_connections "In1.Cu" "In3.Cu" "In5.Cu" "In8.Cu" "In10.Cu" "In12.Cu")
		(net 417)
	)
	(via
		(at 200.918542 152.330047)
		(size 0.35)
		(drill 0.15)
		(layers "F.Cu" "B.Cu")
		(remove_unused_layers yes)
		(keep_end_layers yes)
		(free yes)
		(zone_layer_connections "In1.Cu" "In3.Cu" "In5.Cu" "In8.Cu" "In10.Cu" "In12.Cu")
		(net 417)
	)
	(via
		(at 208.7 118.38)
		(size 0.35)
		(drill 0.15)
		(layers "F.Cu" "B.Cu")
		(remove_unused_layers yes)
		(keep_end_layers yes)
		(free yes)
		(zone_layer_connections "In1.Cu" "In3.Cu" "In5.Cu" "In8.Cu" "In10.Cu" "In12.Cu")
		(net 417)
	)
	(via
		(at 203.699 135.5)
		(size 0.35)
		(drill 0.15)
		(layers "F.Cu" "B.Cu")
		(remove_unused_layers yes)
		(keep_end_layers yes)
		(zone_layer_connections "In1.Cu" "In3.Cu" "In5.Cu" "In8.Cu" "In10.Cu" "In12.Cu")
		(net 417)
	)
	(via
		(at 182.360904 148.731531)
		(size 0.35)
		(drill 0.15)
		(layers "F.Cu" "B.Cu")
		(remove_unused_layers yes)
		(keep_end_layers yes)
		(zone_layer_connections "In1.Cu" "In3.Cu" "In4.Cu" "In5.Cu" "In8.Cu" "In10.Cu"
			"In12.Cu"
		)
		(net 417)
	)
	(via
		(at 216.382499 152.2245)
		(size 0.35)
		(drill 0.15)
		(layers "F.Cu" "B.Cu")
		(remove_unused_layers yes)
		(keep_end_layers yes)
		(zone_layer_connections "In1.Cu" "In3.Cu" "In5.Cu" "In8.Cu" "In10.Cu" "In12.Cu")
		(net 417)
	)
	(via
		(at 208.35 153.27)
		(size 0.35)
		(drill 0.15)
		(layers "F.Cu" "B.Cu")
		(remove_unused_layers yes)
		(keep_end_layers yes)
		(free yes)
		(zone_layer_connections "In1.Cu" "In3.Cu" "In5.Cu" "In8.Cu" "In10.Cu" "In12.Cu")
		(net 417)
	)
	(via
		(at 213.965 141.634)
		(size 0.35)
		(drill 0.15)
		(layers "F.Cu" "B.Cu")
		(remove_unused_layers yes)
		(keep_end_layers yes)
		(zone_layer_connections "In1.Cu" "In3.Cu" "In5.Cu" "In8.Cu" "In10.Cu" "In12.Cu")
		(net 417)
	)
	(via
		(at 197.720074 119.303357)
		(size 0.35)
		(drill 0.15)
		(layers "F.Cu" "B.Cu")
		(remove_unused_layers yes)
		(keep_end_layers yes)
		(zone_layer_connections "In1.Cu" "In3.Cu" "In5.Cu" "In8.Cu" "In10.Cu" "In12.Cu")
		(net 417)
	)
	(via
		(at 196.08 135.12)
		(size 0.35)
		(drill 0.15)
		(layers "F.Cu" "B.Cu")
		(remove_unused_layers yes)
		(keep_end_layers yes)
		(zone_layer_connections "In1.Cu" "In3.Cu" "In5.Cu" "In8.Cu" "In10.Cu" "In12.Cu")
		(net 417)
	)
	(via
		(at 222.2 146.095)
		(size 0.35)
		(drill 0.15)
		(layers "F.Cu" "B.Cu")
		(remove_unused_layers yes)
		(keep_end_layers yes)
		(zone_layer_connections "In1.Cu" "In3.Cu" "In5.Cu" "In8.Cu" "In10.Cu" "In12.Cu")
		(net 417)
	)
	(via
		(at 208.65 155.25)
		(size 0.35)
		(drill 0.15)
		(layers "F.Cu" "B.Cu")
		(remove_unused_layers yes)
		(keep_end_layers yes)
		(free yes)
		(zone_layer_connections "In1.Cu" "In3.Cu" "In5.Cu" "In8.Cu" "In10.Cu" "In12.Cu")
		(net 417)
	)
	(via
		(at 221.95 142.91)
		(size 0.35)
		(drill 0.15)
		(layers "F.Cu" "B.Cu")
		(remove_unused_layers yes)
		(keep_end_layers yes)
		(zone_layer_connections "In1.Cu" "In3.Cu" "In5.Cu" "In8.Cu" "In10.Cu" "In12.Cu")
		(net 417)
	)
	(via
		(at 180.35 141.9375)
		(size 0.35)
		(drill 0.15)
		(layers "F.Cu" "B.Cu")
		(remove_unused_layers yes)
		(keep_end_layers yes)
		(zone_layer_connections "In1.Cu" "In3.Cu" "In4.Cu" "In5.Cu" "In8.Cu" "In10.Cu"
			"In11.Cu" "In12.Cu"
		)
		(net 417)
	)
	(via
		(at 180.8055 123.7425)
		(size 0.35)
		(drill 0.15)
		(layers "F.Cu" "B.Cu")
		(remove_unused_layers yes)
		(keep_end_layers yes)
		(zone_layer_connections "In1.Cu" "In3.Cu" "In5.Cu" "In8.Cu" "In10.Cu" "In12.Cu")
		(net 417)
	)
	(via
		(at 221.32 120.65)
		(size 0.35)
		(drill 0.15)
		(layers "F.Cu" "B.Cu")
		(remove_unused_layers yes)
		(keep_end_layers yes)
		(zone_layer_connections "In1.Cu" "In3.Cu" "In5.Cu" "In8.Cu" "In10.Cu" "In12.Cu")
		(net 417)
	)
	(via
		(at 215.397922 142.167245)
		(size 0.35)
		(drill 0.15)
		(layers "F.Cu" "B.Cu")
		(remove_unused_layers yes)
		(keep_end_layers yes)
		(zone_layer_connections "In1.Cu" "In3.Cu" "In5.Cu" "In8.Cu" "In10.Cu" "In12.Cu")
		(net 417)
	)
	(via
		(at 217.08 155.361)
		(size 0.35)
		(drill 0.15)
		(layers "F.Cu" "B.Cu")
		(remove_unused_layers yes)
		(keep_end_layers yes)
		(zone_layer_connections "In1.Cu" "In3.Cu" "In5.Cu" "In8.Cu" "In10.Cu" "In12.Cu")
		(net 417)
	)
	(via
		(at 189.55 144.25)
		(size 0.35)
		(drill 0.15)
		(layers "F.Cu" "B.Cu")
		(remove_unused_layers yes)
		(keep_end_layers yes)
		(free yes)
		(zone_layer_connections "In1.Cu" "In3.Cu" "In5.Cu" "In8.Cu" "In10.Cu" "In12.Cu")
		(net 417)
	)
	(via
		(at 209.2 145.45)
		(size 0.35)
		(drill 0.15)
		(layers "F.Cu" "B.Cu")
		(remove_unused_layers yes)
		(keep_end_layers yes)
		(zone_layer_connections "In1.Cu" "In3.Cu" "In5.Cu" "In8.Cu" "In10.Cu" "In12.Cu")
		(net 417)
	)
	(via
		(at 182.360904 147.831531)
		(size 0.35)
		(drill 0.15)
		(layers "F.Cu" "B.Cu")
		(remove_unused_layers yes)
		(keep_end_layers yes)
		(zone_layer_connections "In1.Cu" "In3.Cu" "In4.Cu" "In5.Cu" "In8.Cu" "In10.Cu"
			"In12.Cu"
		)
		(net 417)
	)
	(via
		(at 221.32 119.15)
		(size 0.35)
		(drill 0.15)
		(layers "F.Cu" "B.Cu")
		(remove_unused_layers yes)
		(keep_end_layers yes)
		(zone_layer_connections "In1.Cu" "In3.Cu" "In5.Cu" "In8.Cu" "In10.Cu" "In12.Cu")
		(net 417)
	)
	(via
		(at 215.361 122.45)
		(size 0.35)
		(drill 0.15)
		(layers "F.Cu" "B.Cu")
		(remove_unused_layers yes)
		(keep_end_layers yes)
		(zone_layer_connections "In1.Cu" "In3.Cu" "In5.Cu" "In8.Cu" "In10.Cu" "In12.Cu")
		(net 417)
	)
	(via
		(at 180.8055 134.1415)
		(size 0.35)
		(drill 0.15)
		(layers "F.Cu" "B.Cu")
		(remove_unused_layers yes)
		(keep_end_layers yes)
		(zone_layer_connections "In1.Cu" "In3.Cu" "In5.Cu" "In8.Cu" "In10.Cu" "In12.Cu")
		(net 417)
	)
	(via
		(at 208.119049 117.943594)
		(size 0.35)
		(drill 0.15)
		(layers "F.Cu" "B.Cu")
		(remove_unused_layers yes)
		(keep_end_layers yes)
		(free yes)
		(zone_layer_connections "In1.Cu" "In3.Cu" "In5.Cu" "In8.Cu" "In10.Cu" "In12.Cu")
		(net 417)
	)
	(via
		(at 220.624 152.699)
		(size 0.35)
		(drill 0.15)
		(layers "F.Cu" "B.Cu")
		(remove_unused_layers yes)
		(keep_end_layers yes)
		(zone_layer_connections "In1.Cu" "In3.Cu" "In5.Cu" "In8.Cu" "In10.Cu" "In12.Cu")
		(net 417)
	)
	(via
		(at 183.434404 149.204531)
		(size 0.35)
		(drill 0.15)
		(layers "F.Cu" "B.Cu")
		(remove_unused_layers yes)
		(keep_end_layers yes)
		(zone_layer_connections "In1.Cu" "In3.Cu" "In4.Cu" "In5.Cu" "In8.Cu" "In10.Cu"
			"In12.Cu"
		)
		(net 417)
	)
	(via
		(at 221.3 122.16)
		(size 0.35)
		(drill 0.15)
		(layers "F.Cu" "B.Cu")
		(remove_unused_layers yes)
		(keep_end_layers yes)
		(zone_layer_connections "In1.Cu" "In3.Cu" "In5.Cu" "In8.Cu" "In10.Cu" "In12.Cu")
		(net 417)
	)
	(via
		(at 198.922 116.75)
		(size 0.35)
		(drill 0.15)
		(layers "F.Cu" "B.Cu")
		(remove_unused_layers yes)
		(keep_end_layers yes)
		(zone_layer_connections "In1.Cu" "In3.Cu" "In5.Cu" "In8.Cu" "In10.Cu" "In12.Cu")
		(net 417)
	)
	(via
		(at 215.619181 141.607542)
		(size 0.35)
		(drill 0.15)
		(layers "F.Cu" "B.Cu")
		(remove_unused_layers yes)
		(keep_end_layers yes)
		(zone_layer_connections "In1.Cu" "In3.Cu" "In5.Cu" "In8.Cu" "In10.Cu" "In12.Cu")
		(net 417)
	)
	(via
		(at 227.6 142.69)
		(size 0.35)
		(drill 0.15)
		(layers "F.Cu" "B.Cu")
		(remove_unused_layers yes)
		(keep_end_layers yes)
		(zone_layer_connections "In3.Cu" "In5.Cu" "In8.Cu" "In10.Cu" "In12.Cu")
		(net 417)
	)
	(via
		(at 185.75 122.35)
		(size 0.35)
		(drill 0.15)
		(layers "F.Cu" "B.Cu")
		(remove_unused_layers yes)
		(keep_end_layers yes)
		(zone_layer_connections "In1.Cu" "In3.Cu" "In5.Cu" "In8.Cu" "In10.Cu" "In12.Cu")
		(net 417)
	)
	(via
		(at 179.2035 136.7415)
		(size 0.35)
		(drill 0.15)
		(layers "F.Cu" "B.Cu")
		(remove_unused_layers yes)
		(keep_end_layers yes)
		(zone_layer_connections "In1.Cu" "In3.Cu" "In5.Cu" "In8.Cu" "In10.Cu" "In12.Cu")
		(net 417)
	)
	(via
		(at 183.1 141.9375)
		(size 0.35)
		(drill 0.15)
		(layers "F.Cu" "B.Cu")
		(remove_unused_layers yes)
		(keep_end_layers yes)
		(zone_layer_connections "In1.Cu" "In3.Cu" "In4.Cu" "In5.Cu" "In8.Cu" "In10.Cu"
			"In11.Cu" "In12.Cu"
		)
		(net 417)
	)
	(via
		(at 191.322 155.260999)
		(size 0.35)
		(drill 0.15)
		(layers "F.Cu" "B.Cu")
		(remove_unused_layers yes)
		(keep_end_layers yes)
		(free yes)
		(zone_layer_connections "In1.Cu" "In3.Cu" "In5.Cu" "In8.Cu" "In10.Cu" "In12.Cu")
		(net 417)
	)
	(via
		(at 210.55 124.9)
		(size 0.35)
		(drill 0.15)
		(layers "F.Cu" "B.Cu")
		(remove_unused_layers yes)
		(keep_end_layers yes)
		(zone_layer_connections "In1.Cu" "In3.Cu" "In5.Cu" "In8.Cu" "In10.Cu" "In12.Cu")
		(net 417)
	)
	(via
		(at 202.114 153.711)
		(size 0.35)
		(drill 0.15)
		(layers "F.Cu" "B.Cu")
		(remove_unused_layers yes)
		(keep_end_layers yes)
		(free yes)
		(zone_layer_connections "In1.Cu" "In3.Cu" "In5.Cu" "In8.Cu" "In10.Cu" "In12.Cu")
		(net 417)
	)
	(via
		(at 219.67 154.1)
		(size 0.35)
		(drill 0.15)
		(layers "F.Cu" "B.Cu")
		(remove_unused_layers yes)
		(keep_end_layers yes)
		(free yes)
		(zone_layer_connections "In1.Cu" "In3.Cu" "In5.Cu" "In8.Cu" "In10.Cu" "In12.Cu")
		(net 417)
	)
	(via
		(at 186.68 119.215)
		(size 0.35)
		(drill 0.15)
		(layers "F.Cu" "B.Cu")
		(remove_unused_layers yes)
		(keep_end_layers yes)
		(zone_layer_connections "In1.Cu" "In3.Cu" "In5.Cu" "In8.Cu" "In10.Cu" "In12.Cu")
		(net 417)
	)
	(via
		(at 185.1 141.9375)
		(size 0.35)
		(drill 0.15)
		(layers "F.Cu" "B.Cu")
		(remove_unused_layers yes)
		(keep_end_layers yes)
		(zone_layer_connections "In1.Cu" "In3.Cu" "In4.Cu" "In5.Cu" "In8.Cu" "In10.Cu"
			"In11.Cu" "In12.Cu"
		)
		(net 417)
	)
	(via
		(at 180.202763 148.663922)
		(size 0.35)
		(drill 0.15)
		(layers "F.Cu" "B.Cu")
		(remove_unused_layers yes)
		(keep_end_layers yes)
		(zone_layer_connections "In1.Cu" "In3.Cu" "In4.Cu" "In5.Cu" "In8.Cu" "In10.Cu"
			"In12.Cu"
		)
		(net 417)
	)
	(via
		(at 184.0035 130.2415)
		(size 0.35)
		(drill 0.15)
		(layers "F.Cu" "B.Cu")
		(remove_unused_layers yes)
		(keep_end_layers yes)
		(zone_layer_connections "In1.Cu" "In3.Cu" "In5.Cu" "In8.Cu" "In10.Cu" "In12.Cu")
		(net 417)
	)
	(via
		(at 225.4015 140.847)
		(size 0.35)
		(drill 0.15)
		(layers "F.Cu" "B.Cu")
		(remove_unused_layers yes)
		(keep_end_layers yes)
		(zone_layer_connections "In1.Cu" "In3.Cu" "In5.Cu" "In8.Cu" "In10.Cu" "In12.Cu")
		(net 417)
	)
	(via
		(at 184.0035 128.9415)
		(size 0.35)
		(drill 0.15)
		(layers "F.Cu" "B.Cu")
		(remove_unused_layers yes)
		(keep_end_layers yes)
		(zone_layer_connections "In1.Cu" "In3.Cu" "In5.Cu" "In8.Cu" "In10.Cu" "In12.Cu")
		(net 417)
	)
	(via
		(at 214.3 127.6)
		(size 0.35)
		(drill 0.15)
		(layers "F.Cu" "B.Cu")
		(remove_unused_layers yes)
		(keep_end_layers yes)
		(zone_layer_connections "In1.Cu" "In3.Cu" "In5.Cu" "In8.Cu" "In10.Cu" "In12.Cu")
		(net 417)
	)
	(via
		(at 179.892933 139.764999)
		(size 0.35)
		(drill 0.15)
		(layers "F.Cu" "B.Cu")
		(remove_unused_layers yes)
		(keep_end_layers yes)
		(zone_layer_connections "In1.Cu" "In3.Cu" "In4.Cu" "In5.Cu" "In8.Cu" "In10.Cu"
			"In11.Cu" "In12.Cu"
		)
		(net 417)
	)
	(via
		(at 200.499 125.901)
		(size 0.35)
		(drill 0.15)
		(layers "F.Cu" "B.Cu")
		(remove_unused_layers yes)
		(keep_end_layers yes)
		(zone_layer_connections "In1.Cu" "In3.Cu" "In5.Cu" "In8.Cu" "In10.Cu" "In12.Cu")
		(net 417)
	)
	(via
		(at 209.2 144.3)
		(size 0.35)
		(drill 0.15)
		(layers "F.Cu" "B.Cu")
		(remove_unused_layers yes)
		(keep_end_layers yes)
		(zone_layer_connections "In1.Cu" "In3.Cu" "In5.Cu" "In8.Cu" "In10.Cu" "In12.Cu")
		(net 417)
	)
	(via
		(at 214.361 122.475)
		(size 0.35)
		(drill 0.15)
		(layers "F.Cu" "B.Cu")
		(remove_unused_layers yes)
		(keep_end_layers yes)
		(zone_layer_connections "In1.Cu" "In3.Cu" "In5.Cu" "In8.Cu" "In10.Cu" "In12.Cu")
		(net 417)
	)
	(via
		(at 182.4055 126.3415)
		(size 0.35)
		(drill 0.15)
		(layers "F.Cu" "B.Cu")
		(remove_unused_layers yes)
		(keep_end_layers yes)
		(zone_layer_connections "In1.Cu" "In3.Cu" "In5.Cu" "In8.Cu" "In10.Cu" "In12.Cu")
		(net 417)
	)
	(via
		(at 196.5 131.501)
		(size 0.35)
		(drill 0.15)
		(layers "F.Cu" "B.Cu")
		(remove_unused_layers yes)
		(keep_end_layers yes)
		(zone_layer_connections "In1.Cu" "In3.Cu" "In5.Cu" "In8.Cu" "In10.Cu" "In12.Cu")
		(net 417)
	)
	(via
		(at 220.644 153.409)
		(size 0.35)
		(drill 0.15)
		(layers "F.Cu" "B.Cu")
		(remove_unused_layers yes)
		(keep_end_layers yes)
		(zone_layer_connections "In1.Cu" "In3.Cu" "In5.Cu" "In8.Cu" "In10.Cu" "In12.Cu")
		(net 417)
	)
	(via
		(at 225.74 135.59)
		(size 0.35)
		(drill 0.15)
		(layers "F.Cu" "B.Cu")
		(remove_unused_layers yes)
		(keep_end_layers yes)
		(zone_layer_connections "In5.Cu" "In8.Cu" "In10.Cu" "In12.Cu")
		(net 417)
	)
	(via
		(at 212.210439 148.209976)
		(size 0.35)
		(drill 0.15)
		(layers "F.Cu" "B.Cu")
		(remove_unused_layers yes)
		(keep_end_layers yes)
		(free yes)
		(zone_layer_connections "In1.Cu" "In3.Cu" "In5.Cu" "In8.Cu" "In10.Cu" "In12.Cu")
		(net 417)
	)
	(via
		(at 178.4035 128.9415)
		(size 0.35)
		(drill 0.15)
		(layers "F.Cu" "B.Cu")
		(remove_unused_layers yes)
		(keep_end_layers yes)
		(zone_layer_connections "In1.Cu" "In3.Cu" "In5.Cu" "In8.Cu" "In10.Cu" "In12.Cu")
		(net 417)
	)
	(via
		(at 214.75 120.75)
		(size 0.35)
		(drill 0.15)
		(layers "F.Cu" "B.Cu")
		(remove_unused_layers yes)
		(keep_end_layers yes)
		(zone_layer_connections "In1.Cu" "In3.Cu" "In5.Cu" "In8.Cu" "In10.Cu" "In12.Cu")
		(net 417)
	)
	(via
		(at 212.865 140.65)
		(size 0.35)
		(drill 0.15)
		(layers "F.Cu" "B.Cu")
		(remove_unused_layers yes)
		(keep_end_layers yes)
		(zone_layer_connections "In1.Cu" "In3.Cu" "In5.Cu" "In8.Cu" "In10.Cu" "In12.Cu")
		(net 417)
	)
	(via
		(at 205.322926 119.303357)
		(size 0.35)
		(drill 0.15)
		(layers "F.Cu" "B.Cu")
		(remove_unused_layers yes)
		(keep_end_layers yes)
		(free yes)
		(zone_layer_connections "In1.Cu" "In3.Cu" "In5.Cu" "In8.Cu" "In10.Cu" "In12.Cu")
		(net 417)
	)
	(via
		(at 176.15 130.25)
		(size 0.35)
		(drill 0.15)
		(layers "F.Cu" "B.Cu")
		(remove_unused_layers yes)
		(keep_end_layers yes)
		(zone_layer_connections "In1.Cu" "In3.Cu" "In5.Cu" "In8.Cu" "In10.Cu" "In12.Cu")
		(net 417)
	)
	(via
		(at 214.75 118.754)
		(size 0.35)
		(drill 0.15)
		(layers "F.Cu" "B.Cu")
		(remove_unused_layers yes)
		(keep_end_layers yes)
		(zone_layer_connections "In1.Cu" "In3.Cu" "In5.Cu" "In8.Cu" "In10.Cu" "In12.Cu")
		(net 417)
	)
	(via
		(at 196.34 142.53)
		(size 0.35)
		(drill 0.15)
		(layers "F.Cu" "B.Cu")
		(remove_unused_layers yes)
		(keep_end_layers yes)
		(zone_layer_connections "In1.Cu" "In3.Cu" "In5.Cu" "In8.Cu" "In10.Cu" "In12.Cu")
		(net 417)
	)
	(via
		(at 190.1 119.75)
		(size 0.35)
		(drill 0.15)
		(layers "F.Cu" "B.Cu")
		(remove_unused_layers yes)
		(keep_end_layers yes)
		(zone_layer_connections "In1.Cu" "In3.Cu" "In5.Cu" "In8.Cu" "In10.Cu" "In12.Cu")
		(net 417)
	)
	(via
		(at 182.309404 149.629531)
		(size 0.35)
		(drill 0.15)
		(layers "F.Cu" "B.Cu")
		(remove_unused_layers yes)
		(keep_end_layers yes)
		(zone_layer_connections "In1.Cu" "In3.Cu" "In4.Cu" "In5.Cu" "In8.Cu" "In10.Cu"
			"In12.Cu"
		)
		(net 417)
	)
	(via
		(at 176.15 128.9)
		(size 0.35)
		(drill 0.15)
		(layers "F.Cu" "B.Cu")
		(remove_unused_layers yes)
		(keep_end_layers yes)
		(zone_layer_connections "In1.Cu" "In3.Cu" "In5.Cu" "In8.Cu" "In10.Cu" "In12.Cu")
		(net 417)
	)
	(via
		(at 226.05 140.605)
		(size 0.35)
		(drill 0.15)
		(layers "F.Cu" "B.Cu")
		(remove_unused_layers yes)
		(keep_end_layers yes)
		(zone_layer_connections "In3.Cu" "In5.Cu" "In8.Cu" "In10.Cu" "In12.Cu")
		(net 417)
	)
	(via
		(at 202.113542 152.330047)
		(size 0.35)
		(drill 0.15)
		(layers "F.Cu" "B.Cu")
		(remove_unused_layers yes)
		(keep_end_layers yes)
		(free yes)
		(zone_layer_connections "In1.Cu" "In3.Cu" "In5.Cu" "In8.Cu" "In10.Cu" "In12.Cu")
		(net 417)
	)
	(via
		(at 175.22 132.85)
		(size 0.35)
		(drill 0.15)
		(layers "F.Cu" "B.Cu")
		(remove_unused_layers yes)
		(keep_end_layers yes)
		(zone_layer_connections "In1.Cu" "In3.Cu" "In5.Cu" "In8.Cu" "In10.Cu" "In12.Cu")
		(net 417)
	)
	(via
		(at 191.7 139.5)
		(size 0.35)
		(drill 0.15)
		(layers "F.Cu" "B.Cu")
		(remove_unused_layers yes)
		(keep_end_layers yes)
		(zone_layer_connections "In1.Cu" "In3.Cu" "In5.Cu" "In8.Cu" "In10.Cu" "In12.Cu")
		(net 417)
	)
	(via
		(at 224.88 135.89)
		(size 0.35)
		(drill 0.15)
		(layers "F.Cu" "B.Cu")
		(remove_unused_layers yes)
		(keep_end_layers yes)
		(zone_layer_connections "In1.Cu" "In3.Cu" "In5.Cu" "In8.Cu" "In10.Cu" "In12.Cu")
		(net 417)
	)
	(via
		(at 217.75367 153.532252)
		(size 0.35)
		(drill 0.15)
		(layers "F.Cu" "B.Cu")
		(remove_unused_layers yes)
		(keep_end_layers yes)
		(free yes)
		(zone_layer_connections "In1.Cu" "In3.Cu" "In5.Cu" "In8.Cu" "In10.Cu" "In12.Cu")
		(net 417)
	)
	(via
		(at 190.1 134.7)
		(size 0.35)
		(drill 0.15)
		(layers "F.Cu" "B.Cu")
		(remove_unused_layers yes)
		(keep_end_layers yes)
		(zone_layer_connections "In1.Cu" "In3.Cu" "In5.Cu" "In8.Cu" "In10.Cu" "In12.Cu")
		(net 417)
	)
	(via
		(at 194.9 137.901)
		(size 0.35)
		(drill 0.15)
		(layers "F.Cu" "B.Cu")
		(remove_unused_layers yes)
		(keep_end_layers yes)
		(zone_layer_connections "In1.Cu" "In3.Cu" "In5.Cu" "In8.Cu" "In10.Cu" "In12.Cu")
		(net 417)
	)
	(via
		(at 190.9 145.1)
		(size 0.35)
		(drill 0.15)
		(layers "F.Cu" "B.Cu")
		(remove_unused_layers yes)
		(keep_end_layers yes)
		(zone_layer_connections "In1.Cu" "In3.Cu" "In5.Cu" "In8.Cu" "In10.Cu" "In12.Cu")
		(net 417)
	)
	(via
		(at 190.002492 145.594953)
		(size 0.35)
		(drill 0.15)
		(layers "F.Cu" "B.Cu")
		(remove_unused_layers yes)
		(keep_end_layers yes)
		(zone_layer_connections "In1.Cu" "In3.Cu" "In4.Cu" "In5.Cu" "In8.Cu" "In10.Cu"
			"In12.Cu"
		)
		(net 417)
	)
	(via
		(at 222.35 134.235)
		(size 0.35)
		(drill 0.15)
		(layers "F.Cu" "B.Cu")
		(remove_unused_layers yes)
		(keep_end_layers yes)
		(zone_layer_connections "In1.Cu" "In3.Cu" "In5.Cu" "In8.Cu" "In10.Cu" "In12.Cu")
		(net 417)
	)
	(via
		(at 212.74 123.85)
		(size 0.35)
		(drill 0.15)
		(layers "F.Cu" "B.Cu")
		(remove_unused_layers yes)
		(keep_end_layers yes)
		(zone_layer_connections "In1.Cu" "In3.Cu" "In5.Cu" "In8.Cu" "In10.Cu" "In12.Cu")
		(net 417)
	)
	(via
		(at 200.05 144.41)
		(size 0.35)
		(drill 0.15)
		(layers "F.Cu" "B.Cu")
		(remove_unused_layers yes)
		(keep_end_layers yes)
		(zone_layer_connections "In1.Cu" "In3.Cu" "In5.Cu" "In8.Cu" "In10.Cu" "In12.Cu")
		(net 417)
	)
	(via
		(at 189.299 124.3)
		(size 0.35)
		(drill 0.15)
		(layers "F.Cu" "B.Cu")
		(remove_unused_layers yes)
		(keep_end_layers yes)
		(zone_layer_connections "In1.Cu" "In3.Cu" "In5.Cu" "In8.Cu" "In10.Cu" "In12.Cu")
		(net 417)
	)
	(via
		(at 184.8045 135.4415)
		(size 0.35)
		(drill 0.15)
		(layers "F.Cu" "B.Cu")
		(remove_unused_layers yes)
		(keep_end_layers yes)
		(zone_layer_connections "In1.Cu" "In3.Cu" "In5.Cu" "In8.Cu" "In10.Cu" "In12.Cu")
		(net 417)
	)
	(via
		(at 214 146.95)
		(size 0.35)
		(drill 0.15)
		(layers "F.Cu" "B.Cu")
		(remove_unused_layers yes)
		(keep_end_layers yes)
		(zone_layer_connections "In1.Cu" "In3.Cu" "In5.Cu" "In8.Cu" "In10.Cu" "In12.Cu")
		(net 417)
	)
	(via
		(at 206.299 148.701)
		(size 0.35)
		(drill 0.15)
		(layers "F.Cu" "B.Cu")
		(remove_unused_layers yes)
		(keep_end_layers yes)
		(zone_layer_connections "In1.Cu" "In3.Cu" "In5.Cu" "In8.Cu" "In10.Cu" "In12.Cu")
		(net 417)
	)
	(via
		(at 190.1 126.701)
		(size 0.35)
		(drill 0.15)
		(layers "F.Cu" "B.Cu")
		(remove_unused_layers yes)
		(keep_end_layers yes)
		(zone_layer_connections "In1.Cu" "In3.Cu" "In5.Cu" "In8.Cu" "In10.Cu" "In12.Cu")
		(net 417)
	)
	(via
		(at 199.699 131.501)
		(size 0.35)
		(drill 0.15)
		(layers "F.Cu" "B.Cu")
		(remove_unused_layers yes)
		(keep_end_layers yes)
		(zone_layer_connections "In1.Cu" "In3.Cu" "In5.Cu" "In8.Cu" "In10.Cu" "In12.Cu")
		(net 417)
	)
	(via
		(at 193.085 144.45)
		(size 0.35)
		(drill 0.15)
		(layers "F.Cu" "B.Cu")
		(remove_unused_layers yes)
		(keep_end_layers yes)
		(zone_layer_connections "In1.Cu" "In3.Cu" "In5.Cu" "In8.Cu" "In10.Cu" "In12.Cu")
		(net 417)
	)
	(via
		(at 180.690096 147.548958)
		(size 0.35)
		(drill 0.15)
		(layers "F.Cu" "B.Cu")
		(remove_unused_layers yes)
		(keep_end_layers yes)
		(zone_layer_connections "In1.Cu" "In3.Cu" "In4.Cu" "In5.Cu" "In8.Cu" "In10.Cu"
			"In12.Cu"
		)
		(net 417)
	)
	(via
		(at 199.3 135.1)
		(size 0.35)
		(drill 0.15)
		(layers "F.Cu" "B.Cu")
		(remove_unused_layers yes)
		(keep_end_layers yes)
		(zone_layer_connections "In1.Cu" "In3.Cu" "In5.Cu" "In8.Cu" "In10.Cu" "In12.Cu")
		(net 417)
	)
	(via
		(at 209.675 116.9)
		(size 0.35)
		(drill 0.15)
		(layers "F.Cu" "B.Cu")
		(remove_unused_layers yes)
		(keep_end_layers yes)
		(zone_layer_connections "In1.Cu" "In3.Cu" "In5.Cu" "In8.Cu" "In10.Cu" "In12.Cu")
		(net 417)
	)
	(via
		(at 177.205 127.967)
		(size 0.35)
		(drill 0.15)
		(layers "F.Cu" "B.Cu")
		(remove_unused_layers yes)
		(keep_end_layers yes)
		(zone_layer_connections "In1.Cu" "In3.Cu" "In5.Cu" "In8.Cu" "In10.Cu" "In12.Cu")
		(net 417)
	)
	(via
		(at 184.0035 134.7905)
		(size 0.35)
		(drill 0.15)
		(layers "F.Cu" "B.Cu")
		(remove_unused_layers yes)
		(keep_end_layers yes)
		(zone_layer_connections "In1.Cu" "In3.Cu" "In5.Cu" "In8.Cu" "In10.Cu" "In12.Cu")
		(net 417)
	)
	(via
		(at 219.132 117.704)
		(size 0.35)
		(drill 0.15)
		(layers "F.Cu" "B.Cu")
		(remove_unused_layers yes)
		(keep_end_layers yes)
		(zone_layer_connections "In1.Cu" "In3.Cu" "In5.Cu" "In8.Cu" "In10.Cu" "In12.Cu")
		(net 417)
	)
	(via
		(at 213.72 152.39)
		(size 0.35)
		(drill 0.15)
		(layers "F.Cu" "B.Cu")
		(remove_unused_layers yes)
		(keep_end_layers yes)
		(free yes)
		(zone_layer_connections "In1.Cu" "In3.Cu" "In5.Cu" "In8.Cu" "In10.Cu" "In12.Cu")
		(net 417)
	)
	(via
		(at 196.517074 119.303357)
		(size 0.35)
		(drill 0.15)
		(layers "F.Cu" "B.Cu")
		(remove_unused_layers yes)
		(keep_end_layers yes)
		(zone_layer_connections "In1.Cu" "In3.Cu" "In5.Cu" "In8.Cu" "In10.Cu" "In12.Cu")
		(net 417)
	)
	(via
		(at 195.25 149.054646)
		(size 0.35)
		(drill 0.15)
		(layers "F.Cu" "B.Cu")
		(remove_unused_layers yes)
		(keep_end_layers yes)
		(free yes)
		(zone_layer_connections "In1.Cu" "In3.Cu" "In5.Cu" "In8.Cu" "In10.Cu" "In12.Cu")
		(net 417)
	)
	(via
		(at 214.75 119.754)
		(size 0.35)
		(drill 0.15)
		(layers "F.Cu" "B.Cu")
		(remove_unused_layers yes)
		(keep_end_layers yes)
		(zone_layer_connections "In1.Cu" "In3.Cu" "In5.Cu" "In8.Cu" "In10.Cu" "In12.Cu")
		(net 417)
	)
	(via
		(at 197.7 133.5)
		(size 0.35)
		(drill 0.15)
		(layers "F.Cu" "B.Cu")
		(remove_unused_layers yes)
		(keep_end_layers yes)
		(zone_layer_connections "In1.Cu" "In3.Cu" "In5.Cu" "In8.Cu" "In10.Cu" "In12.Cu")
		(net 417)
	)
	(via
		(at 203.322 155.260999)
		(size 0.35)
		(drill 0.15)
		(layers "F.Cu" "B.Cu")
		(remove_unused_layers yes)
		(keep_end_layers yes)
		(free yes)
		(zone_layer_connections "In1.Cu" "In3.Cu" "In5.Cu" "In8.Cu" "In10.Cu" "In12.Cu")
		(net 417)
	)
	(via
		(at 218.6 131.65)
		(size 0.35)
		(drill 0.15)
		(layers "F.Cu" "B.Cu")
		(remove_unused_layers yes)
		(keep_end_layers yes)
		(zone_layer_connections "In1.Cu" "In3.Cu" "In5.Cu" "In8.Cu" "In10.Cu" "In12.Cu")
		(net 417)
	)
	(via
		(at 196.9 133.5)
		(size 0.35)
		(drill 0.15)
		(layers "F.Cu" "B.Cu")
		(remove_unused_layers yes)
		(keep_end_layers yes)
		(zone_layer_connections "In1.Cu" "In3.Cu" "In5.Cu" "In8.Cu" "In10.Cu" "In12.Cu")
		(net 417)
	)
	(via
		(at 181.6045 134.7905)
		(size 0.35)
		(drill 0.15)
		(layers "F.Cu" "B.Cu")
		(remove_unused_layers yes)
		(keep_end_layers yes)
		(zone_layer_connections "In1.Cu" "In3.Cu" "In5.Cu" "In8.Cu" "In10.Cu" "In12.Cu")
		(net 417)
	)
	(via
		(at 198.1 131.5)
		(size 0.35)
		(drill 0.15)
		(layers "F.Cu" "B.Cu")
		(remove_unused_layers yes)
		(keep_end_layers yes)
		(zone_layer_connections "In1.Cu" "In3.Cu" "In5.Cu" "In8.Cu" "In10.Cu" "In12.Cu")
		(net 417)
	)
	(via
		(at 189.072 154.501)
		(size 0.35)
		(drill 0.15)
		(layers "F.Cu" "B.Cu")
		(remove_unused_layers yes)
		(keep_end_layers yes)
		(zone_layer_connections "In1.Cu" "In3.Cu" "In5.Cu" "In8.Cu" "In10.Cu" "In12.Cu")
		(net 417)
	)
	(via
		(at 197.318542 152.330047)
		(size 0.35)
		(drill 0.15)
		(layers "F.Cu" "B.Cu")
		(remove_unused_layers yes)
		(keep_end_layers yes)
		(free yes)
		(zone_layer_connections "In1.Cu" "In3.Cu" "In5.Cu" "In8.Cu" "In10.Cu" "In12.Cu")
		(net 417)
	)
	(via
		(at 192.15 120.8)
		(size 0.35)
		(drill 0.15)
		(layers "F.Cu" "B.Cu")
		(remove_unused_layers yes)
		(keep_end_layers yes)
		(zone_layer_connections "In1.Cu" "In3.Cu" "In5.Cu" "In8.Cu" "In10.Cu" "In12.Cu")
		(net 417)
	)
	(via
		(at 205.2 116.491063)
		(size 0.35)
		(drill 0.15)
		(layers "F.Cu" "B.Cu")
		(remove_unused_layers yes)
		(keep_end_layers yes)
		(zone_layer_connections "In1.Cu" "In3.Cu" "In5.Cu" "In8.Cu" "In10.Cu" "In12.Cu")
		(net 417)
	)
	(via
		(at 183.2045 122.4415)
		(size 0.35)
		(drill 0.15)
		(layers "F.Cu" "B.Cu")
		(remove_unused_layers yes)
		(keep_end_layers yes)
		(zone_layer_connections "In1.Cu" "In3.Cu" "In5.Cu" "In8.Cu" "In10.Cu" "In12.Cu")
		(net 417)
	)
	(via
		(at 205.649 146.101)
		(size 0.35)
		(drill 0.15)
		(layers "F.Cu" "B.Cu")
		(remove_unused_layers yes)
		(keep_end_layers yes)
		(zone_layer_connections "In1.Cu" "In3.Cu" "In5.Cu" "In8.Cu" "In10.Cu" "In12.Cu")
		(net 417)
	)
	(via
		(at 214.97 152.39)
		(size 0.35)
		(drill 0.15)
		(layers "F.Cu" "B.Cu")
		(remove_unused_layers yes)
		(keep_end_layers yes)
		(free yes)
		(zone_layer_connections "In1.Cu" "In3.Cu" "In5.Cu" "In8.Cu" "In10.Cu" "In12.Cu")
		(net 417)
	)
	(via
		(at 205.718542 152.330047)
		(size 0.35)
		(drill 0.15)
		(layers "F.Cu" "B.Cu")
		(remove_unused_layers yes)
		(keep_end_layers yes)
		(free yes)
		(zone_layer_connections "In1.Cu" "In3.Cu" "In5.Cu" "In8.Cu" "In10.Cu" "In12.Cu")
		(net 417)
	)
	(via
		(at 195.101 149.932273)
		(size 0.35)
		(drill 0.15)
		(layers "F.Cu" "B.Cu")
		(remove_unused_layers yes)
		(keep_end_layers yes)
		(free yes)
		(zone_layer_connections "In1.Cu" "In3.Cu" "In5.Cu" "In8.Cu" "In10.Cu" "In12.Cu")
		(net 417)
	)
	(via
		(at 202.9 141.101)
		(size 0.35)
		(drill 0.15)
		(layers "F.Cu" "B.Cu")
		(remove_unused_layers yes)
		(keep_end_layers yes)
		(zone_layer_connections "In1.Cu" "In3.Cu" "In5.Cu" "In8.Cu" "In10.Cu" "In12.Cu")
		(net 417)
	)
	(via
		(at 177.658427 147.772745)
		(size 0.35)
		(drill 0.15)
		(layers "F.Cu" "B.Cu")
		(remove_unused_layers yes)
		(keep_end_layers yes)
		(zone_layer_connections "In1.Cu" "In3.Cu" "In4.Cu" "In5.Cu" "In8.Cu" "In10.Cu"
			"In12.Cu"
		)
		(net 417)
	)
	(via
		(at 183.2045 136.7415)
		(size 0.35)
		(drill 0.15)
		(layers "F.Cu" "B.Cu")
		(remove_unused_layers yes)
		(keep_end_layers yes)
		(zone_layer_connections "In1.Cu" "In3.Cu" "In5.Cu" "In8.Cu" "In10.Cu" "In12.Cu")
		(net 417)
	)
	(via
		(at 198.57225 137.4625)
		(size 0.35)
		(drill 0.15)
		(layers "F.Cu" "B.Cu")
		(remove_unused_layers yes)
		(keep_end_layers yes)
		(zone_layer_connections "In1.Cu" "In3.Cu" "In5.Cu" "In8.Cu" "In10.Cu" "In12.Cu")
		(net 417)
	)
	(via
		(at 215.33 118.35)
		(size 0.35)
		(drill 0.15)
		(layers "F.Cu" "B.Cu")
		(remove_unused_layers yes)
		(keep_end_layers yes)
		(zone_layer_connections "In1.Cu" "In3.Cu" "In5.Cu" "In8.Cu" "In10.Cu" "In12.Cu")
		(net 417)
	)
	(via
		(at 180.375 137.675)
		(size 0.35)
		(drill 0.15)
		(layers "F.Cu" "B.Cu")
		(remove_unused_layers yes)
		(keep_end_layers yes)
		(zone_layer_connections "In1.Cu" "In3.Cu" "In4.Cu" "In5.Cu" "In8.Cu" "In10.Cu"
			"In11.Cu" "In12.Cu"
		)
		(net 417)
	)
	(via
		(at 213.4435 134.449)
		(size 0.35)
		(drill 0.15)
		(layers "F.Cu" "B.Cu")
		(remove_unused_layers yes)
		(keep_end_layers yes)
		(zone_layer_connections "In1.Cu" "In3.Cu" "In5.Cu" "In8.Cu" "In10.Cu" "In12.Cu")
		(net 417)
	)
	(via
		(at 198.925312 137.16117)
		(size 0.35)
		(drill 0.15)
		(layers "F.Cu" "B.Cu")
		(remove_unused_layers yes)
		(keep_end_layers yes)
		(zone_layer_connections "In1.Cu" "In3.Cu" "In5.Cu" "In8.Cu" "In10.Cu" "In12.Cu")
		(net 417)
	)
	(via
		(at 181.340096 153.198958)
		(size 0.35)
		(drill 0.15)
		(layers "F.Cu" "B.Cu")
		(remove_unused_layers yes)
		(keep_end_layers yes)
		(zone_layer_connections "In1.Cu" "In3.Cu" "In4.Cu" "In5.Cu" "In8.Cu" "In10.Cu"
			"In12.Cu"
		)
		(net 417)
	)
	(via
		(at 175.2 149.4)
		(size 0.35)
		(drill 0.15)
		(layers "F.Cu" "B.Cu")
		(remove_unused_layers yes)
		(keep_end_layers yes)
		(zone_layer_connections "In1.Cu" "In3.Cu" "In4.Cu" "In5.Cu" "In8.Cu" "In10.Cu"
			"In12.Cu"
		)
		(net 417)
	)
	(via
		(at 178.4045 124.3925)
		(size 0.35)
		(drill 0.15)
		(layers "F.Cu" "B.Cu")
		(remove_unused_layers yes)
		(keep_end_layers yes)
		(zone_layer_connections "In1.Cu" "In3.Cu" "In5.Cu" "In8.Cu" "In10.Cu" "In12.Cu")
		(net 417)
	)
	(via
		(at 216.116209 146.899261)
		(size 0.35)
		(drill 0.15)
		(layers "F.Cu" "B.Cu")
		(remove_unused_layers yes)
		(keep_end_layers yes)
		(zone_layer_connections "In1.Cu" "In3.Cu" "In5.Cu" "In8.Cu" "In10.Cu" "In12.Cu")
		(net 417)
	)
	(via
		(at 218.1 144.495)
		(size 0.35)
		(drill 0.15)
		(layers "F.Cu" "B.Cu")
		(remove_unused_layers yes)
		(keep_end_layers yes)
		(zone_layer_connections "In1.Cu" "In3.Cu" "In5.Cu" "In8.Cu" "In10.Cu" "In12.Cu")
		(net 417)
	)
	(via
		(at 217.365999 152.393)
		(size 0.35)
		(drill 0.15)
		(layers "F.Cu" "B.Cu")
		(remove_unused_layers yes)
		(keep_end_layers yes)
		(free yes)
		(zone_layer_connections "In1.Cu" "In3.Cu" "In5.Cu" "In8.Cu" "In10.Cu" "In12.Cu")
		(net 417)
	)
	(via
		(at 224.85 136.77)
		(size 0.35)
		(drill 0.15)
		(layers "F.Cu" "B.Cu")
		(remove_unused_layers yes)
		(keep_end_layers yes)
		(zone_layer_connections "In1.Cu" "In3.Cu" "In5.Cu" "In8.Cu" "In10.Cu" "In12.Cu")
		(net 417)
	)
	(via
		(at 194.9 125.101)
		(size 0.35)
		(drill 0.15)
		(layers "F.Cu" "B.Cu")
		(remove_unused_layers yes)
		(keep_end_layers yes)
		(zone_layer_connections "In1.Cu" "In3.Cu" "In5.Cu" "In8.Cu" "In10.Cu" "In12.Cu")
		(net 417)
	)
	(via
		(at 191.096666 150.750333)
		(size 0.35)
		(drill 0.15)
		(layers "F.Cu" "B.Cu")
		(remove_unused_layers yes)
		(keep_end_layers yes)
		(free yes)
		(zone_layer_connections "In1.Cu" "In3.Cu" "In5.Cu" "In8.Cu" "In10.Cu" "In12.Cu")
		(net 417)
	)
	(via
		(at 211.548 150.25)
		(size 0.35)
		(drill 0.15)
		(layers "F.Cu" "B.Cu")
		(remove_unused_layers yes)
		(keep_end_layers yes)
		(zone_layer_connections "In1.Cu" "In3.Cu" "In5.Cu" "In8.Cu" "In10.Cu" "In12.Cu")
		(net 417)
	)
	(via
		(at 184.0035 124.3925)
		(size 0.35)
		(drill 0.15)
		(layers "F.Cu" "B.Cu")
		(remove_unused_layers yes)
		(keep_end_layers yes)
		(zone_layer_connections "In1.Cu" "In3.Cu" "In5.Cu" "In8.Cu" "In10.Cu" "In12.Cu")
		(net 417)
	)
	(via
		(at 215.9 125)
		(size 0.35)
		(drill 0.15)
		(layers "F.Cu" "B.Cu")
		(remove_unused_layers yes)
		(keep_end_layers yes)
		(zone_layer_connections "In1.Cu" "In3.Cu" "In5.Cu" "In8.Cu" "In10.Cu" "In12.Cu")
		(net 417)
	)
	(via
		(at 199.88 142.85)
		(size 0.35)
		(drill 0.15)
		(layers "F.Cu" "B.Cu")
		(remove_unused_layers yes)
		(keep_end_layers yes)
		(zone_layer_connections "In1.Cu" "In3.Cu" "In5.Cu" "In8.Cu" "In10.Cu" "In12.Cu")
		(net 417)
	)
	(via
		(at 221.864 152.719)
		(size 0.35)
		(drill 0.15)
		(layers "F.Cu" "B.Cu")
		(remove_unused_layers yes)
		(keep_end_layers yes)
		(zone_layer_connections "In1.Cu" "In3.Cu" "In5.Cu" "In8.Cu" "In10.Cu" "In12.Cu")
		(net 417)
	)
	(via
		(at 209.35 142.2)
		(size 0.35)
		(drill 0.15)
		(layers "F.Cu" "B.Cu")
		(remove_unused_layers yes)
		(keep_end_layers yes)
		(free yes)
		(zone_layer_connections "In1.Cu" "In3.Cu" "In5.Cu" "In8.Cu" "In10.Cu" "In12.Cu")
		(net 417)
	)
	(via
		(at 200.922 155.260999)
		(size 0.35)
		(drill 0.15)
		(layers "F.Cu" "B.Cu")
		(remove_unused_layers yes)
		(keep_end_layers yes)
		(free yes)
		(zone_layer_connections "In1.Cu" "In3.Cu" "In5.Cu" "In8.Cu" "In10.Cu" "In12.Cu")
		(net 417)
	)
	(via
		(at 209.494501 152.0945)
		(size 0.35)
		(drill 0.15)
		(layers "F.Cu" "B.Cu")
		(remove_unused_layers yes)
		(keep_end_layers yes)
		(free yes)
		(zone_layer_connections "In1.Cu" "In3.Cu" "In5.Cu" "In8.Cu" "In10.Cu" "In12.Cu")
		(net 417)
	)
	(via
		(at 181.6045 128.9415)
		(size 0.35)
		(drill 0.15)
		(layers "F.Cu" "B.Cu")
		(remove_unused_layers yes)
		(keep_end_layers yes)
		(zone_layer_connections "In1.Cu" "In3.Cu" "In5.Cu" "In8.Cu" "In10.Cu" "In12.Cu")
		(net 417)
	)
	(via
		(at 223.525 122.075)
		(size 0.35)
		(drill 0.15)
		(layers "F.Cu" "B.Cu")
		(remove_unused_layers yes)
		(keep_end_layers yes)
		(zone_layer_connections "In1.Cu" "In3.Cu" "In5.Cu" "In8.Cu" "In10.Cu" "In12.Cu")
		(net 417)
	)
	(via
		(at 224.75 141.8)
		(size 0.35)
		(drill 0.15)
		(layers "F.Cu" "B.Cu")
		(remove_unused_layers yes)
		(keep_end_layers yes)
		(zone_layer_connections "In3.Cu" "In5.Cu" "In8.Cu" "In10.Cu" "In12.Cu")
		(net 417)
	)
	(via
		(at 202.1 137.901)
		(size 0.35)
		(drill 0.15)
		(layers "F.Cu" "B.Cu")
		(remove_unused_layers yes)
		(keep_end_layers yes)
		(zone_layer_connections "In1.Cu" "In3.Cu" "In5.Cu" "In8.Cu" "In10.Cu" "In12.Cu")
		(net 417)
	)
	(via
		(at 204.518542 152.330047)
		(size 0.35)
		(drill 0.15)
		(layers "F.Cu" "B.Cu")
		(remove_unused_layers yes)
		(keep_end_layers yes)
		(free yes)
		(zone_layer_connections "In1.Cu" "In3.Cu" "In5.Cu" "In8.Cu" "In10.Cu" "In12.Cu")
		(net 417)
	)
	(via
		(at 176.0045 133.5)
		(size 0.35)
		(drill 0.15)
		(layers "F.Cu" "B.Cu")
		(remove_unused_layers yes)
		(keep_end_layers yes)
		(zone_layer_connections "In1.Cu" "In3.Cu" "In5.Cu" "In8.Cu" "In10.Cu" "In12.Cu")
		(net 417)
	)
	(via
		(at 215.4425 131.647)
		(size 0.35)
		(drill 0.15)
		(layers "F.Cu" "B.Cu")
		(remove_unused_layers yes)
		(keep_end_layers yes)
		(zone_layer_connections "In1.Cu" "In3.Cu" "In5.Cu" "In8.Cu" "In10.Cu" "In12.Cu")
		(net 417)
	)
	(via
		(at 197.72 116.6)
		(size 0.35)
		(drill 0.15)
		(layers "F.Cu" "B.Cu")
		(remove_unused_layers yes)
		(keep_end_layers yes)
		(zone_layer_connections "In1.Cu" "In3.Cu" "In5.Cu" "In8.Cu" "In10.Cu" "In12.Cu")
		(net 417)
	)
	(via
		(at 206.11 134.74)
		(size 0.35)
		(drill 0.15)
		(layers "F.Cu" "B.Cu")
		(remove_unused_layers yes)
		(keep_end_layers yes)
		(zone_layer_connections "In1.Cu" "In3.Cu" "In5.Cu" "In8.Cu" "In10.Cu" "In12.Cu")
		(net 417)
	)
	(via
		(at 181.440096 147.348958)
		(size 0.35)
		(drill 0.15)
		(layers "F.Cu" "B.Cu")
		(remove_unused_layers yes)
		(keep_end_layers yes)
		(zone_layer_connections "In1.Cu" "In3.Cu" "In4.Cu" "In5.Cu" "In8.Cu" "In10.Cu"
			"In12.Cu"
		)
		(net 417)
	)
	(via
		(at 176.8035 122.4415)
		(size 0.35)
		(drill 0.15)
		(layers "F.Cu" "B.Cu")
		(remove_unused_layers yes)
		(keep_end_layers yes)
		(zone_layer_connections "In1.Cu" "In3.Cu" "In5.Cu" "In8.Cu" "In10.Cu" "In12.Cu")
		(net 417)
	)
	(via
		(at 214.947 139.2)
		(size 0.35)
		(drill 0.15)
		(layers "F.Cu" "B.Cu")
		(remove_unused_layers yes)
		(keep_end_layers yes)
		(zone_layer_connections "In1.Cu" "In3.Cu" "In5.Cu" "In8.Cu" "In10.Cu" "In12.Cu")
		(net 417)
	)
	(via
		(at 179.375 141.9375)
		(size 0.35)
		(drill 0.15)
		(layers "F.Cu" "B.Cu")
		(remove_unused_layers yes)
		(keep_end_layers yes)
		(zone_layer_connections "In1.Cu" "In3.Cu" "In4.Cu" "In5.Cu" "In8.Cu" "In10.Cu"
			"In11.Cu" "In12.Cu"
		)
		(net 417)
	)
	(via
		(at 210.2 142.65)
		(size 0.35)
		(drill 0.15)
		(layers "F.Cu" "B.Cu")
		(remove_unused_layers yes)
		(keep_end_layers yes)
		(zone_layer_connections "In1.Cu" "In3.Cu" "In5.Cu" "In8.Cu" "In10.Cu" "In12.Cu")
		(net 417)
	)
	(via
		(at 199.722 155.260999)
		(size 0.35)
		(drill 0.15)
		(layers "F.Cu" "B.Cu")
		(remove_unused_layers yes)
		(keep_end_layers yes)
		(free yes)
		(zone_layer_connections "In1.Cu" "In3.Cu" "In5.Cu" "In8.Cu" "In10.Cu" "In12.Cu")
		(net 417)
	)
	(via
		(at 193.13 149.06)
		(size 0.35)
		(drill 0.15)
		(layers "F.Cu" "B.Cu")
		(remove_unused_layers yes)
		(keep_end_layers yes)
		(free yes)
		(zone_layer_connections "In1.Cu" "In3.Cu" "In5.Cu" "In8.Cu" "In10.Cu" "In12.Cu")
		(net 417)
	)
	(via
		(at 212.18 122.6)
		(size 0.35)
		(drill 0.15)
		(layers "F.Cu" "B.Cu")
		(remove_unused_layers yes)
		(keep_end_layers yes)
		(zone_layer_connections "In1.Cu" "In3.Cu" "In5.Cu" "In8.Cu" "In10.Cu" "In12.Cu")
		(net 417)
	)
	(via
		(at 175.475 142.4835)
		(size 0.35)
		(drill 0.15)
		(layers "F.Cu" "B.Cu")
		(remove_unused_layers yes)
		(keep_end_layers yes)
		(zone_layer_connections "In1.Cu" "In3.Cu" "In4.Cu" "In5.Cu" "In8.Cu" "In10.Cu"
			"In11.Cu" "In12.Cu"
		)
		(net 417)
	)
	(via
		(at 206.924226 152.020641)
		(size 0.35)
		(drill 0.15)
		(layers "F.Cu" "B.Cu")
		(remove_unused_layers yes)
		(keep_end_layers yes)
		(zone_layer_connections "In1.Cu" "In3.Cu" "In5.Cu" "In8.Cu" "In10.Cu" "In12.Cu")
		(net 417)
	)
	(via
		(at 204.519 153.711)
		(size 0.35)
		(drill 0.15)
		(layers "F.Cu" "B.Cu")
		(remove_unused_layers yes)
		(keep_end_layers yes)
		(free yes)
		(zone_layer_connections "In1.Cu" "In3.Cu" "In5.Cu" "In8.Cu" "In10.Cu" "In12.Cu")
		(net 417)
	)
	(via
		(at 182.984404 149.204531)
		(size 0.35)
		(drill 0.15)
		(layers "F.Cu" "B.Cu")
		(remove_unused_layers yes)
		(keep_end_layers yes)
		(zone_layer_connections "In1.Cu" "In3.Cu" "In4.Cu" "In5.Cu" "In8.Cu" "In10.Cu"
			"In12.Cu"
		)
		(net 417)
	)
	(via
		(at 210.7 120.75)
		(size 0.35)
		(drill 0.15)
		(layers "F.Cu" "B.Cu")
		(remove_unused_layers yes)
		(keep_end_layers yes)
		(free yes)
		(zone_layer_connections "In1.Cu" "In3.Cu" "In5.Cu" "In8.Cu" "In10.Cu" "In12.Cu")
		(net 417)
	)
	(via
		(at 190.9 144.5)
		(size 0.35)
		(drill 0.15)
		(layers "F.Cu" "B.Cu")
		(remove_unused_layers yes)
		(keep_end_layers yes)
		(zone_layer_connections "In1.Cu" "In3.Cu" "In5.Cu" "In8.Cu" "In10.Cu" "In12.Cu")
		(net 417)
	)
	(via
		(at 223.414 155.345)
		(size 0.35)
		(drill 0.15)
		(layers "F.Cu" "B.Cu")
		(remove_unused_layers yes)
		(keep_end_layers yes)
		(zone_layer_connections "In1.Cu" "In3.Cu" "In5.Cu" "In8.Cu" "In10.Cu" "In12.Cu")
		(net 417)
	)
	(via
		(at 193.299 136.301)
		(size 0.35)
		(drill 0.15)
		(layers "F.Cu" "B.Cu")
		(remove_unused_layers yes)
		(keep_end_layers yes)
		(zone_layer_connections "In1.Cu" "In3.Cu" "In5.Cu" "In8.Cu" "In10.Cu" "In12.Cu")
		(net 417)
	)
	(segment
		(start 205.722 155.260999)
		(end 205.722 154.171)
		(width 0.15)
		(layer "B.Cu")
		(net 417)
	)
	(segment
		(start 206.68 147.85)
		(end 206.68 148.596)
		(width 0.15)
		(layer "B.Cu")
		(net 417)
	)
	(segment
		(start 191.912 146.938)
		(end 191.7 147.15)
		(width 0.256)
		(layer "B.Cu")
		(net 417)
	)
	(segment
		(start 209.797 120.171)
		(end 209.797 119.472)
		(width 0.256)
		(layer "B.Cu")
		(net 417)
	)
	(segment
		(start 197.722 120.171)
		(end 197.722 119.305283)
		(width 0.2)
		(layer "B.Cu")
		(net 417)
	)
	(segment
		(start 194.63 145.3)
		(end 195.24 145.3)
		(width 0.256)
		(layer "B.Cu")
		(net 417)
	)
	(segment
		(start 204.522 155.260999)
		(end 204.522 154.171)
		(width 0.15)
		(layer "B.Cu")
		(net 417)
	)
	(segment
		(start 223.75 122.3)
		(end 223.75 122.52)
		(width 0.2)
		(layer "B.Cu")
		(net 417)
	)
	(segment
		(start 192.521 151.462)
		(end 192.521 152.342585)
		(width 0.201)
		(layer "B.Cu")
		(net 417)
	)
	(segment
		(start 222.575 147.531369)
		(end 222.696369 147.41)
		(width 0.4)
		(layer "B.Cu")
		(net 417)
	)
	(segment
		(start 200.922 154.176)
		(end 200.917 154.171)
		(width 0.15)
		(layer "B.Cu")
		(net 417)
	)
	(segment
		(start 198.411 150.87)
		(end 197.43 150.87)
		(width 0.15)
		(layer "B.Cu")
		(net 417)
	)
	(segment
		(start 216.35 122.45)
		(end 216.35 121.75)
		(width 0.2)
		(layer "B.Cu")
		(net 417)
	)
	(segment
		(start 191.589 137.101)
		(end 191.71 136.98)
		(width 0.4)
		(layer "B.Cu")
		(net 417)
	)
	(segment
		(start 201.75 145.416)
		(end 201.75 145.452)
		(width 0.201)
		(layer "B.Cu")
		(net 417)
	)
	(segment
		(start 219.431 121.754)
		(end 219.385 121.8)
		(width 0.35)
		(layer "B.Cu")
		(net 417)
	)
	(segment
		(start 205.2 116.491063)
		(end 204.922 116.769063)
		(width 0.184)
		(layer "B.Cu")
		(net 417)
	)
	(segment
		(start 191.321 151.462)
		(end 191.321 152.327589)
		(width 0.201)
		(layer "B.Cu")
		(net 417)
	)
	(segment
		(start 189.25 119.5)
		(end 189.25 120.168)
		(width 0.256)
		(layer "B.Cu")
		(net 417)
	)
	(segment
		(start 225.8425 146.32)
		(end 225.8425 142.3575)
		(width 0.256)
		(layer "B.Cu")
		(net 417)
	)
	(segment
		(start 189.25 120.168)
		(end 189.247 120.171)
		(width 0.256)
		(layer "B.Cu")
		(net 417)
	)
	(segment
		(start 195.71 127.61)
		(end 195.71 129.1)
		(width 0.4)
		(layer "B.Cu")
		(net 417)
	)
	(segment
		(start 206.16438 147.726)
		(end 205.84838 147.41)
		(width 0.1)
		(layer "B.Cu")
		(net 417)
	)
	(segment
		(start 192.8095 133.5895)
		(end 193.119 133.28)
		(width 0.4)
		(layer "B.Cu")
		(net 417)
	)
	(segment
		(start 202.113542 151.464458)
		(end 202.116 151.462)
		(width 0.201)
		(layer "B.Cu")
		(net 417)
	)
	(segment
		(start 223.882 130.55)
		(end 223.882 131.587)
		(width 0.174)
		(layer "B.Cu")
		(net 417)
	)
	(segment
		(start 204.518542 151.464458)
		(end 204.521 151.462)
		(width 0.201)
		(layer "B.Cu")
		(net 417)
	)
	(segment
		(start 209.797 117.461)
		(end 209.797 117.022)
		(width 0.256)
		(layer "B.Cu")
		(net 417)
	)
	(segment
		(start 219.431 123.8)
		(end 219.431 122.811)
		(width 0.2)
		(layer "B.Cu")
		(net 417)
	)
	(segment
		(start 216.477 146.300054)
		(end 216.026946 145.85)
		(width 0.174)
		(layer "B.Cu")
		(net 417)
	)
	(segment
		(start 198.922 116.75)
		(end 198.922 117.461)
		(width 0.184)
		(layer "B.Cu")
		(net 417)
	)
	(segment
		(start 219.431 116.704)
		(end 219.431 117.704)
		(width 0.2)
		(layer "B.Cu")
		(net 417)
	)
	(segment
		(start 223.895 131.6)
		(end 223.882 131.587)
		(width 0.256)
		(layer "B.Cu")
		(net 417)
	)
	(segment
		(start 208.65 155.24)
		(end 208.65 155.25)
		(width 0.15)
		(layer "B.Cu")
		(net 417)
	)
	(segment
		(start 195.85 127.47)
		(end 195.784 127.404)
		(width 0.4)
		(layer "B.Cu")
		(net 417)
	)
	(segment
		(start 221.03 142.14)
		(end 220.76 141.87)
		(width 0.09)
		(layer "B.Cu")
		(net 417)
	)
	(segment
		(start 177.68 147.86)
		(end 177.65 147.83)
		(width 0.2)
		(layer "B.Cu")
		(net 417)
	)
	(segment
		(start 215.5085 131.713)
		(end 215.4425 131.647)
		(width 0.174)
		(layer "B.Cu")
		(net 417)
	)
	(segment
		(start 196.122 151.461)
		(end 196.122 151.907)
		(width 0.201)
		(layer "B.Cu")
		(net 417)
	)
	(segment
		(start 213.865 147.1)
		(end 213.9 147.065)
		(width 0.174)
		(layer "B.Cu")
		(net 417)
	)
	(segment
		(start 194.922 151.907)
		(end 194.922 151.461)
		(width 0.201)
		(layer "B.Cu")
		(net 417)
	)
	(segment
		(start 219.645 144.495)
		(end 219.725 144.415)
		(width 0.177)
		(layer "B.Cu")
		(net 417)
	)
	(segment
		(start 201.32 119.302963)
		(end 201.319534 119.302497)
		(width 0.2)
		(layer "B.Cu")
		(net 417)
	)
	(segment
		(start 175.7 148.9)
		(end 175.7 148.88)
		(width 0.2)
		(layer "B.Cu")
		(net 417)
	)
	(segment
		(start 180.05 134.016)
		(end 179.2035 134.1415)
		(width 0.4)
		(layer "B.Cu")
		(net 417)
	)
	(segment
		(start 202.117 155.260999)
		(end 202.1195 155.258499)
		(width 0.145)
		(layer "B.Cu")
		(net 417)
	)
	(segment
		(start 192.8 135.52)
		(end 192.8 135.802)
		(width 0.4)
		(layer "B.Cu")
		(net 417)
	)
	(segment
		(start 198.975 122.18)
		(end 198.975 122.775)
		(width 0.4)
		(layer "B.Cu")
		(net 417)
	)
	(segment
		(start 197.722 116.602)
		(end 197.722 117.461)
		(width 0.184)
		(layer "B.Cu")
		(net 417)
	)
	(segment
		(start 193.718542 152.330047)
		(end 193.718542 151.464458)
		(width 0.2)
		(layer "B.Cu")
		(net 417)
	)
	(segment
		(start 202.1195 154.1735)
		(end 202.117 154.171)
		(width 0.145)
		(layer "B.Cu")
		(net 417)
	)
	(segment
		(start 206.922 116.491063)
		(end 206.922 117.461)
		(width 0.125)
		(layer "B.Cu")
		(net 417)
	)
	(segment
		(start 221.87 121.55)
		(end 222.75 122.43)
		(width 0.2)
		(layer "B.Cu")
		(net 417)
	)
	(segment
		(start 196.09 137.15)
		(end 198.934 137.15)
		(width 0.4)
		(layer "B.Cu")
		(net 417)
	)
	(segment
		(start 202.73 125.7)
		(end 202.73 125.271)
		(width 0.4)
		(layer "B.Cu")
		(net 417)
	)
	(segment
		(start 223.880974 147.794026)
		(end 221.951526 147.794026)
		(width 0.4)
		(layer "B.Cu")
		(net 417)
	)
	(segment
		(start 220.5425 150.775)
		(end 219.841 150.775)
		(width 0.174)
		(layer "B.Cu")
		(net 417)
	)
	(segment
		(start 194.35 145.02)
		(end 194.63 145.3)
		(width 0.256)
		(layer "B.Cu")
		(net 417)
	)
	(segment
		(start 200.922 155.260999)
		(end 200.922 154.176)
		(width 0.15)
		(layer "B.Cu")
		(net 417)
	)
	(segment
		(start 198.54575 137.436)
		(end 198.57225 137.4625)
		(width 0.4)
		(layer "B.Cu")
		(net 417)
	)
	(segment
		(start 223.9 147.775)
		(end 223.880974 147.794026)
		(width 0.4)
		(layer "B.Cu")
		(net 417)
	)
	(segment
		(start 185.75 122.35)
		(end 185.75 121.33)
		(width 0.15)
		(layer "B.Cu")
		(net 417)
	)
	(segment
		(start 194.9 125.686)
		(end 194.816 125.77)
		(width 0.4)
		(layer "B.Cu")
		(net 417)
	)
	(segment
		(start 222.35 126.435)
		(end 222.26 126.435)
		(width 0.2)
		(layer "B.Cu")
		(net 417)
	)
	(segment
		(start 208.122 116.491063)
		(end 208.122 117.461)
		(width 0.125)
		(layer "B.Cu")
		(net 417)
	)
	(segment
		(start 207.15 136.35)
		(end 207.77 136.35)
		(width 0.14)
		(layer "B.Cu")
		(net 417)
	)
	(segment
		(start 223.9 131.6)
		(end 223.895 131.6)
		(width 0.256)
		(layer "B.Cu")
		(net 417)
	)
	(segment
		(start 221.15 138.8)
		(end 221.15 138.7755)
		(width 0.256)
		(layer "B.Cu")
		(net 417)
	)
	(segment
		(start 206.702 148.578)
		(end 206.63 148.65)
		(width 0.256)
		(layer "B.Cu")
		(net 417)
	)
	(segment
		(start 200.75 148.68)
		(end 200.697 148.627)
		(width 0.256)
		(layer "B.Cu")
		(net 417)
	)
	(segment
		(start 215.6 143.65)
		(end 216 144.05)
		(width 0.174)
		(layer "B.Cu")
		(net 417)
	)
	(segment
		(start 204.49 129.892)
		(end 204.499 129.901)
		(width 0.4)
		(layer "B.Cu")
		(net 417)
	)
	(segment
		(start 204.518542 152.330047)
		(end 204.518542 151.464458)
		(width 0.201)
		(layer "B.Cu")
		(net 417)
	)
	(segment
		(start 180.8055 125.0425)
		(end 180 125.534)
		(width 0.4)
		(layer "B.Cu")
		(net 417)
	)
	(segment
		(start 194.922 120.171)
		(end 194.908 120.157)
		(width 0.2)
		(layer "B.Cu")
		(net 417)
	)
	(segment
		(start 214.75 119.754)
		(end 214.341 119.754)
		(width 0.35)
		(layer "B.Cu")
		(net 417)
	)
	(segment
		(start 197.04 133.27)
		(end 199.89 133.27)
		(width 0.4)
		(layer "B.Cu")
		(net 417)
	)
	(segment
		(start 220.9575 147.92263)
		(end 220.9575 147.775)
		(width 0.256)
		(layer "B.Cu")
		(net 417)
	)
	(segment
		(start 197.322 154.176)
		(end 197.317 154.171)
		(width 0.15)
		(layer "B.Cu")
		(net 417)
	)
	(segment
		(start 203.694 127.495)
		(end 203.699 127.5)
		(width 0.4)
		(layer "B.Cu")
		(net 417)
	)
	(segment
		(start 208.122 154.171)
		(end 208.122 153.498)
		(width 0.15)
		(layer "B.Cu")
		(net 417)
	)
	(segment
		(start 208.584 144.175)
		(end 208.584 143.65)
		(width 0.4)
		(layer "B.Cu")
		(net 417)
	)
	(segment
		(start 209.797 117.022)
		(end 209.675 116.9)
		(width 0.256)
		(layer "B.Cu")
		(net 417)
	)
	(segment
		(start 218.601 131.651)
		(end 218.601 132.25)
		(width 0.256)
		(layer "B.Cu")
		(net 417)
	)
	(segment
		(start 196.0375 151.9915)
		(end 195.0065 151.9915)
		(width 0.201)
		(layer "B.Cu")
		(net 417)
	)
	(segment
		(start 205.55 141.7)
		(end 205.056 141.7)
		(width 0.4)
		(layer "B.Cu")
		(net 417)
	)
	(segment
		(start 214.345 120.75)
		(end 214.341 120.754)
		(width 0.35)
		(layer "B.Cu")
		(net 417)
	)
	(segment
		(start 208.55 148.275)
		(end 209.316 148.275)
		(width 0.4)
		(layer "B.Cu")
		(net 417)
	)
	(segment
		(start 215.6925 131.713)
		(end 215.5085 131.713)
		(width 0.174)
		(layer "B.Cu")
		(net 417)
	)
	(segment
		(start 195.32 116.51)
		(end 195.32 117.458)
		(width 0.184)
		(layer "B.Cu")
		(net 417)
	)
	(segment
		(start 223.96 144.46)
		(end 224.313135 144.46)
		(width 0.09)
		(layer "B.Cu")
		(net 417)
	)
	(segment
		(start 199.864 131.304)
		(end 199.89 131.33)
		(width 0.4)
		(layer "B.Cu")
		(net 417)
	)
	(segment
		(start 197.322 155.260999)
		(end 197.322 154.176)
		(width 0.15)
		(layer "B.Cu")
		(net 417)
	)
	(segment
		(start 222.75 122.43)
		(end 222.75 122.52)
		(width 0.2)
		(layer "B.Cu")
		(net 417)
	)
	(segment
		(start 216.166946 146.91)
		(end 216.477 146.599946)
		(width 0.174)
		(layer "B.Cu")
		(net 417)
	)
	(segment
		(start 198.5235 127.8795)
		(end 199.3195 128.6755)
		(width 0.201)
		(layer "B.Cu")
		(net 417)
	)
	(segment
		(start 212.865 140.65)
		(end 212.431 140.65)
		(width 0.174)
		(layer "B.Cu")
		(net 417)
	)
	(segment
		(start 177.68 148.9)
		(end 177.68 147.86)
		(width 0.2)
		(layer "B.Cu")
		(net 417)
	)
	(segment
		(start 224.395 143.795936)
		(end 223.740064 143.141)
		(width 0.09)
		(layer "B.Cu")
		(net 417)
	)
	(segment
		(start 191.868 125.101)
		(end 191.868 126.012)
		(width 0.4)
		(layer "B.Cu")
		(net 417)
	)
	(segment
		(start 203.884 145.416)
		(end 205 145.416)
		(width 0.182)
		(layer "B.Cu")
		(net 417)
	)
	(segment
		(start 197.04 138.959)
		(end 197.28 138.719)
		(width 0.4)
		(layer "B.Cu")
		(net 417)
	)
	(segment
		(start 175.2 149.4)
		(end 175.7 148.9)
		(width 0.2)
		(layer "B.Cu")
		(net 417)
	)
	(segment
		(start 215.3895 131.7)
		(end 215.4425 131.647)
		(width 0.174)
		(layer "B.Cu")
		(net 417)
	)
	(segment
		(start 184.35 116.95)
		(end 185.25 116.95)
		(width 0.15)
		(layer "B.Cu")
		(net 417)
	)
	(segment
		(start 215.78 149.24)
		(end 215.44 149.24)
		(width 0.174)
		(layer "B.Cu")
		(net 417)
	)
	(segment
		(start 216.382499 152.2245)
		(end 216.382499 152.732499)
		(width 0.15)
		(layer "B.Cu")
		(net 417)
	)
	(segment
		(start 197.43 150.87)
		(end 197.317 150.983)
		(width 0.15)
		(layer "B.Cu")
		(net 417)
	)
	(segment
		(start 214.0925 132.197)
		(end 213.7085 132.697)
		(width 0.174)
		(layer "B.Cu")
		(net 417)
	)
	(segment
		(start 199.317074 119.497074)
		(end 199.317074 120.169074)
		(width 0.2)
		(layer "B.Cu")
		(net 417)
	)
	(segment
		(start 213.6925 131.681)
		(end 213.7085 131.681)
		(width 0.174)
		(layer "B.Cu")
		(net 417)
	)
	(segment
		(start 198.522 151.461)
		(end 198.522 150.981)
		(width 0.15)
		(layer "B.Cu")
		(net 417)
	)
	(segment
		(start 208.84 118.38)
		(end 208.7 118.38)
		(width 0.2)
		(layer "B.Cu")
		(net 417)
	)
	(segment
		(start 196.0755 130.4305)
		(end 196.0755 129.4655)
		(width 0.201)
		(layer "B.Cu")
		(net 417)
	)
	(segment
		(start 206.579 148.701)
		(end 206.63 148.65)
		(width 0.256)
		(layer "B.Cu")
		(net 417)
	)
	(segment
		(start 203.049 148.408)
		(end 202.732 148.725)
		(width 0.201)
		(layer "B.Cu")
		(net 417)
	)
	(segment
		(start 219.73 144.4275)
		(end 219.7375 144.42)
		(width 0.256)
		(layer "B.Cu")
		(net 417)
	)
	(segment
		(start 203.699 145.601)
		(end 203.884 145.416)
		(width 0.201)
		(layer "B.Cu")
		(net 417)
	)
	(segment
		(start 215.6925 130.713)
		(end 215.6765 130.697)
		(width 0.174)
		(layer "B.Cu")
		(net 417)
	)
	(segment
		(start 202.658625 116.683)
		(end 202.672017 116.683)
		(width 0.184)
		(layer "B.Cu")
		(net 417)
	)
	(segment
		(start 200.9245 128.6755)
		(end 201.3 128.3)
		(width 0.201)
		(layer "B.Cu")
		(net 417)
	)
	(segment
		(start 194.9 124.716)
		(end 194.444 124.26)
		(width 0.4)
		(layer "B.Cu")
		(net 417)
	)
	(segment
		(start 194.93 147.15)
		(end 194.85 147.23)
		(width 0.256)
		(layer "B.Cu")
		(net 417)
	)
	(segment
		(start 222.880974 147.794026)
		(end 222.575 147.794026)
		(width 0.4)
		(layer "B.Cu")
		(net 417)
	)
	(segment
		(start 217.15 121.75)
		(end 216.35 121.75)
		(width 0.2)
		(layer "B.Cu")
		(net 417)
	)
	(segment
		(start 209.2 145.45)
		(end 209.075 145.575)
		(width 0.4)
		(layer "B.Cu")
		(net 417)
	)
	(segment
		(start 197.299 139.353)
		(end 197.04 139.094)
		(width 0.4)
		(layer "B.Cu")
		(net 417)
	)
	(segment
		(start 222.575 147.794026)
		(end 222.575 147.531369)
		(width 0.4)
		(layer "B.Cu")
		(net 417)
	)
	(segment
		(start 200.109 139.11)
		(end 200.499 139.5)
		(width 0.4)
		(layer "B.Cu")
		(net 417)
	)
	(segment
		(start 195.85 127.47)
		(end 195.73 127.47)
		(width 0.4)
		(layer "B.Cu")
		(net 417)
	)
	(segment
		(start 220.939 143.105655)
		(end 220.939 142.657865)
		(width 0.09)
		(layer "B.Cu")
		(net 417)
	)
	(segment
		(start 182.05 119.85)
		(end 182.05 119.402)
		(width 0.1)
		(layer "B.Cu")
		(net 417)
	)
	(segment
		(start 224.313135 144.46)
		(end 224.395 144.378135)
		(width 0.09)
		(layer "B.Cu")
		(net 417)
	)
	(segment
		(start 218.6005 129.16)
		(end 218.6005 129.6495)
		(width 0.256)
		(layer "B.Cu")
		(net 417)
	)
	(segment
		(start 201.75 145.452)
		(end 202.399 146.101)
		(width 0.201)
		(layer "B.Cu")
		(net 417)
	)
	(segment
		(start 206.19 134.76)
		(end 206.445 135.015)
		(width 0.14)
		(layer "B.Cu")
		(net 417)
	)
	(segment
		(start 190.122 152.326589)
		(end 190.124458 152.329047)
		(width 0.201)
		(layer "B.Cu")
		(net 417)
	)
	(segment
		(start 221.880686 126.055686)
		(end 221.839137 126.055686)
		(width 0.2)
		(layer "B.Cu")
		(net 417)
	)
	(segment
		(start 198.6215 137.4625)
		(end 198.94 137.144)
		(width 0.4)
		(layer "B.Cu")
		(net 417)
	)
	(segment
		(start 213.899 150.05)
		(end 213.931 150.05)
		(width 0.174)
		(layer "B.Cu")
		(net 417)
	)
	(segment
		(start 197.04 139.094)
		(end 196.106 139.094)
		(width 0.4)
		(layer "B.Cu")
		(net 417)
	)
	(segment
		(start 208.584 143.65)
		(end 208.609 143.625)
		(width 0.4)
		(layer "B.Cu")
		(net 417)
	)
	(segment
		(start 214.6935 131.7)
		(end 213.9425 131.447)
		(width 0.174)
		(layer "B.Cu")
		(net 417)
	)
	(segment
		(start 216.026946 145.85)
		(end 215.881 145.85)
		(width 0.174)
		(layer "B.Cu")
		(net 417)
	)
	(segment
		(start 200.697 147.673)
		(end 200.92 147.45)
		(width 0.256)
		(layer "B.Cu")
		(net 417)
	)
	(segment
		(start 190.122 119.772)
		(end 190.122 120.171)
		(width 0.15)
		(layer "B.Cu")
		(net 417)
	)
	(segment
		(start 222.26 126.435)
		(end 221.880686 126.055686)
		(width 0.2)
		(layer "B.Cu")
		(net 417)
	)
	(segment
		(start 215.7095 129.668)
		(end 215.9635 129.922)
		(width 0.177)
		(layer "B.Cu")
		(net 417)
	)
	(segment
		(start 192.499 133.9)
		(end 192.8095 133.5895)
		(width 0.4)
		(layer "B.Cu")
		(net 417)
	)
	(segment
		(start 192.82 133.6)
		(end 192.82 134.27)
		(width 0.4)
		(layer "B.Cu")
		(net 417)
	)
	(segment
		(start 219.53 148.27)
		(end 219.53 148.325)
		(width 0.256)
		(layer "B.Cu")
		(net 417)
	)
	(segment
		(start 214.345 121.75)
		(end 214.341 121.754)
		(width 0.35)
		(layer "B.Cu")
		(net 417)
	)
	(segment
		(start 198.3 123.56)
		(end 198.25 123.51)
		(width 0.4)
		(layer "B.Cu")
		(net 417)
	)
	(segment
		(start 218.6 131.65)
		(end 218.601 131.651)
		(width 0.256)
		(layer "B.Cu")
		(net 417)
	)
	(segment
		(start 212.431 140.65)
		(end 212.415 140.666)
		(width 0.174)
		(layer "B.Cu")
		(net 417)
	)
	(segment
		(start 203.705 135.494)
		(end 203.699 135.5)
		(width 0.4)
		(layer "B.Cu")
		(net 417)
	)
	(segment
		(start 196.122 155.260999)
		(end 196.122 154.171)
		(width 0.15)
		(layer "B.Cu")
		(net 417)
	)
	(segment
		(start 199.1 119.28)
		(end 199.317074 119.497074)
		(width 0.2)
		(layer "B.Cu")
		(net 417)
	)
	(segment
		(start 185.25 116.95)
		(end 185.75 117.45)
		(width 0.15)
		(layer "B.Cu")
		(net 417)
	)
	(segment
		(start 194.35 144.45)
		(end 194.35 145.02)
		(width 0.256)
		(layer "B.Cu")
		(net 417)
	)
	(segment
		(start 215.625 121.75)
		(end 216.35 121.75)
		(width 0.2)
		(layer "B.Cu")
		(net 417)
	)
	(segment
		(start 204.49 129.25)
		(end 204.49 129.892)
		(width 0.4)
		(layer "B.Cu")
		(net 417)
	)
	(segment
		(start 208.604 143.58)
		(end 208.604 142.62)
		(width 0.4)
		(layer "B.Cu")
		(net 417)
	)
	(segment
		(start 197.304 126.701)
		(end 197.299 126.706)
		(width 0.4)
		(layer "B.Cu")
		(net 417)
	)
	(segment
		(start 203.049 148.051)
		(end 203.049 148.408)
		(width 0.201)
		(layer "B.Cu")
		(net 417)
	)
	(segment
		(start 206.11 134.74)
		(end 206.13 134.76)
		(width 0.14)
		(layer "B.Cu")
		(net 417)
	)
	(segment
		(start 199.3 133.5)
		(end 196.9 133.5)
		(width 0.4)
		(layer "B.Cu")
		(net 417)
	)
	(segment
		(start 186.475 154.905)
		(end 185.33 154.905)
		(width 0.2)
		(layer "B.Cu")
		(net 417)
	)
	(segment
		(start 219.431 118.704)
		(end 218.854 118.704)
		(width 0.35)
		(layer "B.Cu")
		(net 417)
	)
	(segment
		(start 220.965586 147.783086)
		(end 220.9575 147.775)
		(width 0.256)
		(layer "B.Cu")
		(net 417)
	)
	(segment
		(start 220.76 141.87)
		(end 220.59 141.87)
		(width 0.09)
		(layer "B.Cu")
		(net 417)
	)
	(segment
		(start 185.33 154.905)
		(end 185.325 154.91)
		(width 0.2)
		(layer "B.Cu")
		(net 417)
	)
	(segment
		(start 208.122 154.171)
		(end 208.122 154.712)
		(width 0.15)
		(layer "B.Cu")
		(net 417)
	)
	(segment
		(start 219.841 150.775)
		(end 219.6 150.534)
		(width 0.174)
		(layer "B.Cu")
		(net 417)
	)
	(segment
		(start 194.44 124.26)
		(end 194.44 123.26)
		(width 0.4)
		(layer "B.Cu")
		(net 417)
	)
	(segment
		(start 199.722 155.260999)
		(end 199.722 154.171)
		(width 0.15)
		(layer "B.Cu")
		(net 417)
	)
	(segment
		(start 206.556 147.726)
		(end 206.16438 147.726)
		(width 0.1)
		(layer "B.Cu")
		(net 417)
	)
	(segment
		(start 178.75 144.1425)
		(end 178.62 144.0125)
		(width 0.2)
		(layer "B.Cu")
		(net 417)
	)
	(segment
		(start 205.84838 147.41)
		(end 205.73 147.41)
		(width 0.1)
		(layer "B.Cu")
		(net 417)
	)
	(segment
		(start 198.522 155.260999)
		(end 198.522 154.171)
		(width 0.15)
		(layer "B.Cu")
		(net 417)
	)
	(segment
		(start 194.9 125.101)
		(end 194.9 124.716)
		(width 0.4)
		(layer "B.Cu")
		(net 417)
	)
	(segment
		(start 221.42987 148.395)
		(end 220.9575 147.92263)
		(width 0.256)
		(layer "B.Cu")
		(net 417)
	)
	(segment
		(start 202.917 116.927983)
		(end 202.917 117.461)
		(width 0.184)
		(layer "B.Cu")
		(net 417)
	)
	(segment
		(start 202.525625 116.55)
		(end 202.658625 116.683)
		(width 0.184)
		(layer "B.Cu")
		(net 417)
	)
	(segment
		(start 203.322 120.171)
		(end 203.322 119.305283)
		(width 0.2)
		(layer "B.Cu")
		(net 417)
	)
	(segment
		(start 198.522 150.981)
		(end 198.411 150.87)
		(width 0.15)
		(layer "B.Cu")
		(net 417)
	)
	(segment
		(start 209.797 151.792001)
		(end 209.797 151.461)
		(width 0.256)
		(layer "B.Cu")
		(net 417)
	)
	(segment
		(start 206.445 135.645)
		(end 207.15 136.35)
		(width 0.14)
		(layer "B.Cu")
		(net 417)
	)
	(segment
		(start 213.931 150.05)
		(end 214.915 149.066)
		(width 0.174)
		(layer "B.Cu")
		(net 417)
	)
	(segment
		(start 199.3195 128.6755)
		(end 200.9245 128.6755)
		(width 0.201)
		(layer "B.Cu")
		(net 417)
	)
	(segment
		(start 208.584 150.425)
		(end 208.584 144.175)
		(width 0.4)
		(layer "B.Cu")
		(net 417)
	)
	(segment
		(start 221.4255 134.8255)
		(end 221.4255 135.261)
		(width 0.1)
		(layer "B.Cu")
		(net 417)
	)
	(segment
		(start 191.322 154.171)
		(end 191.322 155.176999)
		(width 0.15)
		(layer "B.Cu")
		(net 417)
	)
	(segment
		(start 196.522 116.5)
		(end 196.522 117.461)
		(width 0.184)
		(layer "B.Cu")
		(net 417)
	)
	(segment
		(start 226.182 131.587)
		(end 226.195 131.6)
		(width 0.174)
		(layer "B.Cu")
		(net 417)
	)
	(segment
		(start 191.912 146.818)
		(end 191.912 146.938)
		(width 0.256)
		(layer "B.Cu")
		(net 417)
	)
	(segment
		(start 208.68 139.15)
		(end 208.68 138.22)
		(width 0.14)
		(layer "B.Cu")
		(net 417)
	)
	(segment
		(start 208.584 149.45)
		(end 209.35 149.45)
		(width 0.4)
		(layer "B.Cu")
		(net 417)
	)
	(segment
		(start 190.9 137.101)
		(end 191.589 137.101)
		(width 0.4)
		(layer "B.Cu")
		(net 417)
	)
	(segment
		(start 206.922 152.018415)
		(end 206.922 151.461)
		(width 0.1)
		(layer "B.Cu")
		(net 417)
	)
	(segment
		(start 204.922 116.769063)
		(end 204.922 117.461)
		(width 0.184)
		(layer "B.Cu")
		(net 417)
	)
	(segment
		(start 208.68 138.22)
		(end 208.7 138.2)
		(width 0.14)
		(layer "B.Cu")
		(net 417)
	)
	(segment
		(start 208.68 140.680001)
		(end 209.3 141.300001)
		(width 0.2)
		(layer "B.Cu")
		(net 417)
	)
	(segment
		(start 197.722 119.305283)
		(end 197.720074 119.303357)
		(width 0.2)
		(layer "B.Cu")
		(net 417)
	)
	(segment
		(start 205 145.416)
		(end 205 145.452)
		(width 0.182)
		(layer "B.Cu")
		(net 417)
	)
	(segment
		(start 224.395 144.378135)
		(end 224.395 143.795936)
		(width 0.09)
		(layer "B.Cu")
		(net 417)
	)
	(segment
		(start 191.321 152.327589)
		(end 191.323458 152.330047)
		(width 0.201)
		(layer "B.Cu")
		(net 417)
	)
	(segment
		(start 219.431 119.7234)
		(end 218.85 119.7234)
		(width 0.35)
		(layer "B.Cu")
		(net 417)
	)
	(segment
		(start 223.740064 143.141)
		(end 223.021133 143.141)
		(width 0.09)
		(layer "B.Cu")
		(net 417)
	)
	(segment
		(start 185.325 154.91)
		(end 185.11 154.91)
		(width 0.2)
		(layer "B.Cu")
		(net 417)
	)
	(segment
		(start 219.3916 120.7)
		(end 218.85 120.7)
		(width 0.35)
		(layer "B.Cu")
		(net 417)
	)
	(segment
		(start 202.184 137.1)
		(end 202.184 138.09)
		(width 0.4)
		(layer "B.Cu")
		(net 417)
	)
	(segment
		(start 192.521 152.342585)
		(end 192.529439 152.351024)
		(width 0.201)
		(layer "B.Cu")
		(net 417)
	)
	(segment
		(start 202.672017 116.683)
		(end 202.917 116.927983)
		(width 0.184)
		(layer "B.Cu")
		(net 417)
	)
	(segment
		(start 180.05 134.016)
		(end 180.8055 134.1415)
		(width 0.4)
		(layer "B.Cu")
		(net 417)
	)
	(segment
		(start 215.6925 131.713)
		(end 215.6925 130.713)
		(width 0.174)
		(layer "B.Cu")
		(net 417)
	)
	(segment
		(start 222.619999 141.86)
		(end 222.32 141.86)
		(width 0.09)
		(layer "B.Cu")
		(net 417)
	)
	(segment
		(start 197.04 131.304)
		(end 199.864 131.304)
		(width 0.4)
		(layer "B.Cu")
		(net 417)
	)
	(segment
		(start 191 143.291)
		(end 190.091 143.291)
		(width 0.125)
		(layer "B.Cu")
		(net 417)
	)
	(segment
		(start 206.445 135.015)
		(end 206.445 135.645)
		(width 0.14)
		(layer "B.Cu")
		(net 417)
	)
	(segment
		(start 211.0225 133.697)
		(end 211.7125 133.697)
		(width 0.256)
		(layer "B.Cu")
		(net 417)
	)
	(segment
		(start 219.53 148.325)
		(end 218.925 147.72)
		(width 0.256)
		(layer "B.Cu")
		(net 417)
	)
	(segment
		(start 209.8 154.174)
		(end 209.797 154.171)
		(width 0.1)
		(layer "B.Cu")
		(net 417)
	)
	(segment
		(start 206.299 148.701)
		(end 206.579 148.701)
		(width 0.256)
		(layer "B.Cu")
		(net 417)
	)
	(segment
		(start 193.722 155.260999)
		(end 193.722 154.171)
		(width 0.15)
		(layer "B.Cu")
		(net 417)
	)
	(segment
		(start 197.04 139.094)
		(end 197.04 138.959)
		(width 0.4)
		(layer "B.Cu")
		(net 417)
	)
	(segment
		(start 192.499 125.901)
		(end 191.979 125.901)
		(width 0.4)
		(layer "B.Cu")
		(net 417)
	)
	(segment
		(start 197.299 139.5)
		(end 197.299 139.353)
		(width 0.4)
		(layer "B.Cu")
		(net 417)
	)
	(segment
		(start 214.6935 131.7)
		(end 215.3895 131.7)
		(width 0.174)
		(layer "B.Cu")
		(net 417)
	)
	(segment
		(start 213.6925 131.681)
		(end 213.6925 132.681)
		(width 0.174)
		(layer "B.Cu")
		(net 417)
	)
	(segment
		(start 196.1 135.21)
		(end 196.09 135.2)
		(width 0.4)
		(layer "B.Cu")
		(net 417)
	)
	(segment
		(start 198.5235 127.1245)
		(end 198.5235 127.8795)
		(width 0.201)
		(layer "B.Cu")
		(net 417)
	)
	(segment
		(start 223.525 122.075)
		(end 223.75 122.3)
		(width 0.2)
		(layer "B.Cu")
		(net 417)
	)
	(segment
		(start 223.195 122.075)
		(end 222.75 122.52)
		(width 0.2)
		(layer "B.Cu")
		(net 417)
	)
	(segment
		(start 196.0755 129.4655)
		(end 195.71 129.1)
		(width 0.201)
		(layer "B.Cu")
		(net 417)
	)
	(segment
		(start 203.699 146.101)
		(end 203.699 145.601)
		(width 0.201)
		(layer "B.Cu")
		(net 417)
	)
	(segment
		(start 221.582 130.55)
		(end 221.582 131.587)
		(width 0.174)
		(layer "B.Cu")
		(net 417)
	)
	(segment
		(start 180.025 136.934)
		(end 179.2035 136.7415)
		(width 0.4)
		(layer "B.Cu")
		(net 417)
	)
	(segment
		(start 195.0065 151.9915)
		(end 194.922 151.907)
		(width 0.201)
		(layer "B.Cu")
		(net 417)
	)
	(segment
		(start 213.7085 131.681)
		(end 213.9425 131.447)
		(width 0.174)
		(layer "B.Cu")
		(net 417)
	)
	(segment
		(start 205.322926 120.169074)
		(end 205.322926 119.303357)
		(width 0.2)
		(layer "B.Cu")
		(net 417)
	)
	(segment
		(start 221.6 131.6)
		(end 221.595 131.6)
		(width 0.256)
		(layer "B.Cu")
		(net 417)
	)
	(segment
		(start 212.67 131.06)
		(end 213.287 131.677)
		(width 0.15)
		(layer "B.Cu")
		(net 417)
	)
	(segment
		(start 214.554562 143.634)
		(end 214.038562 144.15)
		(width 0.174)
		(layer "B.Cu")
		(net 417)
	)
	(segment
		(start 198 137.154)
		(end 197.99 137.144)
		(width 0.4)
		(layer "B.Cu")
		(net 417)
	)
	(segment
		(start 191.322 155.176999)
		(end 191.35 155.204999)
		(width 0.15)
		(layer "B.Cu")
		(net 417)
	)
	(segment
		(start 218.854 118.704)
		(end 218.85 118.7)
		(width 0.15)
		(layer "B.Cu")
		(net 417)
	)
	(segment
		(start 211.7125 132.697)
		(end 211.7125 134.697)
		(width 0.256)
		(layer "B.Cu")
		(net 417)
	)
	(segment
		(start 194.9 125.101)
		(end 194.9 125.686)
		(width 0.4)
		(layer "B.Cu")
		(net 417)
	)
	(segment
		(start 185.11 154.91)
		(end 184.1 153.9)
		(width 0.2)
		(layer "B.Cu")
		(net 417)
	)
	(segment
		(start 194.44 123.26)
		(end 194.43 123.25)
		(width 0.4)
		(layer "B.Cu")
		(net 417)
	)
	(segment
		(start 198.1 126.701)
		(end 197.304 126.701)
		(width 0.4)
		(layer "B.Cu")
		(net 417)
	)
	(segment
		(start 213.865 147.1)
		(end 213.931 147.034)
		(width 0.174)
		(layer "B.Cu")
		(net 417)
	)
	(segment
		(start 190.121 154.172)
		(end 190.121 155.261999)
		(width 0.1)
		(layer "B.Cu")
		(net 417)
	)
	(segment
		(start 213.361 122.774)
		(end 214.361 122.774)
		(width 0.2)
		(layer "B.Cu")
		(net 417)
	)
	(segment
		(start 221.03 142.566865)
		(end 221.03 142.14)
		(width 0.09)
		(layer "B.Cu")
		(net 417)
	)
	(segment
		(start 223.021133 143.141)
		(end 222.826888 142.946755)
		(width 0.09)
		(layer "B.Cu")
		(net 417)
	)
	(segment
		(start 214.038562 144.15)
		(end 213.915 144.15)
		(width 0.174)
		(layer "B.Cu")
		(net 417)
	)
	(segment
		(start 223.525 122.075)
		(end 223.195 122.075)
		(width 0.2)
		(layer "B.Cu")
		(net 417)
	)
	(segment
		(start 213.287 131.677)
		(end 213.6925 131.677)
		(width 0.15)
		(layer "B.Cu")
		(net 417)
	)
	(segment
		(start 214.865 147.034)
		(end 214.989 146.91)
		(width 0.174)
		(layer "B.Cu")
		(net 417)
	)
	(segment
		(start 202.73 125.271)
		(end 202.9 125.101)
		(width 0.4)
		(layer "B.Cu")
		(net 417)
	)
	(segment
		(start 196.106 139.094)
		(end 195.7 139.5)
		(width 0.4)
		(layer "B.Cu")
		(net 417)
	)
	(segment
		(start 202.113542 152.330047)
		(end 202.113542 151.464458)
		(width 0.201)
		(layer "B.Cu")
		(net 417)
	)
	(segment
		(start 206.9195 155.258499)
		(end 206.9195 154.1735)
		(width 0.145)
		(layer "B.Cu")
		(net 417)
	)
	(segment
		(start 196.517074 120.169074)
		(end 196.517074 119.303357)
		(width 0.2)
		(layer "B.Cu")
		(net 417)
	)
	(segment
		(start 202.9 133.101)
		(end 202.4 133.601)
		(width 0.4)
		(layer "B.Cu")
		(net 417)
	)
	(segment
		(start 217.361 121.961)
		(end 217.15 121.75)
		(width 0.2)
		(layer "B.Cu")
		(net 417)
	)
	(segment
		(start 201.32 120.171)
		(end 201.32 119.302963)
		(width 0.2)
		(layer "B.Cu")
		(net 417)
	)
	(segment
		(start 216.477 146.599946)
		(end 216.477 146.300054)
		(width 0.174)
		(layer "B.Cu")
		(net 417)
	)
	(segment
		(start 222.826888 142.946755)
		(end 222.77 142.889867)
		(width 0.09)
		(layer "B.Cu")
		(net 417)
	)
	(segment
		(start 196.122 152.326589)
		(end 196.118542 152.330047)
		(width 0.201)
		(layer "B.Cu")
		(net 417)
	)
	(segment
		(start 214.75 118.754)
		(end 214.341 118.754)
		(width 0.35)
		(layer "B.Cu")
		(net 417)
	)
	(segment
		(start 199.89 135.21)
		(end 196.1 135.21)
		(width 0.4)
		(layer "B.Cu")
		(net 417)
	)
	(segment
		(start 198.1 126.701)
		(end 198.5235 127.1245)
		(width 0.201)
		(layer "B.Cu")
		(net 417)
	)
	(segment
		(start 190.08 134.72)
		(end 190.1 134.7)
		(width 0.4)
		(layer "B.Cu")
		(net 417)
	)
	(segment
		(start 195.784 127.404)
		(end 195.784 126.8)
		(width 0.4)
		(layer "B.Cu")
		(net 417)
	)
	(segment
		(start 222.6994 117.1821)
		(end 222.5378 117.3437)
		(width 0.174)
		(layer "B.Cu")
		(net 417)
	)
	(segment
		(start 190.08 135.52)
		(end 190.08 134.72)
		(width 0.4)
		(layer "B.Cu")
		(net 417)
	)
	(segment
		(start 196.0995 137.5005)
		(end 196.164 137.436)
		(width 0.4)
		(layer "B.Cu")
		(net 417)
	)
	(segment
		(start 197.317 152.328505)
		(end 197.318542 152.330047)
		(width 0.2)
		(layer "B.Cu")
		(net 417)
	)
	(segment
		(start 182.05 119.402)
		(end 182.152 119.3)
		(width 0.1)
		(layer "B.Cu")
		(net 417)
	)
	(segment
		(start 205.718542 151.464458)
		(end 205.721 151.462)
		(width 0.201)
		(layer "B.Cu")
		(net 417)
	)
	(segment
		(start 217.98 141.08)
		(end 217.98 140.67)
		(width 0.15)
		(layer "B.Cu")
		(net 417)
	)
	(segment
		(start 206.25 141.7)
		(end 206.63 142.08)
		(width 0.4)
		(layer "B.Cu")
		(net 417)
	)
	(segment
		(start 196.64 147.15)
		(end 194.93 147.15)
		(width 0.256)
		(layer "B.Cu")
		(net 417)
	)
	(segment
		(start 226.182 130.55)
		(end 226.182 131.587)
		(width 0.174)
		(layer "B.Cu")
		(net 417)
	)
	(segment
		(start 216.382499 152.732499)
		(end 216.62 152.97)
		(width 0.15)
		(layer "B.Cu")
		(net 417)
	)
	(segment
		(start 205.55 141.7)
		(end 206.25 141.7)
		(width 0.4)
		(layer "B.Cu")
		(net 417)
	)
	(segment
		(start 198.3 123.45)
		(end 198.3 123.56)
		(width 0.4)
		(layer "B.Cu")
		(net 417)
	)
	(segment
		(start 209.322 117.898)
		(end 208.84 118.38)
		(width 0.2)
		(layer "B.Cu")
		(net 417)
	)
	(segment
		(start 222.77 142.889867)
		(end 222.77 142.010001)
		(width 0.09)
		(layer "B.Cu")
		(net 417)
	)
	(segment
		(start 177.7 134.584)
		(end 178.4035 134.7905)
		(width 0.4)
		(layer "B.Cu")
		(net 417)
	)
	(segment
		(start 196.122 151.907)
		(end 196.0375 151.9915)
		(width 0.201)
		(layer "B.Cu")
		(net 417)
	)
	(segment
		(start 203.699 147.401)
		(end 203.699 146.626)
		(width 0.201)
		(layer "B.Cu")
		(net 417)
	)
	(segment
		(start 214.75 120.75)
		(end 214.345 120.75)
		(width 0.35)
		(layer "B.Cu")
		(net 417)
	)
	(segment
		(start 208.122 154.712)
		(end 208.65 155.24)
		(width 0.15)
		(layer "B.Cu")
		(net 417)
	)
	(segment
		(start 197.317 150.983)
		(end 197.317 151.461)
		(width 0.15)
		(layer "B.Cu")
		(net 417)
	)
	(segment
		(start 192.8095 133.5895)
		(end 192.82 133.6)
		(width 0.4)
		(layer "B.Cu")
		(net 417)
	)
	(segment
		(start 200.697 148.627)
		(end 200.697 147.673)
		(width 0.256)
		(layer "B.Cu")
		(net 417)
	)
	(segment
		(start 199.91 139.11)
		(end 200.109 139.11)
		(width 0.4)
		(layer "B.Cu")
		(net 417)
	)
	(segment
		(start 196.164 137.436)
		(end 198.54575 137.436)
		(width 0.4)
		(layer "B.Cu")
		(net 417)
	)
	(segment
		(start 193.718542 151.464458)
		(end 193.721 151.462)
		(width 0.2)
		(layer "B.Cu")
		(net 417)
	)
	(segment
		(start 209.8 154.925)
		(end 209.8 154.174)
		(width 0.256)
		(layer "B.Cu")
		(net 417)
	)
	(segment
		(start 208.122 152.018415)
		(end 208.122 151.461)
		(width 0.1)
		(layer "B.Cu")
		(net 417)
	)
	(segment
		(start 215.44 149.24)
		(end 215.266 149.066)
		(width 0.174)
		(layer "B.Cu")
		(net 417)
	)
	(segment
		(start 190.091 143.291)
		(end 189.98 143.18)
		(width 0.125)
		(layer "B.Cu")
		(net 417)
	)
	(segment
		(start 218.6005 129.6495)
		(end 218.6 129.65)
		(width 0.256)
		(layer "B.Cu")
		(net 417)
	)
	(segment
		(start 219.431 120.7394)
		(end 219.3916 120.7)
		(width 0.35)
		(layer "B.Cu")
		(net 417)
	)
	(segment
		(start 199.3 133.5)
		(end 199.66 133.5)
		(width 0.4)
		(layer "B.Cu")
		(net 417)
	)
	(segment
		(start 224.33 148.205)
		(end 223.9 147.775)
		(width 0.4)
		(layer "B.Cu")
		(net 417)
	)
	(segment
		(start 194.908 120.157)
		(end 194.908 119.501)
		(width 0.2)
		(layer "B.Cu")
		(net 417)
	)
	(segment
		(start 208.68 139.15)
		(end 208.68 140.680001)
		(width 0.2)
		(layer "B.Cu")
		(net 417)
	)
	(segment
		(start 212.9325 152.7925)
		(end 213.14 153)
		(width 0.15)
		(layer "B.Cu")
		(net 417)
	)
	(segment
		(start 185 141.4475)
		(end 185.9325 141.4475)
		(width 0.15)
		(layer "B.Cu")
		(net 417)
	)
	(segment
		(start 180.025 136.934)
		(end 180.8055 136.7415)
		(width 0.4)
		(layer "B.Cu")
		(net 417)
	)
	(segment
		(start 198.975 122.775)
		(end 198.3 123.45)
		(width 0.4)
		(layer "B.Cu")
		(net 417)
	)
	(segment
		(start 198.934 137.15)
		(end 198.94 137.144)
		(width 0.4)
		(layer "B.Cu")
		(net 417)
	)
	(segment
		(start 198.296 123.56)
		(end 198.039 123.56)
		(width 0.4)
		(layer "B.Cu")
		(net 417)
	)
	(segment
		(start 192.8 135.802)
		(end 193.299 136.301)
		(width 0.4)
		(layer "B.Cu")
		(net 417)
	)
	(segment
		(start 193.292 129.1)
		(end 193.292 128.307)
		(width 0.4)
		(layer "B.Cu")
		(net 417)
	)
	(segment
		(start 189.247 151.461)
		(end 189.247 151.347)
		(width 0.1)
		(layer "B.Cu")
		(net 417)
	)
	(segment
		(start 216 144.05)
		(end 216.131 144.05)
		(width 0.174)
		(layer "B.Cu")
		(net 417)
	)
	(segment
		(start 195.89 130.616)
		(end 196.0755 130.4305)
		(width 0.201)
		(layer "B.Cu")
		(net 417)
	)
	(segment
		(start 208.122 153.498)
		(end 208.35 153.27)
		(width 0.15)
		(layer "B.Cu")
		(net 417)
	)
	(segment
		(start 224.33 148.33)
		(end 224.33 148.205)
		(width 0.4)
		(layer "B.Cu")
		(net 417)
	)
	(segment
		(start 202.4 133.601)
		(end 202.4 133.85)
		(width 0.4)
		(layer "B.Cu")
		(net 417)
	)
	(segment
		(start 208.124226 152.020641)
		(end 208.122 152.018415)
		(width 0.1)
		(layer "B.Cu")
		(net 417)
	)
	(segment
		(start 198 138.1)
		(end 198 137.154)
		(width 0.4)
		(layer "B.Cu")
		(net 417)
	)
	(segment
		(start 197.317 151.461)
		(end 197.317 152.328505)
		(width 0.2)
		(layer "B.Cu")
		(net 417)
	)
	(segment
		(start 192.46 146.27)
		(end 191.912 146.818)
		(width 0.256)
		(layer "B.Cu")
		(net 417)
	)
	(segment
		(start 212.9325 152.224501)
		(end 212.9325 152.7925)
		(width 0.15)
		(layer "B.Cu")
		(net 417)
	)
	(segment
		(start 215.361 122.014)
		(end 215.625 121.75)
		(width 0.2)
		(layer "B.Cu")
		(net 417)
	)
	(segment
		(start 192.522 154.171)
		(end 192.522 155.260999)
		(width 0.15)
		(layer "B.Cu")
		(net 417)
	)
	(segment
		(start 221.15 138.7755)
		(end 221.4255 138.5)
		(width 0.256)
		(layer "B.Cu")
		(net 417)
	)
	(segment
		(start 222.77 142.010001)
		(end 222.619999 141.86)
		(width 0.09)
		(layer "B.Cu")
		(net 417)
	)
	(segment
		(start 191.641 142.65)
		(end 191 143.291)
		(width 0.125)
		(layer "B.Cu")
		(net 417)
	)
	(segment
		(start 214.989 146.91)
		(end 216.166946 146.91)
		(width 0.174)
		(layer "B.Cu")
		(net 417)
	)
	(segment
		(start 206.68 148.596)
		(end 206.626 148.65)
		(width 0.15)
		(layer "B.Cu")
		(net 417)
	)
	(segment
		(start 209.322 117.461)
		(end 209.322 117.898)
		(width 0.2)
		(layer "B.Cu")
		(net 417)
	)
	(segment
		(start 222.9 147.775)
		(end 222.880974 147.794026)
		(width 0.4)
		(layer "B.Cu")
		(net 417)
	)
	(segment
		(start 206.917 155.260999)
		(end 206.9195 155.258499)
		(width 0.145)
		(layer "B.Cu")
		(net 417)
	)
	(segment
		(start 206.63 148.65)
		(end 206.63 149.621)
		(width 0.256)
		(layer "B.Cu")
		(net 417)
	)
	(segment
		(start 209.075 145.575)
		(end 208.6 145.575)
		(width 0.4)
		(layer "B.Cu")
		(net 417)
	)
	(segment
		(start 213.6925 132.681)
		(end 213.7085 132.697)
		(width 0.174)
		(layer "B.Cu")
		(net 417)
	)
	(segment
		(start 209.494501 152.0945)
		(end 209.797 151.792001)
		(width 0.256)
		(layer "B.Cu")
		(net 417)
	)
	(segment
		(start 217.361 122.45)
		(end 217.361 121.961)
		(width 0.2)
		(layer "B.Cu")
		(net 417)
	)
	(segment
		(start 190.122 151.461)
		(end 190.122 152.326589)
		(width 0.201)
		(layer "B.Cu")
		(net 417)
	)
	(segment
		(start 205 145.452)
		(end 205.649 146.101)
		(width 0.182)
		(layer "B.Cu")
		(net 417)
	)
	(segment
		(start 197.28 138.719)
		(end 197.299 138.719)
		(width 0.4)
		(layer "B.Cu")
		(net 417)
	)
	(segment
		(start 209.322 116.491063)
		(end 209.322 117.461)
		(width 0.125)
		(layer "B.Cu")
		(net 417)
	)
	(segment
		(start 194.922 155.260999)
		(end 194.922 154.171)
		(width 0.15)
		(layer "B.Cu")
		(net 417)
	)
	(segment
		(start 192.499 133.9)
		(end 192.499 133.949)
		(width 0.4)
		(layer "B.Cu")
		(net 417)
	)
	(segment
		(start 203.318542 151.464458)
		(end 203.321 151.462)
		(width 0.201)
		(layer "B.Cu")
		(net 417)
	)
	(segment
		(start 214.75 121.75)
		(end 214.345 121.75)
		(width 0.35)
		(layer "B.Cu")
		(net 417)
	)
	(segment
		(start 198.57225 137.4625)
		(end 198.6215 137.4625)
		(width 0.4)
		(layer "B.Cu")
		(net 417)
	)
	(segment
		(start 224.15 141.05)
		(end 224.15 140.75)
		(width 0.15)
		(layer "B.Cu")
		(net 417)
	)
	(segment
		(start 186.25 141.13)
		(end 186.482 140.898)
		(width 0.125)
		(layer "B.Cu")
		(net 417)
	)
	(segment
		(start 179.2035 123.7415)
		(end 180 123.584)
		(width 0.4)
		(layer "B.Cu")
		(net 417)
	)
	(segment
		(start 221.951526 147.794026)
		(end 221.9325 147.775)
		(width 0.4)
		(layer "B.Cu")
		(net 417)
	)
	(segment
		(start 180 123.584)
		(end 180.8055 123.7425)
		(width 0.4)
		(layer "B.Cu")
		(net 417)
	)
	(segment
		(start 205.056 141.7)
		(end 204.51 141.154)
		(width 0.4)
		(layer "B.Cu")
		(net 417)
	)
	(segment
		(start 224.15 140.75)
		(end 223.92 140.52)
		(width 0.15)
		(layer "B.Cu")
		(net 417)
	)
	(segment
		(start 177.7 124.616)
		(end 178.4045 124.3925)
		(width 0.4)
		(layer "B.Cu")
		(net 417)
	)
	(segment
		(start 206.924226 152.020641)
		(end 206.922 152.018415)
		(width 0.1)
		(layer "B.Cu")
		(net 417)
	)
	(segment
		(start 220.4 124.82)
		(end 220.4 124.769)
		(width 0.15)
		(layer "B.Cu")
		(net 417)
	)
	(segment
		(start 221.4255 138.5)
		(end 221.4255 138.136)
		(width 0.256)
		(layer "B.Cu")
		(net 417)
	)
	(segment
		(start 203.049 148.051)
		(end 203.699 147.401)
		(width 0.201)
		(layer "B.Cu")
		(net 417)
	)
	(segment
		(start 192.499 133.949)
		(end 192.82 134.27)
		(width 0.4)
		(layer "B.Cu")
		(net 417)
	)
	(segment
		(start 193.292 128.307)
		(end 193.299 128.3)
		(width 0.4)
		(layer "B.Cu")
		(net 417)
	)
	(segment
		(start 203.694 126.71)
		(end 203.694 127.495)
		(width 0.4)
		(layer "B.Cu")
		(net 417)
	)
	(segment
		(start 206.09 132.3)
		(end 205.299 132.3)
		(width 0.4)
		(layer "B.Cu")
		(net 417)
	)
	(segment
		(start 198.039 123.56)
		(end 197.299 124.3)
		(width 0.4)
		(layer "B.Cu")
		(net 417)
	)
	(segment
		(start 199.66 133.5)
		(end 199.89 133.27)
		(width 0.4)
		(layer "B.Cu")
		(net 417)
	)
	(segment
		(start 210.6725 133.347)
		(end 211.0225 133.697)
		(width 0.256)
		(layer "B.Cu")
		(net 417)
	)
	(segment
		(start 202.1195 155.258499)
		(end 202.1195 154.1735)
		(width 0.145)
		(layer "B.Cu")
		(net 417)
	)
	(segment
		(start 186.482 140.898)
		(end 188.147 140.898)
		(width 0.125)
		(layer "B.Cu")
		(net 417)
	)
	(segment
		(start 221.9325 147.8625)
		(end 221.9325 147.775)
		(width 0.256)
		(layer "B.Cu")
		(net 417)
	)
	(segment
		(start 221.42987 148.395)
		(end 221.42987 148.36513)
		(width 0.256)
		(layer "B.Cu")
		(net 417)
	)
	(segment
		(start 213.931 147.034)
		(end 214.865 147.034)
		(width 0.174)
		(layer "B.Cu")
		(net 417)
	)
	(segment
		(start 219.385 121.8)
		(end 218.85 121.8)
		(width 0.35)
		(layer "B.Cu")
		(net 417)
	)
	(segment
		(start 185.75 117.45)
		(end 185.75 118.47)
		(width 0.15)
		(layer "B.Cu")
		(net 417)
	)
	(segment
		(start 225.8425 142.3575)
		(end 225.855 142.345)
		(width 0.256)
		(layer "B.Cu")
		(net 417)
	)
	(segment
		(start 213.9 147.065)
		(end 213.9 146.1)
		(width 0.174)
		(layer "B.Cu")
		(net 417)
	)
	(segment
		(start 185.9325 141.4475)
		(end 186.25 141.13)
		(width 0.15)
		(layer "B.Cu")
		(net 417)
	)
	(segment
		(start 193.45 146.27)
		(end 192.46 146.27)
		(width 0.256)
		(layer "B.Cu")
		(net 417)
	)
	(segment
		(start 178.75 145.07)
		(end 178.75 144.1425)
		(width 0.2)
		(layer "B.Cu")
		(net 417)
	)
	(segment
		(start 208.584 144.175)
		(end 208.734 144.325)
		(width 0.4)
		(layer "B.Cu")
		(net 417)
	)
	(segment
		(start 221.42987 148.36513)
		(end 221.9325 147.8625)
		(width 0.256)
		(layer "B.Cu")
		(net 417)
	)
	(segment
		(start 203.318542 152.330047)
		(end 203.318542 151.464458)
		(width 0.201)
		(layer "B.Cu")
		(net 417)
	)
	(segment
		(start 217.98 140.67)
		(end 217.41 140.1)
		(width 0.15)
		(layer "B.Cu")
		(net 417)
	)
	(segment
		(start 205.718542 152.330047)
		(end 205.718542 151.464458)
		(width 0.201)
		(layer "B.Cu")
		(net 417)
	)
	(segment
		(start 211.965 145.13)
		(end 210.9 145.13)
		(width 0.2)
		(layer "B.Cu")
		(net 417)
	)
	(segment
		(start 218.1 144.495)
		(end 219.645 144.495)
		(width 0.177)
		(layer "B.Cu")
		(net 417)
	)
	(segment
		(start 179.2035 125.0425)
		(end 180 125.534)
		(width 0.4)
		(layer "B.Cu")
		(net 417)
	)
	(segment
		(start 219.431 122.811)
		(end 219.42 122.8)
		(width 0.2)
		(layer "B.Cu")
		(net 417)
	)
	(segment
		(start 221.582 131.587)
		(end 221.595 131.6)
		(width 0.174)
		(layer "B.Cu")
		(net 417)
	)
	(segment
		(start 208.734 144.325)
		(end 209.2 144.325)
		(width 0.4)
		(layer "B.Cu")
		(net 417)
	)
	(segment
		(start 195.85 127.47)
		(end 195.71 127.61)
		(width 0.4)
		(layer "B.Cu")
		(net 417)
	)
	(segment
		(start 206.13 134.76)
		(end 206.19 134.76)
		(width 0.14)
		(layer "B.Cu")
		(net 417)
	)
	(segment
		(start 193.119 133.28)
		(end 193.74 133.28)
		(width 0.4)
		(layer "B.Cu")
		(net 417)
	)
	(segment
		(start 206.63 142.08)
		(end 206.63 142.6)
		(width 0.4)
		(layer "B.Cu")
		(net 417)
	)
	(segment
		(start 208.575 147.3)
		(end 209.341 147.3)
		(width 0.4)
		(layer "B.Cu")
		(net 417)
	)
	(segment
		(start 190.1 119.75)
		(end 190.122 119.772)
		(width 0.15)
		(layer "B.Cu")
		(net 417)
	)
	(segment
		(start 209.797 119.472)
		(end 209.725 119.4)
		(width 0.256)
		(layer "B.Cu")
		(net 417)
	)
	(segment
		(start 203.699 146.626)
		(end 203.71724 146.60776)
		(width 0.201)
		(layer "B.Cu")
		(net 417)
	)
	(segment
		(start 215.266 149.066)
		(end 214.915 149.066)
		(width 0.174)
		(layer "B.Cu")
		(net 417)
	)
	(segment
		(start 203.699 146.101)
		(end 203.699 146.58952)
		(width 0.201)
		(layer "B.Cu")
		(net 417)
	)
	(segment
		(start 191.85 142.65)
		(end 191.641 142.65)
		(width 0.125)
		(layer "B.Cu")
		(net 417)
	)
	(segment
		(start 206.556 147.726)
		(end 206.68 147.85)
		(width 0.15)
		(layer "B.Cu")
		(net 417)
	)
	(segment
		(start 220.927091 143.117564)
		(end 220.939 143.105655)
		(width 0.09)
		(layer "B.Cu")
		(net 417)
	)
	(segment
		(start 189.247 151.347)
		(end 189.075 151.175)
		(width 0.1)
		(layer "B.Cu")
		(net 417)
	)
	(segment
		(start 214.341 116.704)
		(end 214.341 117.754)
		(width 0.2)
		(layer "B.Cu")
		(net 417)
	)
	(segment
		(start 191.979 125.901)
		(end 191.7 126.18)
		(width 0.4)
		(layer "B.Cu")
		(net 417)
	)
	(segment
		(start 204.5 135.494)
		(end 203.705 135.494)
		(width 0.4)
		(layer "B.Cu")
		(net 417)
	)
	(segment
		(start 203.699 146.58952)
		(end 203.71724 146.60776)
		(width 0.201)
		(layer "B.Cu")
		(net 417)
	)
	(segment
		(start 220.4 124.769)
		(end 219.431 123.8)
		(width 0.15)
		(layer "B.Cu")
		(net 417)
	)
	(segment
		(start 182.4 125.8)
		(end 182.4055 126.3415)
		(width 0.4)
		(layer "B.Cu")
		(net 417)
	)
	(segment
		(start 220.939 142.657865)
		(end 221.03 142.566865)
		(width 0.09)
		(layer "B.Cu")
		(net 417)
	)
	(segment
		(start 191.868 126.012)
		(end 191.7 126.18)
		(width 0.4)
		(layer "B.Cu")
		(net 417)
	)
	(segment
		(start 195.73 127.47)
		(end 195.704 127.496)
		(width 0.4)
		(layer "B.Cu")
		(net 417)
	)
	(segment
		(start 197.72 116.6)
		(end 197.722 116.602)
		(width 0.184)
		(layer "B.Cu")
		(net 417)
	)
	(segment
		(start 215.361 122.45)
		(end 215.361 122.014)
		(width 0.2)
		(layer "B.Cu")
		(net 417)
	)
	(segment
		(start 193.74 133.28)
		(end 194.03 132.99)
		(width 0.4)
		(layer "B.Cu")
		(net 417)
	)
	(segment
		(start 183.25 134.584)
		(end 184.0035 134.7905)
		(width 0.4)
		(layer "B.Cu")
		(net 417)
	)
	(segment
		(start 203.322 155.260999)
		(end 203.322 154.171)
		(width 0.15)
		(layer "B.Cu")
		(net 417)
	)
	(segment
		(start 175.25 135.144)
		(end 176.0045 134.7905)
		(width 0.256)
		(layer "B.Cu")
		(net 417)
	)
	(segment
		(start 196.122 151.907)
		(end 196.122 152.326589)
		(width 0.201)
		(layer "B.Cu")
		(net 417)
	)
	(segment
		(start 197.716001 135.883999)
		(end 198.1 135.5)
		(width 0.4)
		(layer "F.Cu")
		(net 418)
	)
	(segment
		(start 199.699 137.101)
		(end 199.701 137.101)
		(width 0.4)
		(layer "F.Cu")
		(net 418)
	)
	(segment
		(start 199.701 137.101)
		(end 200.1 137.5)
		(width 0.4)
		(layer "F.Cu")
		(net 418)
	)
	(segment
		(start 223.089 153.592)
		(end 222.768 153.592)
		(width 0.2)
		(layer "F.Cu")
		(net 418)
	)
	(segment
		(start 223.064 153.088)
		(end 222.768 153.088)
		(width 0.2)
		(layer "F.Cu")
		(net 418)
	)
	(via
		(at 219.5995 131)
		(size 0.35)
		(drill 0.15)
		(layers "F.Cu" "B.Cu")
		(remove_unused_layers yes)
		(keep_end_layers yes)
		(zone_layer_connections "In7.Cu")
		(net 418)
	)
	(via
		(at 199.75 137.85)
		(size 0.35)
		(drill 0.15)
		(layers "F.Cu" "B.Cu")
		(remove_unused_layers yes)
		(keep_end_layers yes)
		(zone_layer_connections "In2.Cu")
		(net 418)
	)
	(via
		(at 179.133398 138.318008)
		(size 0.35)
		(drill 0.15)
		(layers "F.Cu" "B.Cu")
		(remove_unused_layers yes)
		(keep_end_layers yes)
		(zone_layer_connections "In2.Cu")
		(net 418)
	)
	(via
		(at 194.9 137.1)
		(size 0.35)
		(drill 0.15)
		(layers "F.Cu" "B.Cu")
		(remove_unused_layers yes)
		(keep_end_layers yes)
		(zone_layer_connections "In2.Cu")
		(net 418)
	)
	(via
		(at 188.630623 140.08022)
		(size 0.35)
		(drill 0.15)
		(layers "F.Cu" "B.Cu")
		(remove_unused_layers yes)
		(keep_end_layers yes)
		(zone_layer_connections "In2.Cu" "In7.Cu")
		(net 418)
	)
	(via
		(at 223.064 153.088)
		(size 0.35)
		(drill 0.15)
		(layers "F.Cu" "B.Cu")
		(remove_unused_layers yes)
		(keep_end_layers yes)
		(zone_layer_connections "In7.Cu")
		(net 418)
	)
	(via
		(at 198.899 137.901)
		(size 0.35)
		(drill 0.15)
		(layers "F.Cu" "B.Cu")
		(remove_unused_layers yes)
		(keep_end_layers yes)
		(zone_layer_connections "In2.Cu")
		(net 418)
	)
	(via
		(at 188.462 139.6)
		(size 0.35)
		(drill 0.15)
		(layers "F.Cu" "B.Cu")
		(remove_unused_layers yes)
		(keep_end_layers yes)
		(zone_layer_connections "In2.Cu" "In7.Cu")
		(net 418)
	)
	(via
		(at 219.5995 130.303999)
		(size 0.35)
		(drill 0.15)
		(layers "F.Cu" "B.Cu")
		(remove_unused_layers yes)
		(keep_end_layers yes)
		(zone_layer_connections "In7.Cu")
		(net 418)
	)
	(via
		(at 222.006 151.785)
		(size 0.35)
		(drill 0.15)
		(layers "F.Cu" "B.Cu")
		(remove_unused_layers yes)
		(keep_end_layers yes)
		(zone_layer_connections "In7.Cu")
		(net 418)
	)
	(via
		(at 223.089 153.592)
		(size 0.35)
		(drill 0.15)
		(layers "F.Cu" "B.Cu")
		(remove_unused_layers yes)
		(keep_end_layers yes)
		(zone_layer_connections "In7.Cu")
		(net 418)
	)
	(via
		(at 197.299 137.95)
		(size 0.35)
		(drill 0.15)
		(layers "F.Cu" "B.Cu")
		(remove_unused_layers yes)
		(keep_end_layers yes)
		(zone_layer_connections "In2.Cu")
		(net 418)
	)
	(via
		(at 200.1 137.5)
		(size 0.35)
		(drill 0.15)
		(layers "F.Cu" "B.Cu")
		(remove_unused_layers yes)
		(keep_end_layers yes)
		(zone_layer_connections "In2.Cu")
		(net 418)
	)
	(via
		(at 194.9 130.701)
		(size 0.35)
		(drill 0.15)
		(layers "F.Cu" "B.Cu")
		(remove_unused_layers yes)
		(keep_end_layers yes)
		(zone_layer_connections "In2.Cu")
		(net 418)
	)
	(via
		(at 195.75 137.92)
		(size 0.35)
		(drill 0.15)
		(layers "F.Cu" "B.Cu")
		(remove_unused_layers yes)
		(keep_end_layers yes)
		(zone_layer_connections "In2.Cu")
		(net 418)
	)
	(via
		(at 187.832 139.712076)
		(size 0.35)
		(drill 0.15)
		(layers "F.Cu" "B.Cu")
		(remove_unused_layers yes)
		(keep_end_layers yes)
		(zone_layer_connections "In2.Cu" "In7.Cu")
		(net 418)
	)
	(via
		(at 220.85 122.15)
		(size 0.35)
		(drill 0.15)
		(layers "F.Cu" "B.Cu")
		(remove_unused_layers yes)
		(keep_end_layers yes)
		(zone_layer_connections "In7.Cu")
		(net 418)
	)
	(via
		(at 222.425 134.825)
		(size 0.35)
		(drill 0.15)
		(layers "F.Cu" "B.Cu")
		(remove_unused_layers yes)
		(keep_end_layers yes)
		(zone_layer_connections "In7.Cu")
		(net 418)
	)
	(via
		(at 197.716001 135.883999)
		(size 0.35)
		(drill 0.15)
		(layers "F.Cu" "B.Cu")
		(remove_unused_layers yes)
		(keep_end_layers yes)
		(zone_layer_connections "In2.Cu")
		(net 418)
	)
	(via
		(at 180.089065 139.138248)
		(size 0.35)
		(drill 0.15)
		(layers "F.Cu" "B.Cu")
		(remove_unused_layers yes)
		(keep_end_layers yes)
		(zone_layer_connections "In2.Cu")
		(net 418)
	)
	(via
		(at 220.8 119.15)
		(size 0.35)
		(drill 0.15)
		(layers "F.Cu" "B.Cu")
		(remove_unused_layers yes)
		(keep_end_layers yes)
		(zone_layer_connections "In7.Cu")
		(net 418)
	)
	(via
		(at 200.499 129.901)
		(size 0.35)
		(drill 0.15)
		(layers "F.Cu" "B.Cu")
		(remove_unused_layers yes)
		(keep_end_layers yes)
		(zone_layer_connections "In2.Cu")
		(net 418)
	)
	(segment
		(start 199.91 137.69)
		(end 199.91 137.675)
		(width 0.256)
		(layer "B.Cu")
		(net 418)
	)
	(segment
		(start 219.5995 131)
		(end 219.5995 130.639)
		(width 0.256)
		(layer "B.Cu")
		(net 418)
	)
	(segment
		(start 200.173 129.575)
		(end 200.499 129.901)
		(width 0.4)
		(layer "B.Cu")
		(net 418)
	)
	(segment
		(start 194.5 136.94)
		(end 194.72 137.16)
		(width 0.2)
		(layer "B.Cu")
		(net 418)
	)
	(segment
		(start 194.2 135.52)
		(end 194.5 135.82)
		(width 0.2)
		(layer "B.Cu")
		(net 418)
	)
	(segment
		(start 179.8 138.98461)
		(end 179.133398 138.318008)
		(width 0.35)
		(layer "B.Cu")
		(net 418)
	)
	(segment
		(start 199.525 138.075)
		(end 199.525 138.1)
		(width 0.256)
		(layer "B.Cu")
		(net 418)
	)
	(segment
		(start 220.395 118.704)
		(end 220.395 117.704)
		(width 0.174)
		(layer "B.Cu")
		(net 418)
	)
	(segment
		(start 220.395 122.77)
		(end 220.395 121.754)
		(width 0.174)
		(layer "B.Cu")
		(net 418)
	)
	(segment
		(start 220.395 123.7874)
		(end 220.395 122.77)
		(width 0.174)
		(layer "B.Cu")
		(net 418)
	)
	(segment
		(start 198.96 138.1)
		(end 199.525 138.1)
		(width 0.256)
		(layer "B.Cu")
		(net 418)
	)
	(segment
		(start 220.391 118.704)
		(end 220.395 118.704)
		(width 0.174)
		(layer "B.Cu")
		(net 418)
	)
	(segment
		(start 222.4245 134.8255)
		(end 222.425 134.825)
		(width 0.1)
		(layer "B.Cu")
		(net 418)
	)
	(segment
		(start 220.5 122.15)
		(end 220.395 122.255)
		(width 0.174)
		(layer "B.Cu")
		(net 418)
	)
	(segment
		(start 222.4245 135.261)
		(end 222.4245 134.8255)
		(width 0.1)
		(layer "B.Cu")
		(net 418)
	)
	(segment
		(start 220.85 122.15)
		(end 220.5 122.15)
		(width 0.174)
		(layer "B.Cu")
		(net 418)
	)
	(segment
		(start 199.91 137.675)
		(end 199.925 137.675)
		(width 0.256)
		(layer "B.Cu")
		(net 418)
	)
	(segment
		(start 199.251 129.575)
		(end 200.173 129.575)
		(width 0.4)
		(layer "B.Cu")
		(net 418)
	)
	(segment
		(start 222.91 152.15)
		(end 222.545 151.785)
		(width 0.2)
		(layer "B.Cu")
		(net 418)
	)
	(segment
		(start 196.009 138.134)
		(end 196.08 138.134)
		(width 0.4)
		(layer "B.Cu")
		(net 418)
	)
	(segment
		(start 194.72 137.16)
		(end 195.035 137.16)
		(width 0.4)
		(layer "B.Cu")
		(net 418)
	)
	(segment
		(start 220.391 118.741)
		(end 220.391 118.704)
		(width 0.174)
		(layer "B.Cu")
		(net 418)
	)
	(segment
		(start 194.5 135.82)
		(end 194.5 136.94)
		(width 0.2)
		(layer "B.Cu")
		(net 418)
	)
	(segment
		(start 179.8 139)
		(end 179.8 138.98461)
		(width 0.35)
		(layer "B.Cu")
		(net 418)
	)
	(segment
		(start 199.91 137.675)
		(end 199.91 137.164)
		(width 0.256)
		(layer "B.Cu")
		(net 418)
	)
	(segment
		(start 222.91 152.76)
		(end 222.91 152.15)
		(width 0.2)
		(layer "B.Cu")
		(net 418)
	)
	(segment
		(start 199.75 137.85)
		(end 199.91 137.69)
		(width 0.256)
		(layer "B.Cu")
		(net 418)
	)
	(segment
		(start 199.925 137.675)
		(end 200.1 137.5)
		(width 0.256)
		(layer "B.Cu")
		(net 418)
	)
	(segment
		(start 222.545 151.785)
		(end 222.006 151.785)
		(width 0.2)
		(layer "B.Cu")
		(net 418)
	)
	(segment
		(start 198.91 129.234)
		(end 199.251 129.575)
		(width 0.4)
		(layer "B.Cu")
		(net 418)
	)
	(segment
		(start 199.86 138.1)
		(end 199.91 138.15)
		(width 0.256)
		(layer "B.Cu")
		(net 418)
	)
	(segment
		(start 199.91 138.15)
		(end 199.91 137.675)
		(width 0.256)
		(layer "B.Cu")
		(net 418)
	)
	(segment
		(start 220.395 122.255)
		(end 220.395 122.77)
		(width 0.174)
		(layer "B.Cu")
		(net 418)
	)
	(segment
		(start 195.035 137.16)
		(end 196.009 138.134)
		(width 0.4)
		(layer "B.Cu")
		(net 418)
	)
	(segment
		(start 199.75 137.85)
		(end 199.525 138.075)
		(width 0.256)
		(layer "B.Cu")
		(net 418)
	)
	(segment
		(start 197.04 138.134)
		(end 196.08 138.134)
		(width 0.256)
		(layer "B.Cu")
		(net 418)
	)
	(segment
		(start 220.8 119.15)
		(end 220.391 118.741)
		(width 0.174)
		(layer "B.Cu")
		(net 418)
	)
	(segment
		(start 220.395 119.7234)
		(end 220.395 118.704)
		(width 0.174)
		(layer "B.Cu")
		(net 418)
	)
	(segment
		(start 199.525 138.1)
		(end 199.86 138.1)
		(width 0.256)
		(layer "B.Cu")
		(net 418)
	)
	(segment
		(start 224.62 142.57)
		(end 224.3765 142.8135)
		(width 0.1)
		(layer "F.Cu")
		(net 421)
	)
	(segment
		(start 224.3765 142.8135)
		(end 224.3765 142.942)
		(width 0.1)
		(layer "F.Cu")
		(net 421)
	)
	(via
		(at 224.62 142.57)
		(size 0.35)
		(drill 0.15)
		(layers "F.Cu" "B.Cu")
		(remove_unused_layers yes)
		(keep_end_layers yes)
		(zone_layer_connections)
		(net 421)
	)
	(segment
		(start 224.845 142.345)
		(end 225.12 142.345)
		(width 0.15)
		(layer "B.Cu")
		(net 421)
	)
	(segment
		(start 224.62 142.57)
		(end 224.845 142.345)
		(width 0.15)
		(layer "B.Cu")
		(net 421)
	)
	(segment
		(start 224.818 144.142)
		(end 224.3765 144.142)
		(width 0.1)
		(layer "F.Cu")
		(net 422)
	)
	(segment
		(start 224.83 144.13)
		(end 224.818 144.142)
		(width 0.1)
		(layer "F.Cu")
		(net 422)
	)
	(via
		(at 224.83 144.13)
		(size 0.35)
		(drill 0.15)
		(layers "F.Cu" "B.Cu")
		(remove_unused_layers yes)
		(keep_end_layers yes)
		(zone_layer_connections)
		(net 422)
	)
	(segment
		(start 224.83 144.13)
		(end 225.045 144.345)
		(width 0.15)
		(layer "B.Cu")
		(net 422)
	)
	(segment
		(start 225.045 144.345)
		(end 225.12 144.345)
		(width 0.15)
		(layer "B.Cu")
		(net 422)
	)
	(segment
		(start 224.4885 143.43)
		(end 224.3765 143.542)
		(width 0.1)
		(layer "F.Cu")
		(net 423)
	)
	(segment
		(start 224.5 143.43)
		(end 224.4885 143.43)
		(width 0.1)
		(layer "F.Cu")
		(net 423)
	)
	(via
		(at 224.5 143.43)
		(size 0.35)
		(drill 0.15)
		(layers "F.Cu" "B.Cu")
		(remove_unused_layers yes)
		(keep_end_layers yes)
		(zone_layer_connections)
		(net 423)
	)
	(segment
		(start 224.6825 143.345)
		(end 224.5 143.345)
		(width 0.15)
		(layer "B.Cu")
		(net 423)
	)
	(segment
		(start 224.5 143.345)
		(end 224.5 143.43)
		(width 0.15)
		(layer "B.Cu")
		(net 423)
	)
	(segment
		(start 225.12 143.345)
		(end 224.6825 143.345)
		(width 0.1)
		(layer "B.Cu")
		(net 423)
	)
	(segment
		(start 224.5 143.345)
		(end 225.12 143.345)
		(width 0.15)
		(layer "B.Cu")
		(net 423)
	)
	(segment
		(start 224.68 144.92)
		(end 224.502 144.742)
		(width 0.1)
		(layer "F.Cu")
		(net 424)
	)
	(segment
		(start 224.502 144.742)
		(end 224.3765 144.742)
		(width 0.1)
		(layer "F.Cu")
		(net 424)
	)
	(via
		(at 224.68 144.92)
		(size 0.35)
		(drill 0.15)
		(layers "F.Cu" "B.Cu")
		(remove_unused_layers yes)
		(keep_end_layers yes)
		(zone_layer_connections)
		(net 424)
	)
	(segment
		(start 225.105 145.345)
		(end 225.12 145.345)
		(width 0.15)
		(layer "B.Cu")
		(net 424)
	)
	(segment
		(start 224.68 144.92)
		(end 225.105 145.345)
		(width 0.15)
		(layer "B.Cu")
		(net 424)
	)
	(via
		(at 202.9 127.5)
		(size 0.35)
		(drill 0.15)
		(layers "F.Cu" "B.Cu")
		(remove_unused_layers yes)
		(keep_end_layers yes)
		(zone_layer_connections)
		(net 428)
	)
	(via
		(at 176.95 148.15)
		(size 0.35)
		(drill 0.15)
		(layers "F.Cu" "B.Cu")
		(remove_unused_layers yes)
		(keep_end_layers yes)
		(zone_layer_connections)
		(net 428)
	)
	(segment
		(start 183.264997 144.374997)
		(end 183.59 144.7)
		(width 0.1)
		(layer "In11.Cu")
		(net 428)
	)
	(segment
		(start 201.56416 130.09546)
		(end 201.56416 129.83584)
		(width 0.1)
		(layer "In11.Cu")
		(net 428)
	)
	(segment
		(start 190 137.5)
		(end 191.2 136.3)
		(width 0.1)
		(layer "In11.Cu")
		(net 428)
	)
	(segment
		(start 180.7088 146.2775)
		(end 181.6225 146.2775)
		(width 0.1)
		(layer "In11.Cu")
		(net 428)
	)
	(segment
		(start 186.7 143.5)
		(end 186.7 140.325)
		(width 0.1)
		(layer "In11.Cu")
		(net 428)
	)
	(segment
		(start 197.174 131.826)
		(end 197.92981 131.07019)
		(width 0.1)
		(layer "In11.Cu")
		(net 428)
	)
	(segment
		(start 191.2 135.54038)
		(end 191.56538 135.175)
		(width 0.1)
		(layer "In11.Cu")
		(net 428)
	)
	(segment
		(start 199.47019 130.3)
		(end 201.35962 130.3)
		(width 0.1)
		(layer "In11.Cu")
		(net 428)
	)
	(segment
		(start 195.83362 131.826)
		(end 197.174 131.826)
		(width 0.1)
		(layer "In11.Cu")
		(net 428)
	)
	(segment
		(start 180.411299 145.98)
		(end 180.7088 146.2775)
		(width 0.1)
		(layer "In11.Cu")
		(net 428)
	)
	(segment
		(start 191.2 136.3)
		(end 191.2 135.54038)
		(width 0.1)
		(layer "In11.Cu")
		(net 428)
	)
	(segment
		(start 191.56538 135.175)
		(end 191.975 135.175)
		(width 0.1)
		(layer "In11.Cu")
		(net 428)
	)
	(segment
		(start 178.168343 147.447745)
		(end 179.636088 145.98)
		(width 0.1)
		(layer "In11.Cu")
		(net 428)
	)
	(segment
		(start 181.6225 146.2775)
		(end 181.78 146.12)
		(width 0.1)
		(layer "In11.Cu")
		(net 428)
	)
	(segment
		(start 181.78 145.33962)
		(end 181.57 145.12962)
		(width 0.1)
		(layer "In11.Cu")
		(net 428)
	)
	(segment
		(start 181.57 145.12962)
		(end 181.57 144.58)
		(width 0.1)
		(layer "In11.Cu")
		(net 428)
	)
	(segment
		(start 181.78 146.12)
		(end 181.78 145.33962)
		(width 0.1)
		(layer "In11.Cu")
		(net 428)
	)
	(segment
		(start 177.452255 147.447745)
		(end 178.168343 147.447745)
		(width 0.1)
		(layer "In11.Cu")
		(net 428)
	)
	(segment
		(start 183.59 144.7)
		(end 185.5 144.7)
		(width 0.1)
		(layer "In11.Cu")
		(net 428)
	)
	(segment
		(start 177.275 147.625)
		(end 177.452255 147.447745)
		(width 0.1)
		(layer "In11.Cu")
		(net 428)
	)
	(segment
		(start 198.7 131.07019)
		(end 199.47019 130.3)
		(width 0.1)
		(layer "In11.Cu")
		(net 428)
	)
	(segment
		(start 185.5 144.7)
		(end 186.7 143.5)
		(width 0.1)
		(layer "In11.Cu")
		(net 428)
	)
	(segment
		(start 197.92981 131.07019)
		(end 198.7 131.07019)
		(width 0.1)
		(layer "In11.Cu")
		(net 428)
	)
	(segment
		(start 188.06969 138.43031)
		(end 189 137.5)
		(width 0.1)
		(layer "In11.Cu")
		(net 428)
	)
	(segment
		(start 194.95962 132.7)
		(end 195.83362 131.826)
		(width 0.1)
		(layer "In11.Cu")
		(net 428)
	)
	(segment
		(start 194.45 132.7)
		(end 194.95962 132.7)
		(width 0.1)
		(layer "In11.Cu")
		(net 428)
	)
	(segment
		(start 176.95 148.15)
		(end 177.275 147.825)
		(width 0.1)
		(layer "In11.Cu")
		(net 428)
	)
	(segment
		(start 186.7 140.325)
		(end 188.06969 138.95531)
		(width 0.1)
		(layer "In11.Cu")
		(net 428)
	)
	(segment
		(start 189 137.5)
		(end 190 137.5)
		(width 0.1)
		(layer "In11.Cu")
		(net 428)
	)
	(segment
		(start 201.56416 129.83584)
		(end 202.9 128.5)
		(width 0.1)
		(layer "In11.Cu")
		(net 428)
	)
	(segment
		(start 201.35962 130.3)
		(end 201.56416 130.09546)
		(width 0.1)
		(layer "In11.Cu")
		(net 428)
	)
	(segment
		(start 202.9 128.5)
		(end 202.9 127.5)
		(width 0.1)
		(layer "In11.Cu")
		(net 428)
	)
	(segment
		(start 179.636088 145.98)
		(end 180.411299 145.98)
		(width 0.1)
		(layer "In11.Cu")
		(net 428)
	)
	(segment
		(start 188.06969 138.95531)
		(end 188.06969 138.43031)
		(width 0.1)
		(layer "In11.Cu")
		(net 428)
	)
	(segment
		(start 191.975 135.175)
		(end 194.45 132.7)
		(width 0.1)
		(layer "In11.Cu")
		(net 428)
	)
	(segment
		(start 181.57 144.58)
		(end 181.775003 144.374997)
		(width 0.1)
		(layer "In11.Cu")
		(net 428)
	)
	(segment
		(start 177.275 147.825)
		(end 177.275 147.625)
		(width 0.1)
		(layer "In11.Cu")
		(net 428)
	)
	(segment
		(start 181.775003 144.374997)
		(end 183.264997 144.374997)
		(width 0.1)
		(layer "In11.Cu")
		(net 428)
	)
	(segment
		(start 221.2015 147.9185)
		(end 221.2015 147.817)
		(width 0.1)
		(layer "F.Cu")
		(net 430)
	)
	(segment
		(start 220.525 149.322)
		(end 220.525 148.595)
		(width 0.1)
		(layer "F.Cu")
		(net 430)
	)
	(segment
		(start 220.525 148.595)
		(end 221.2015 147.9185)
		(width 0.1)
		(layer "F.Cu")
		(net 430)
	)
	(segment
		(start 221.98 154.385)
		(end 221.98 154.585)
		(width 0.125)
		(layer "F.Cu")
		(net 461)
	)
	(segment
		(start 222.772872 154.8391)
		(end 222.772872 154.66727)
		(width 0.125)
		(layer "F.Cu")
		(net 461)
	)
	(segment
		(start 221.8375 154.7275)
		(end 221.8375 154.824474)
		(width 0.125)
		(layer "F.Cu")
		(net 461)
	)
	(segment
		(start 221.8375 154.824474)
		(end 221.93619 154.923164)
		(width 0.125)
		(layer "F.Cu")
		(net 461)
	)
	(segment
		(start 222.688808 154.923164)
		(end 222.772872 154.8391)
		(width 0.125)
		(layer "F.Cu")
		(net 461)
	)
	(segment
		(start 221.98 154.585)
		(end 221.8375 154.7275)
		(width 0.125)
		(layer "F.Cu")
		(net 461)
	)
	(segment
		(start 221.93619 154.923164)
		(end 222.688808 154.923164)
		(width 0.125)
		(layer "F.Cu")
		(net 461)
	)
	(via
		(at 198.1 138.7)
		(size 0.35)
		(drill 0.15)
		(layers "F.Cu" "B.Cu")
		(remove_unused_layers yes)
		(keep_end_layers yes)
		(zone_layer_connections)
		(net 461)
	)
	(via
		(at 222.772872 154.66727)
		(size 0.35)
		(drill 0.15)
		(layers "F.Cu" "B.Cu")
		(remove_unused_layers yes)
		(keep_end_layers yes)
		(zone_layer_connections)
		(net 461)
	)
	(segment
		(start 199.05 139.175)
		(end 199.3 139.425)
		(width 0.1)
		(layer "In2.Cu")
		(net 461)
	)
	(segment
		(start 204.791422 150.52)
		(end 205.501422 150.52)
		(width 0.1)
		(layer "In2.Cu")
		(net 461)
	)
	(segment
		(start 212.288578 150.04)
		(end 214.291422 150.04)
		(width 0.1)
		(layer "In2.Cu")
		(net 461)
	)
	(segment
		(start 200.024 141.23562)
		(end 199.799 141.46062)
		(width 0.1)
		(layer "In2.Cu")
		(net 461)
	)
	(segment
		(start 199.92 146.908578)
		(end 200.241422 147.23)
		(width 0.1)
		(layer "In2.Cu")
		(net 461)
	)
	(segment
		(start 200.024 140.149)
		(end 200.024 141.23562)
		(width 0.1)
		(layer "In2.Cu")
		(net 461)
	)
	(segment
		(start 201.81 148.218578)
		(end 202.211422 148.62)
		(width 0.1)
		(layer "In2.Cu")
		(net 461)
	)
	(segment
		(start 211.178578 151.15)
		(end 212.288578 150.04)
		(width 0.1)
		(layer "In2.Cu")
		(net 461)
	)
	(segment
		(start 202.211422 148.62)
		(end 203.391422 148.62)
		(width 0.1)
		(layer "In2.Cu")
		(net 461)
	)
	(segment
		(start 199.3 139.425)
		(end 199.566422 139.425)
		(width 0.1)
		(layer "In2.Cu")
		(net 461)
	)
	(segment
		(start 199.799 139.924)
		(end 200.024 140.149)
		(width 0.1)
		(layer "In2.Cu")
		(net 461)
	)
	(segment
		(start 214.961422 150.71)
		(end 217.071422 150.71)
		(width 0.1)
		(layer "In2.Cu")
		(net 461)
	)
	(segment
		(start 199.66 144.256422)
		(end 199.66 144.668578)
		(width 0.1)
		(layer "In2.Cu")
		(net 461)
	)
	(segment
		(start 221.421422 155.06)
		(end 221.55 155.06)
		(width 0.1)
		(layer "In2.Cu")
		(net 461)
	)
	(segment
		(start 198.575 139.175)
		(end 199.05 139.175)
		(width 0.1)
		(layer "In2.Cu")
		(net 461)
	)
	(segment
		(start 222.25 155.06)
		(end 222.556213 155.06)
		(width 0.1)
		(layer "In2.Cu")
		(net 461)
	)
	(segment
		(start 198.1 138.7)
		(end 198.575 139.175)
		(width 0.1)
		(layer "In2.Cu")
		(net 461)
	)
	(segment
		(start 201.271422 147.23)
		(end 201.81 147.768578)
		(width 0.1)
		(layer "In2.Cu")
		(net 461)
	)
	(segment
		(start 199.66 144.668578)
		(end 199.92 144.928578)
		(width 0.1)
		(layer "In2.Cu")
		(net 461)
	)
	(segment
		(start 204.255094 149.704288)
		(end 204.327534 149.776728)
		(width 0.1)
		(layer "In2.Cu")
		(net 461)
	)
	(segment
		(start 214.291422 150.04)
		(end 214.961422 150.71)
		(width 0.1)
		(layer "In2.Cu")
		(net 461)
	)
	(segment
		(start 217.071422 150.71)
		(end 221.421422 155.06)
		(width 0.1)
		(layer "In2.Cu")
		(net 461)
	)
	(segment
		(start 199.92 144.928578)
		(end 199.92 146.908578)
		(width 0.1)
		(layer "In2.Cu")
		(net 461)
	)
	(segment
		(start 203.391422 148.62)
		(end 203.88 149.108578)
		(width 0.1)
		(layer "In2.Cu")
		(net 461)
	)
	(segment
		(start 204.327534 150.056113)
		(end 204.791422 150.52)
		(width 0.1)
		(layer "In2.Cu")
		(net 461)
	)
	(segment
		(start 203.88 149.608578)
		(end 203.975711 149.704289)
		(width 0.1)
		(layer "In2.Cu")
		(net 461)
	)
	(segment
		(start 203.88 149.108578)
		(end 203.88 149.608578)
		(width 0.1)
		(layer "In2.Cu")
		(net 461)
	)
	(segment
		(start 200.45 143.466422)
		(end 199.66 144.256422)
		(width 0.1)
		(layer "In2.Cu")
		(net 461)
	)
	(segment
		(start 211.03 151.15)
		(end 211.178578 151.15)
		(width 0.1)
		(layer "In2.Cu")
		(net 461)
	)
	(segment
		(start 204.327534 149.91642)
		(end 204.327534 149.916421)
		(width 0.1)
		(layer "In2.Cu")
		(net 461)
	)
	(segment
		(start 201.81 147.768578)
		(end 201.81 148.218578)
		(width 0.1)
		(layer "In2.Cu")
		(net 461)
	)
	(segment
		(start 199.799 141.557578)
		(end 200.45 142.208578)
		(width 0.1)
		(layer "In2.Cu")
		(net 461)
	)
	(segment
		(start 200.241422 147.23)
		(end 201.271422 147.23)
		(width 0.1)
		(layer "In2.Cu")
		(net 461)
	)
	(segment
		(start 206.131422 151.15)
		(end 210.34753 151.15)
		(width 0.1)
		(layer "In2.Cu")
		(net 461)
	)
	(segment
		(start 200.45 142.208578)
		(end 200.45 143.466422)
		(width 0.1)
		(layer "In2.Cu")
		(net 461)
	)
	(segment
		(start 222.772872 154.843341)
		(end 222.772872 154.66727)
		(width 0.1)
		(layer "In2.Cu")
		(net 461)
	)
	(segment
		(start 210.68 150.81753)
		(end 210.69753 150.81753)
		(width 0.1)
		(layer "In2.Cu")
		(net 461)
	)
	(segment
		(start 199.799 139.657578)
		(end 199.799 139.924)
		(width 0.1)
		(layer "In2.Cu")
		(net 461)
	)
	(segment
		(start 199.566422 139.425)
		(end 199.799 139.657578)
		(width 0.1)
		(layer "In2.Cu")
		(net 461)
	)
	(segment
		(start 222.556213 155.06)
		(end 222.772872 154.843341)
		(width 0.1)
		(layer "In2.Cu")
		(net 461)
	)
	(segment
		(start 205.501422 150.52)
		(end 206.131422 151.15)
		(width 0.1)
		(layer "In2.Cu")
		(net 461)
	)
	(segment
		(start 199.799 141.46062)
		(end 199.799 141.557578)
		(width 0.1)
		(layer "In2.Cu")
		(net 461)
	)
	(arc
		(start 204.115402 149.704288)
		(mid 204.185249 149.675358)
		(end 204.255094 149.704288)
		(width 0.1)
		(layer "In2.Cu")
		(net 461)
	)
	(arc
		(start 210.34753 151.15)
		(mid 210.465076 151.101311)
		(end 210.513765 150.983765)
		(width 0.1)
		(layer "In2.Cu")
		(net 461)
	)
	(arc
		(start 210.69753 150.81753)
		(mid 210.815076 150.866219)
		(end 210.863765 150.983765)
		(width 0.1)
		(layer "In2.Cu")
		(net 461)
	)
	(arc
		(start 221.725 154.885)
		(mid 221.776256 154.761256)
		(end 221.9 154.71)
		(width 0.1)
		(layer "In2.Cu")
		(net 461)
	)
	(arc
		(start 204.327534 149.776728)
		(mid 204.356466 149.846575)
		(end 204.327534 149.91642)
		(width 0.1)
		(layer "In2.Cu")
		(net 461)
	)
	(arc
		(start 221.55 155.06)
		(mid 221.673744 155.008744)
		(end 221.725 154.885)
		(width 0.1)
		(layer "In2.Cu")
		(net 461)
	)
	(arc
		(start 204.327534 149.916421)
		(mid 204.298602 149.986266)
		(end 204.327534 150.056113)
		(width 0.1)
		(layer "In2.Cu")
		(net 461)
	)
	(arc
		(start 210.513765 150.983765)
		(mid 210.562454 150.866219)
		(end 210.68 150.81753)
		(width 0.1)
		(layer "In2.Cu")
		(net 461)
	)
	(arc
		(start 222.075 154.885)
		(mid 222.126256 155.008744)
		(end 222.25 155.06)
		(width 0.1)
		(layer "In2.Cu")
		(net 461)
	)
	(arc
		(start 203.975711 149.704289)
		(mid 204.045557 149.733219)
		(end 204.115402 149.704288)
		(width 0.1)
		(layer "In2.Cu")
		(net 461)
	)
	(arc
		(start 221.9 154.71)
		(mid 222.023744 154.761256)
		(end 222.075 154.885)
		(width 0.1)
		(layer "In2.Cu")
		(net 461)
	)
	(arc
		(start 210.863765 150.983765)
		(mid 210.912454 151.101311)
		(end 211.03 151.15)
		(width 0.1)
		(layer "In2.Cu")
		(net 461)
	)
	(via
		(at 214.97494 153.294476)
		(size 0.35)
		(drill 0.15)
		(layers "F.Cu" "B.Cu")
		(remove_unused_layers yes)
		(keep_end_layers yes)
		(zone_layer_connections)
		(net 498)
	)
	(via
		(at 215.613 144.7505)
		(size 0.35)
		(drill 0.15)
		(layers "F.Cu" "B.Cu")
		(remove_unused_layers yes)
		(keep_end_layers yes)
		(zone_layer_connections)
		(net 498)
	)
	(segment
		(start 215.655 152.200648)
		(end 215.173459 151.719107)
		(width 0.09)
		(layer "In9.Cu")
		(net 498)
	)
	(segment
		(start 213.165 145.290648)
		(end 213.165 144.46375)
		(width 0.09)
		(layer "In9.Cu")
		(net 498)
	)
	(segment
		(start 215.107189 153.162227)
		(end 215.262125 153.162227)
		(width 0.09)
		(layer "In9.Cu")
		(net 498)
	)
	(segment
		(start 215.76644 150.517911)
		(end 216.335 149.949352)
		(width 0.09)
		(layer "In9.Cu")
		(net 498)
	)
	(segment
		(start 215.173459 151.110893)
		(end 215.342176 150.942176)
		(width 0.09)
		(layer "In9.Cu")
		(net 498)
	)
	(segment
		(start 215.749289 150.730043)
		(end 215.749288 150.730042)
		(width 0.09)
		(layer "In9.Cu")
		(net 498)
	)
	(segment
		(start 215.767999 144.472351)
		(end 215.767999 144.595501)
		(width 0.09)
		(layer "In9.Cu")
		(net 498)
	)
	(segment
		(start 215.732139 150.942176)
		(end 215.749289 150.925025)
		(width 0.09)
		(layer "In9.Cu")
		(net 498)
	)
	(segment
		(start 215.520648 144.225)
		(end 215.767999 144.472351)
		(width 0.09)
		(layer "In9.Cu")
		(net 498)
	)
	(segment
		(start 215.767999 144.595501)
		(end 215.613 144.7505)
		(width 0.09)
		(layer "In9.Cu")
		(net 498)
	)
	(segment
		(start 216.335 148.460648)
		(end 213.165 145.290648)
		(width 0.09)
		(layer "In9.Cu")
		(net 498)
	)
	(segment
		(start 214.97494 153.294476)
		(end 215.107189 153.162227)
		(width 0.09)
		(layer "In9.Cu")
		(net 498)
	)
	(segment
		(start 215.655 152.769352)
		(end 215.655 152.200648)
		(width 0.09)
		(layer "In9.Cu")
		(net 498)
	)
	(segment
		(start 215.262125 153.162227)
		(end 215.655 152.769352)
		(width 0.09)
		(layer "In9.Cu")
		(net 498)
	)
	(segment
		(start 215.749288 150.53506)
		(end 215.76644 150.517911)
		(width 0.09)
		(layer "In9.Cu")
		(net 498)
	)
	(segment
		(start 215.173459 151.719107)
		(end 215.173459 151.110893)
		(width 0.09)
		(layer "In9.Cu")
		(net 498)
	)
	(segment
		(start 213.165 144.46375)
		(end 213.40375 144.225)
		(width 0.09)
		(layer "In9.Cu")
		(net 498)
	)
	(segment
		(start 216.335 149.949352)
		(end 216.335 148.460648)
		(width 0.09)
		(layer "In9.Cu")
		(net 498)
	)
	(segment
		(start 215.537156 150.942176)
		(end 215.537157 150.942176)
		(width 0.09)
		(layer "In9.Cu")
		(net 498)
	)
	(segment
		(start 213.40375 144.225)
		(end 215.520648 144.225)
		(width 0.09)
		(layer "In9.Cu")
		(net 498)
	)
	(arc
		(start 215.342176 150.942176)
		(mid 215.439666 150.901794)
		(end 215.537156 150.942176)
		(width 0.09)
		(layer "In9.Cu")
		(net 498)
	)
	(arc
		(start 215.749289 150.925025)
		(mid 215.789671 150.827534)
		(end 215.749289 150.730043)
		(width 0.09)
		(layer "In9.Cu")
		(net 498)
	)
	(arc
		(start 215.749288 150.730042)
		(mid 215.708906 150.632551)
		(end 215.749288 150.53506)
		(width 0.09)
		(layer "In9.Cu")
		(net 498)
	)
	(arc
		(start 215.537157 150.942176)
		(mid 215.634648 150.982558)
		(end 215.732139 150.942176)
		(width 0.09)
		(layer "In9.Cu")
		(net 498)
	)
	(via
		(at 216.113 144.7505)
		(size 0.35)
		(drill 0.15)
		(layers "F.Cu" "B.Cu")
		(remove_unused_layers yes)
		(keep_end_layers yes)
		(zone_layer_connections)
		(net 499)
	)
	(via
		(at 214.97494 152.839976)
		(size 0.35)
		(drill 0.15)
		(layers "F.Cu" "B.Cu")
		(remove_unused_layers yes)
		(keep_end_layers yes)
		(zone_layer_connections)
		(net 499)
	)
	(segment
		(start 215.183423 152.972225)
		(end 215.107189 152.972225)
		(width 0.09)
		(layer "In9.Cu")
		(net 499)
	)
	(segment
		(start 215.599352 144.035)
		(end 213.325046 144.035)
		(width 0.09)
		(layer "In9.Cu")
		(net 499)
	)
	(segment
		(start 215.958001 144.393649)
		(end 215.599352 144.035)
		(width 0.09)
		(layer "In9.Cu")
		(net 499)
	)
	(segment
		(start 212.975 145.369352)
		(end 216.145 148.539352)
		(width 0.09)
		(layer "In9.Cu")
		(net 499)
	)
	(segment
		(start 215.465 152.279352)
		(end 215.465 152.690648)
		(width 0.09)
		(layer "In9.Cu")
		(net 499)
	)
	(segment
		(start 216.145 149.870648)
		(end 214.983459 151.032189)
		(width 0.09)
		(layer "In9.Cu")
		(net 499)
	)
	(segment
		(start 215.465 152.690648)
		(end 215.183423 152.972225)
		(width 0.09)
		(layer "In9.Cu")
		(net 499)
	)
	(segment
		(start 215.958001 144.595501)
		(end 215.958001 144.393649)
		(width 0.09)
		(layer "In9.Cu")
		(net 499)
	)
	(segment
		(start 215.107189 152.972225)
		(end 214.97494 152.839976)
		(width 0.09)
		(layer "In9.Cu")
		(net 499)
	)
	(segment
		(start 216.145 148.539352)
		(end 216.145 149.870648)
		(width 0.09)
		(layer "In9.Cu")
		(net 499)
	)
	(segment
		(start 214.983459 151.032189)
		(end 214.983459 151.797811)
		(width 0.09)
		(layer "In9.Cu")
		(net 499)
	)
	(segment
		(start 213.325046 144.035)
		(end 212.975 144.385046)
		(width 0.09)
		(layer "In9.Cu")
		(net 499)
	)
	(segment
		(start 216.113 144.7505)
		(end 215.958001 144.595501)
		(width 0.09)
		(layer "In9.Cu")
		(net 499)
	)
	(segment
		(start 212.975 144.385046)
		(end 212.975 145.369352)
		(width 0.09)
		(layer "In9.Cu")
		(net 499)
	)
	(segment
		(start 214.983459 151.797811)
		(end 215.465 152.279352)
		(width 0.09)
		(layer "In9.Cu")
		(net 499)
	)
	(segment
		(start 212.927 143.15)
		(end 212.45 143.15)
		(width 0.15)
		(layer "F.Cu")
		(net 500)
	)
	(segment
		(start 213.0995 145.1125)
		(end 214.2875 145.1125)
		(width 0.15)
		(layer "F.Cu")
		(net 500)
	)
	(segment
		(start 212.45 143.15)
		(end 212.3 143.3)
		(width 0.15)
		(layer "F.Cu")
		(net 500)
	)
	(segment
		(start 212.15 144.163)
		(end 211.536 144.163)
		(width 0.15)
		(layer "F.Cu")
		(net 500)
	)
	(segment
		(start 214.2875 145.1125)
		(end 214.615 145.44)
		(width 0.15)
		(layer "F.Cu")
		(net 500)
	)
	(segment
		(start 212.3 144.013)
		(end 212.15 144.163)
		(width 0.15)
		(layer "F.Cu")
		(net 500)
	)
	(segment
		(start 212.15 144.163)
		(end 213.0995 145.1125)
		(width 0.15)
		(layer "F.Cu")
		(net 500)
	)
	(segment
		(start 214.615 145.44)
		(end 214.615 146.112)
		(width 0.15)
		(layer "F.Cu")
		(net 500)
	)
	(segment
		(start 212.3 143.3)
		(end 212.3 144.013)
		(width 0.15)
		(layer "F.Cu")
		(net 500)
	)
	(segment
		(start 192.3 145.9)
		(end 192.59 145.9)
		(width 0.15)
		(layer "F.Cu")
		(net 505)
	)
	(segment
		(start 191.65 145.25)
		(end 192.3 145.9)
		(width 0.15)
		(layer "F.Cu")
		(net 505)
	)
	(segment
		(start 189.1 142.2)
		(end 190.05 142.2)
		(width 0.15)
		(layer "F.Cu")
		(net 505)
	)
	(segment
		(start 190.05 142.2)
		(end 191.65 143.8)
		(width 0.15)
		(layer "F.Cu")
		(net 505)
	)
	(segment
		(start 191.65 143.8)
		(end 191.65 145.25)
		(width 0.15)
		(layer "F.Cu")
		(net 505)
	)
	(via
		(at 189.1 142.2)
		(size 0.35)
		(drill 0.15)
		(layers "F.Cu" "B.Cu")
		(remove_unused_layers yes)
		(keep_end_layers yes)
		(zone_layer_connections)
		(net 505)
	)
	(segment
		(start 189.1 142.2)
		(end 187.7 142.2)
		(width 0.15)
		(layer "B.Cu")
		(net 505)
	)
	(segment
		(start 187.7 142.2)
		(end 187.47 141.97)
		(width 0.15)
		(layer "B.Cu")
		(net 505)
	)
	(segment
		(start 187.47 141.97)
		(end 187.47 141.398)
		(width 0.15)
		(layer "B.Cu")
		(net 505)
	)
	(segment
		(start 228.47 147.815)
		(end 226.665 147.815)
		(width 0.1)
		(layer "F.Cu")
		(net 506)
	)
	(segment
		(start 225.992 147.142)
		(end 225.5765 147.142)
		(width 0.1)
		(layer "F.Cu")
		(net 506)
	)
	(segment
		(start 226.665 147.815)
		(end 225.992 147.142)
		(width 0.1)
		(layer "F.Cu")
		(net 506)
	)
	(segment
		(start 221.8 148.3)
		(end 221.8015 148.2985)
		(width 0.1)
		(layer "F.Cu")
		(net 507)
	)
	(segment
		(start 221.8 148.665001)
		(end 221.8 148.3)
		(width 0.1)
		(layer "F.Cu")
		(net 507)
	)
	(segment
		(start 221.8015 148.2985)
		(end 221.8015 147.817)
		(width 0.1)
		(layer "F.Cu")
		(net 507)
	)
	(segment
		(start 222.364999 149.23)
		(end 221.8 148.665001)
		(width 0.1)
		(layer "F.Cu")
		(net 507)
	)
	(segment
		(start 223 148.9)
		(end 222.4015 148.3015)
		(width 0.1)
		(layer "F.Cu")
		(net 508)
	)
	(segment
		(start 222.4015 148.3015)
		(end 222.4015 147.817)
		(width 0.1)
		(layer "F.Cu")
		(net 508)
	)
	(segment
		(start 223 150.5)
		(end 223 148.9)
		(width 0.1)
		(layer "F.Cu")
		(net 508)
	)
	(segment
		(start 192.75 121.95)
		(end 193.05 121.65)
		(width 0.15)
		(layer "F.Cu")
		(net 509)
	)
	(segment
		(start 190.8 122.2)
		(end 191.05 121.95)
		(width 0.15)
		(layer "F.Cu")
		(net 509)
	)
	(segment
		(start 191.05 121.95)
		(end 192.75 121.95)
		(width 0.15)
		(layer "F.Cu")
		(net 509)
	)
	(via
		(at 190.8 122.2)
		(size 0.35)
		(drill 0.15)
		(layers "F.Cu" "B.Cu")
		(remove_unused_layers yes)
		(keep_end_layers yes)
		(zone_layer_connections)
		(net 509)
	)
	(via
		(at 205.299 141.101)
		(size 0.35)
		(drill 0.15)
		(layers "F.Cu" "B.Cu")
		(remove_unused_layers yes)
		(keep_end_layers yes)
		(zone_layer_connections)
		(net 509)
	)
	(segment
		(start 198.42 139.5)
		(end 198.9 139.98)
		(width 0.09)
		(layer "In7.Cu")
		(net 509)
	)
	(segment
		(start 195.957451 134.62)
		(end 196.12 134.62)
		(width 0.09)
		(layer "In7.Cu")
		(net 509)
	)
	(segment
		(start 190.8 122.55)
		(end 191.35 123.1)
		(width 0.09)
		(layer "In7.Cu")
		(net 509)
	)
	(segment
		(start 199.031549 139.98)
		(end 199.3 140.248451)
		(width 0.09)
		(layer "In7.Cu")
		(net 509)
	)
	(segment
		(start 192.8 123.1)
		(end 194.5 124.8)
		(width 0.09)
		(layer "In7.Cu")
		(net 509)
	)
	(segment
		(start 190.8 122.2)
		(end 190.8 122.55)
		(width 0.09)
		(layer "In7.Cu")
		(net 509)
	)
	(segment
		(start 191.35 123.1)
		(end 192.8 123.1)
		(width 0.09)
		(layer "In7.Cu")
		(net 509)
	)
	(segment
		(start 194.5 133.162549)
		(end 195.957451 134.62)
		(width 0.09)
		(layer "In7.Cu")
		(net 509)
	)
	(segment
		(start 194.5 124.8)
		(end 194.5 133.162549)
		(width 0.09)
		(layer "In7.Cu")
		(net 509)
	)
	(segment
		(start 197.166451 139.18)
		(end 198.232549 139.18)
		(width 0.09)
		(layer "In7.Cu")
		(net 509)
	)
	(segment
		(start 196.12 134.62)
		(end 196.545 135.045)
		(width 0.09)
		(layer "In7.Cu")
		(net 509)
	)
	(segment
		(start 198.9 139.98)
		(end 199.031549 139.98)
		(width 0.09)
		(layer "In7.Cu")
		(net 509)
	)
	(segment
		(start 199.3 140.248451)
		(end 199.3 140.4)
		(width 0.09)
		(layer "In7.Cu")
		(net 509)
	)
	(segment
		(start 196.545 135.045)
		(end 196.545 138.558549)
		(width 0.09)
		(layer "In7.Cu")
		(net 509)
	)
	(segment
		(start 198.232549 139.18)
		(end 198.42 139.367451)
		(width 0.09)
		(layer "In7.Cu")
		(net 509)
	)
	(segment
		(start 199.6 140.7)
		(end 204.898 140.7)
		(width 0.09)
		(layer "In7.Cu")
		(net 509)
	)
	(segment
		(start 196.545 138.558549)
		(end 197.166451 139.18)
		(width 0.09)
		(layer "In7.Cu")
		(net 509)
	)
	(segment
		(start 199.3 140.4)
		(end 199.6 140.7)
		(width 0.09)
		(layer "In7.Cu")
		(net 509)
	)
	(segment
		(start 204.898 140.7)
		(end 205.299 141.101)
		(width 0.09)
		(layer "In7.Cu")
		(net 509)
	)
	(segment
		(start 198.42 139.367451)
		(end 198.42 139.5)
		(width 0.09)
		(layer "In7.Cu")
		(net 509)
	)
	(segment
		(start 217.050857 153.170226)
		(end 217.243689 153.170226)
		(width 0.11)
		(layer "F.Cu")
		(net 510)
	)
	(segment
		(start 216.628499 153.2715)
		(end 216.949583 153.2715)
		(width 0.11)
		(layer "F.Cu")
		(net 510)
	)
	(segment
		(start 216.949583 153.2715)
		(end 217.050857 153.170226)
		(width 0.11)
		(layer "F.Cu")
		(net 510)
	)
	(segment
		(start 217.243689 153.170226)
		(end 217.370939 153.297476)
		(width 0.11)
		(layer "F.Cu")
		(net 510)
	)
	(via
		(at 217.370939 153.297476)
		(size 0.35)
		(drill 0.15)
		(layers "F.Cu" "B.Cu")
		(remove_unused_layers yes)
		(keep_end_layers yes)
		(zone_layer_connections)
		(net 510)
	)
	(via
		(at 213.715499 153.3)
		(size 0.35)
		(drill 0.15)
		(layers "F.Cu" "B.Cu")
		(remove_unused_layers yes)
		(keep_end_layers yes)
		(zone_layer_connections)
		(net 510)
	)
	(segment
		(start 213.715499 153.3)
		(end 213.854999 153.1605)
		(width 0.09)
		(layer "In9.Cu")
		(net 510)
	)
	(segment
		(start 217.37 153.935648)
		(end 216.945 153.510648)
		(width 0.09)
		(layer "In9.Cu")
		(net 510)
	)
	(segment
		(start 217.37 154.564352)
		(end 217.37 153.935648)
		(width 0.09)
		(layer "In9.Cu")
		(net 510)
	)
	(segment
		(start 215.085648 155.22)
		(end 216.714352 155.22)
		(width 0.09)
		(layer "In9.Cu")
		(net 510)
	)
	(segment
		(start 216.945 153.289352)
		(end 217.069125 153.165227)
		(width 0.09)
		(layer "In9.Cu")
		(net 510)
	)
	(segment
		(start 216.714352 155.22)
		(end 217.37 154.564352)
		(width 0.09)
		(layer "In9.Cu")
		(net 510)
	)
	(segment
		(start 217.069125 153.165227)
		(end 217.23869 153.165227)
		(width 0.09)
		(layer "In9.Cu")
		(net 510)
	)
	(segment
		(start 213.854999 153.1605)
		(end 214.051148 153.1605)
		(width 0.09)
		(layer "In9.Cu")
		(net 510)
	)
	(segment
		(start 214.051148 153.1605)
		(end 214.28 153.389352)
		(width 0.09)
		(layer "In9.Cu")
		(net 510)
	)
	(segment
		(start 214.28 154.414352)
		(end 215.085648 155.22)
		(width 0.09)
		(layer "In9.Cu")
		(net 510)
	)
	(segment
		(start 214.28 153.389352)
		(end 214.28 154.414352)
		(width 0.09)
		(layer "In9.Cu")
		(net 510)
	)
	(segment
		(start 216.945 153.510648)
		(end 216.945 153.289352)
		(width 0.09)
		(layer "In9.Cu")
		(net 510)
	)
	(segment
		(start 217.23869 153.165227)
		(end 217.370939 153.297476)
		(width 0.09)
		(layer "In9.Cu")
		(net 510)
	)
	(segment
		(start 216.937274 152.8715)
		(end 217.035999 152.970226)
		(width 0.11)
		(layer "F.Cu")
		(net 511)
	)
	(segment
		(start 217.370939 152.842976)
		(end 217.243689 152.970226)
		(width 0.11)
		(layer "F.Cu")
		(net 511)
	)
	(segment
		(start 217.243689 152.970226)
		(end 217.035999 152.970226)
		(width 0.11)
		(layer "F.Cu")
		(net 511)
	)
	(segment
		(start 216.628498 152.8715)
		(end 216.937274 152.8715)
		(width 0.11)
		(layer "F.Cu")
		(net 511)
	)
	(via
		(at 213.73 152.8455)
		(size 0.35)
		(drill 0.15)
		(layers "F.Cu" "B.Cu")
		(remove_unused_layers yes)
		(keep_end_layers yes)
		(zone_layer_connections)
		(net 511)
	)
	(via
		(at 217.370939 152.842976)
		(size 0.35)
		(drill 0.15)
		(layers "F.Cu" "B.Cu")
		(remove_unused_layers yes)
		(keep_end_layers yes)
		(zone_layer_connections)
		(net 511)
	)
	(segment
		(start 213.73 152.8455)
		(end 213.854999 152.970499)
		(width 0.09)
		(layer "In9.Cu")
		(net 511)
	)
	(segment
		(start 213.854999 152.970499)
		(end 214.129851 152.970499)
		(width 0.09)
		(layer "In9.Cu")
		(net 511)
	)
	(segment
		(start 216.635648 155.03)
		(end 217.18 154.485648)
		(width 0.09)
		(layer "In9.Cu")
		(net 511)
	)
	(segment
		(start 216.990423 152.975225)
		(end 217.23869 152.975225)
		(width 0.09)
		(layer "In9.Cu")
		(net 511)
	)
	(segment
		(start 214.129851 152.970499)
		(end 214.47 153.310648)
		(width 0.09)
		(layer "In9.Cu")
		(net 511)
	)
	(segment
		(start 215.164352 155.03)
		(end 216.635648 155.03)
		(width 0.09)
		(layer "In9.Cu")
		(net 511)
	)
	(segment
		(start 216.755 153.589352)
		(end 216.755 153.210648)
		(width 0.09)
		(layer "In9.Cu")
		(net 511)
	)
	(segment
		(start 214.47 153.310648)
		(end 214.47 154.335648)
		(width 0.09)
		(layer "In9.Cu")
		(net 511)
	)
	(segment
		(start 217.18 154.485648)
		(end 217.18 154.014352)
		(width 0.09)
		(layer "In9.Cu")
		(net 511)
	)
	(segment
		(start 217.18 154.014352)
		(end 216.755 153.589352)
		(width 0.09)
		(layer "In9.Cu")
		(net 511)
	)
	(segment
		(start 214.47 154.335648)
		(end 215.164352 155.03)
		(width 0.09)
		(layer "In9.Cu")
		(net 511)
	)
	(segment
		(start 217.23869 152.975225)
		(end 217.370939 152.842976)
		(width 0.09)
		(layer "In9.Cu")
		(net 511)
	)
	(segment
		(start 216.755 153.210648)
		(end 216.990423 152.975225)
		(width 0.09)
		(layer "In9.Cu")
		(net 511)
	)
	(segment
		(start 216.083 154.520403)
		(end 216.083 154.31)
		(width 0.11)
		(layer "F.Cu")
		(net 512)
	)
	(segment
		(start 215.9835 154.2105)
		(end 215.9835 153.9155)
		(width 0.11)
		(layer "F.Cu")
		(net 512)
	)
	(segment
		(start 216.083 154.31)
		(end 215.9835 154.2105)
		(width 0.11)
		(layer "F.Cu")
		(net 512)
	)
	(segment
		(start 215.963 154.640403)
		(end 216.083 154.520403)
		(width 0.11)
		(layer "F.Cu")
		(net 512)
	)
	(via
		(at 216.115 146.45)
		(size 0.35)
		(drill 0.15)
		(layers "F.Cu" "B.Cu")
		(remove_unused_layers yes)
		(keep_end_layers yes)
		(zone_layer_connections)
		(net 512)
	)
	(via
		(at 215.963 154.640403)
		(size 0.35)
		(drill 0.15)
		(layers "F.Cu" "B.Cu")
		(remove_unused_layers yes)
		(keep_end_layers yes)
		(zone_layer_connections)
		(net 512)
	)
	(segment
		(start 215.960001 146.099351)
		(end 216.089352 145.97)
		(width 0.09)
		(layer "In9.Cu")
		(net 512)
	)
	(segment
		(start 216.555 146.85)
		(end 216.555 146.9)
		(width 0.09)
		(layer "In9.Cu")
		(net 512)
	)
	(segment
		(start 216.805 147.75)
		(end 216.805 152.435648)
		(width 0.09)
		(layer "In9.Cu")
		(net 512)
	)
	(segment
		(start 216.805 152.435648)
		(end 216.092501 153.148147)
		(width 0.09)
		(layer "In9.Cu")
		(net 512)
	)
	(segment
		(start 216.555 147.45)
		(end 216.555 147.5)
		(width 0.09)
		(layer "In9.Cu")
		(net 512)
	)
	(segment
		(start 216.092501 154.510902)
		(end 215.963 154.640403)
		(width 0.09)
		(layer "In9.Cu")
		(net 512)
	)
	(segment
		(start 216.385648 145.97)
		(end 216.805 146.389352)
		(width 0.09)
		(layer "In9.Cu")
		(net 512)
	)
	(segment
		(start 216.089352 145.97)
		(end 216.385648 145.97)
		(width 0.09)
		(layer "In9.Cu")
		(net 512)
	)
	(segment
		(start 215.960001 146.295001)
		(end 215.960001 146.099351)
		(width 0.09)
		(layer "In9.Cu")
		(net 512)
	)
	(segment
		(start 216.805 146.389352)
		(end 216.805 146.6)
		(width 0.09)
		(layer "In9.Cu")
		(net 512)
	)
	(segment
		(start 216.805 147.15)
		(end 216.805 147.2)
		(width 0.09)
		(layer "In9.Cu")
		(net 512)
	)
	(segment
		(start 216.115 146.45)
		(end 215.960001 146.295001)
		(width 0.09)
		(layer "In9.Cu")
		(net 512)
	)
	(segment
		(start 216.092501 153.148147)
		(end 216.092501 154.510902)
		(width 0.09)
		(layer "In9.Cu")
		(net 512)
	)
	(arc
		(start 216.68 147.325)
		(mid 216.591612 147.361612)
		(end 216.555 147.45)
		(width 0.09)
		(layer "In9.Cu")
		(net 512)
	)
	(arc
		(start 216.555 147.5)
		(mid 216.591612 147.588388)
		(end 216.68 147.625)
		(width 0.09)
		(layer "In9.Cu")
		(net 512)
	)
	(arc
		(start 216.68 146.725)
		(mid 216.591612 146.761612)
		(end 216.555 146.85)
		(width 0.09)
		(layer "In9.Cu")
		(net 512)
	)
	(arc
		(start 216.68 147.025)
		(mid 216.768388 147.061612)
		(end 216.805 147.15)
		(width 0.09)
		(layer "In9.Cu")
		(net 512)
	)
	(arc
		(start 216.805 146.6)
		(mid 216.768388 146.688388)
		(end 216.68 146.725)
		(width 0.09)
		(layer "In9.Cu")
		(net 512)
	)
	(arc
		(start 216.805 147.2)
		(mid 216.768388 147.288388)
		(end 216.68 147.325)
		(width 0.09)
		(layer "In9.Cu")
		(net 512)
	)
	(arc
		(start 216.68 147.625)
		(mid 216.768388 147.661612)
		(end 216.805 147.75)
		(width 0.09)
		(layer "In9.Cu")
		(net 512)
	)
	(arc
		(start 216.555 146.9)
		(mid 216.591612 146.988388)
		(end 216.68 147.025)
		(width 0.09)
		(layer "In9.Cu")
		(net 512)
	)
	(segment
		(start 216.283 154.31)
		(end 216.3825 154.2105)
		(width 0.11)
		(layer "F.Cu")
		(net 513)
	)
	(segment
		(start 216.3825 154.2105)
		(end 216.3825 153.9155)
		(width 0.11)
		(layer "F.Cu")
		(net 513)
	)
	(segment
		(start 216.283 154.5114)
		(end 216.283 154.31)
		(width 0.11)
		(layer "F.Cu")
		(net 513)
	)
	(segment
		(start 216.412003 154.640403)
		(end 216.283 154.5114)
		(width 0.11)
		(layer "F.Cu")
		(net 513)
	)
	(via
		(at 215.615 146.45)
		(size 0.35)
		(drill 0.15)
		(layers "F.Cu" "B.Cu")
		(remove_unused_layers yes)
		(keep_end_layers yes)
		(zone_layer_connections)
		(net 513)
	)
	(via
		(at 216.412003 154.640403)
		(size 0.35)
		(drill 0.15)
		(layers "F.Cu" "B.Cu")
		(remove_unused_layers yes)
		(keep_end_layers yes)
		(zone_layer_connections)
		(net 513)
	)
	(segment
		(start 216.995 152.514352)
		(end 216.995 146.310648)
		(width 0.09)
		(layer "In9.Cu")
		(net 513)
	)
	(segment
		(start 216.282502 153.22685)
		(end 216.995 152.514352)
		(width 0.09)
		(layer "In9.Cu")
		(net 513)
	)
	(segment
		(start 215.769999 146.295001)
		(end 215.615 146.45)
		(width 0.09)
		(layer "In9.Cu")
		(net 513)
	)
	(segment
		(start 216.995 146.310648)
		(end 216.464352 145.78)
		(width 0.09)
		(layer "In9.Cu")
		(net 513)
	)
	(segment
		(start 216.010648 145.78)
		(end 215.769999 146.020649)
		(width 0.09)
		(layer "In9.Cu")
		(net 513)
	)
	(segment
		(start 216.464352 145.78)
		(end 216.010648 145.78)
		(width 0.09)
		(layer "In9.Cu")
		(net 513)
	)
	(segment
		(start 216.412003 154.640403)
		(end 216.282502 154.510902)
		(width 0.09)
		(layer "In9.Cu")
		(net 513)
	)
	(segment
		(start 215.769999 146.020649)
		(end 215.769999 146.295001)
		(width 0.09)
		(layer "In9.Cu")
		(net 513)
	)
	(segment
		(start 216.282502 154.510902)
		(end 216.282502 153.22685)
		(width 0.09)
		(layer "In9.Cu")
		(net 513)
	)
	(segment
		(start 212.633 154.31)
		(end 212.633 154.520403)
		(width 0.11)
		(layer "F.Cu")
		(net 514)
	)
	(segment
		(start 212.5335 153.9155)
		(end 212.5335 154.2105)
		(width 0.11)
		(layer "F.Cu")
		(net 514)
	)
	(segment
		(start 212.5335 154.2105)
		(end 212.633 154.31)
		(width 0.11)
		(layer "F.Cu")
		(net 514)
	)
	(segment
		(start 212.633 154.520403)
		(end 212.513 154.640403)
		(width 0.11)
		(layer "F.Cu")
		(net 514)
	)
	(via
		(at 213.25 148.29)
		(size 0.35)
		(drill 0.15)
		(layers "F.Cu" "B.Cu")
		(remove_unused_layers yes)
		(keep_end_layers yes)
		(zone_layer_connections)
		(net 514)
	)
	(via
		(at 212.513 154.640403)
		(size 0.35)
		(drill 0.15)
		(layers "F.Cu" "B.Cu")
		(remove_unused_layers yes)
		(keep_end_layers yes)
		(zone_layer_connections)
		(net 514)
	)
	(segment
		(start 211.814352 155.055)
		(end 212.535648 155.055)
		(width 0.09)
		(layer "In9.Cu")
		(net 514)
	)
	(segment
		(start 211.87 153.754048)
		(end 211.87 153.964352)
		(width 0.09)
		(layer "In9.Cu")
		(net 514)
	)
	(segment
		(start 211.545 154.289352)
		(end 211.545 154.785648)
		(width 0.09)
		(layer "In9.Cu")
		(net 514)
	)
	(segment
		(start 211.545 154.785648)
		(end 211.814352 155.055)
		(width 0.09)
		(layer "In9.Cu")
		(net 514)
	)
	(segment
		(start 213.954351 148.444999)
		(end 214.376452 148.8671)
		(width 0.09)
		(layer "In9.Cu")
		(net 514)
	)
	(segment
		(start 212.009525 153.614524)
		(end 212.009524 153.614524)
		(width 0.09)
		(layer "In9.Cu")
		(net 514)
	)
	(segment
		(start 211.87 153.035648)
		(end 211.87 153.125)
		(width 0.09)
		(layer "In9.Cu")
		(net 514)
	)
	(segment
		(start 212.149049 153.404048)
		(end 212.149049 153.475)
		(width 0.09)
		(layer "In9.Cu")
		(net 514)
	)
	(segment
		(start 213.404999 148.444999)
		(end 213.954351 148.444999)
		(width 0.09)
		(layer "In9.Cu")
		(net 514)
	)
	(segment
		(start 214.376452 148.8671)
		(end 214.376452 149.3329)
		(width 0.09)
		(layer "In9.Cu")
		(net 514)
	)
	(segment
		(start 212.009524 153.264524)
		(end 212.009525 153.264524)
		(width 0.09)
		(layer "In9.Cu")
		(net 514)
	)
	(segment
		(start 211.72 152.885648)
		(end 211.87 153.035648)
		(width 0.09)
		(layer "In9.Cu")
		(net 514)
	)
	(segment
		(start 213.25 148.29)
		(end 213.404999 148.444999)
		(width 0.09)
		(layer "In9.Cu")
		(net 514)
	)
	(segment
		(start 212.642501 154.948147)
		(end 212.642501 154.769904)
		(width 0.09)
		(layer "In9.Cu")
		(net 514)
	)
	(segment
		(start 212.535648 155.055)
		(end 212.642501 154.948147)
		(width 0.09)
		(layer "In9.Cu")
		(net 514)
	)
	(segment
		(start 214.376452 149.3329)
		(end 211.72 151.989352)
		(width 0.09)
		(layer "In9.Cu")
		(net 514)
	)
	(segment
		(start 211.87 153.964352)
		(end 211.545 154.289352)
		(width 0.09)
		(layer "In9.Cu")
		(net 514)
	)
	(segment
		(start 211.72 151.989352)
		(end 211.72 152.885648)
		(width 0.09)
		(layer "In9.Cu")
		(net 514)
	)
	(segment
		(start 212.642501 154.769904)
		(end 212.513 154.640403)
		(width 0.09)
		(layer "In9.Cu")
		(net 514)
	)
	(arc
		(start 212.009524 153.614524)
		(mid 211.910866 153.65539)
		(end 211.87 153.754048)
		(width 0.09)
		(layer "In9.Cu")
		(net 514)
	)
	(arc
		(start 211.87 153.125)
		(mid 211.910866 153.223658)
		(end 212.009524 153.264524)
		(width 0.09)
		(layer "In9.Cu")
		(net 514)
	)
	(arc
		(start 212.149049 153.475)
		(mid 212.108183 153.573658)
		(end 212.009525 153.614524)
		(width 0.09)
		(layer "In9.Cu")
		(net 514)
	)
	(arc
		(start 212.009525 153.264524)
		(mid 212.108183 153.30539)
		(end 212.149049 153.404048)
		(width 0.09)
		(layer "In9.Cu")
		(net 514)
	)
	(segment
		(start 212.833 154.5114)
		(end 212.833 154.31)
		(width 0.11)
		(layer "F.Cu")
		(net 515)
	)
	(segment
		(start 212.833 154.31)
		(end 212.9325 154.2105)
		(width 0.11)
		(layer "F.Cu")
		(net 515)
	)
	(segment
		(start 212.9325 154.2105)
		(end 212.9325 153.9155)
		(width 0.11)
		(layer "F.Cu")
		(net 515)
	)
	(segment
		(start 212.962003 154.640403)
		(end 212.833 154.5114)
		(width 0.11)
		(layer "F.Cu")
		(net 515)
	)
	(via
		(at 213.25 148.789999)
		(size 0.35)
		(drill 0.15)
		(layers "F.Cu" "B.Cu")
		(remove_unused_layers yes)
		(keep_end_layers yes)
		(zone_layer_connections)
		(net 515)
	)
	(via
		(at 212.962003 154.640403)
		(size 0.35)
		(drill 0.15)
		(layers "F.Cu" "B.Cu")
		(remove_unused_layers yes)
		(keep_end_layers yes)
		(zone_layer_connections)
		(net 515)
	)
	(segment
		(start 214.186452 148.945804)
		(end 213.875648 148.635)
		(width 0.09)
		(layer "In9.Cu")
		(net 515)
	)
	(segment
		(start 212.832502 155.02685)
		(end 212.614352 155.245)
		(width 0.09)
		(layer "In9.Cu")
		(net 515)
	)
	(segment
		(start 211.355 154.864352)
		(end 211.355 154.210648)
		(width 0.09)
		(layer "In9.Cu")
		(net 515)
	)
	(segment
		(start 211.735648 155.245)
		(end 211.355 154.864352)
		(width 0.09)
		(layer "In9.Cu")
		(net 515)
	)
	(segment
		(start 211.68 153.885648)
		(end 211.68 153.114352)
		(width 0.09)
		(layer "In9.Cu")
		(net 515)
	)
	(segment
		(start 213.404999 148.635)
		(end 213.25 148.789999)
		(width 0.09)
		(layer "In9.Cu")
		(net 515)
	)
	(segment
		(start 213.875648 148.635)
		(end 213.404999 148.635)
		(width 0.09)
		(layer "In9.Cu")
		(net 515)
	)
	(segment
		(start 211.355 154.210648)
		(end 211.68 153.885648)
		(width 0.09)
		(layer "In9.Cu")
		(net 515)
	)
	(segment
		(start 212.614352 155.245)
		(end 211.735648 155.245)
		(width 0.09)
		(layer "In9.Cu")
		(net 515)
	)
	(segment
		(start 211.53 152.964352)
		(end 211.53 151.910648)
		(width 0.09)
		(layer "In9.Cu")
		(net 515)
	)
	(segment
		(start 211.68 153.114352)
		(end 211.53 152.964352)
		(width 0.09)
		(layer "In9.Cu")
		(net 515)
	)
	(segment
		(start 212.832502 154.769904)
		(end 212.832502 155.02685)
		(width 0.09)
		(layer "In9.Cu")
		(net 515)
	)
	(segment
		(start 214.186452 149.254196)
		(end 214.186452 148.945804)
		(width 0.09)
		(layer "In9.Cu")
		(net 515)
	)
	(segment
		(start 211.53 151.910648)
		(end 214.186452 149.254196)
		(width 0.09)
		(layer "In9.Cu")
		(net 515)
	)
	(segment
		(start 212.962003 154.640403)
		(end 212.832502 154.769904)
		(width 0.09)
		(layer "In9.Cu")
		(net 515)
	)
	(segment
		(start 221.5 137.425)
		(end 220.775 137.425)
		(width 0.256)
		(layer "B.Cu")
		(net 516)
	)
	(segment
		(start 221.9245 139.615)
		(end 221.9245 138.136)
		(width 0.256)
		(layer "B.Cu")
		(net 516)
	)
	(segment
		(start 220.425 137.775)
		(end 219.455 137.775)
		(width 0.256)
		(layer "B.Cu")
		(net 516)
	)
	(segment
		(start 221.9245 137.8495)
		(end 221.5 137.425)
		(width 0.256)
		(layer "B.Cu")
		(net 516)
	)
	(segment
		(start 220.775 137.425)
		(end 220.425 137.775)
		(width 0.256)
		(layer "B.Cu")
		(net 516)
	)
	(segment
		(start 221.9245 138.136)
		(end 221.9245 137.8495)
		(width 0.256)
		(layer "B.Cu")
		(net 516)
	)
	(segment
		(start 221 139.65)
		(end 220.125 138.775)
		(width 0.256)
		(layer "B.Cu")
		(net 517)
	)
	(segment
		(start 221.3905 139.65)
		(end 221 139.65)
		(width 0.256)
		(layer "B.Cu")
		(net 517)
	)
	(segment
		(start 220.125 138.775)
		(end 219.455 138.775)
		(width 0.256)
		(layer "B.Cu")
		(net 517)
	)
	(segment
		(start 221.4255 139.615)
		(end 221.3905 139.65)
		(width 0.256)
		(layer "B.Cu")
		(net 517)
	)
	(segment
		(start 220.05 136.775)
		(end 220.825 136)
		(width 0.4)
		(layer "B.Cu")
		(net 518)
	)
	(segment
		(start 220.825 136)
		(end 221.9245 136)
		(width 0.4)
		(layer "B.Cu")
		(net 518)
	)
	(segment
		(start 221.9245 136)
		(end 221.9245 135.261)
		(width 0.256)
		(layer "B.Cu")
		(net 518)
	)
	(segment
		(start 219.455 136.775)
		(end 220.05 136.775)
		(width 0.4)
		(layer "B.Cu")
		(net 518)
	)
	(segment
		(start 221.9245 136.74)
		(end 221.9245 136)
		(width 0.256)
		(layer "B.Cu")
		(net 518)
	)
	(segment
		(start 197.299 131.501)
		(end 197.299 131.5)
		(width 0.4)
		(layer "F.Cu")
		(net 519)
	)
	(segment
		(start 197.299 131.5)
		(end 196.5 130.701)
		(width 0.4)
		(layer "F.Cu")
		(net 519)
	)
	(via
		(at 196.5 130.701)
		(size 0.35)
		(drill 0.15)
		(layers "F.Cu" "B.Cu")
		(remove_unused_layers yes)
		(keep_end_layers yes)
		(zone_layer_connections)
		(net 519)
	)
	(via
		(at 212.675 139.9)
		(size 0.35)
		(drill 0.15)
		(layers "F.Cu" "B.Cu")
		(remove_unused_layers yes)
		(keep_end_layers yes)
		(zone_layer_connections)
		(net 519)
	)
	(via
		(at 218.475 136.75)
		(size 0.35)
		(drill 0.15)
		(layers "F.Cu" "B.Cu")
		(remove_unused_layers yes)
		(keep_end_layers yes)
		(zone_layer_connections)
		(net 519)
	)
	(segment
		(start 218.495 136.775)
		(end 218.495 136.77)
		(width 0.1)
		(layer "B.Cu")
		(net 519)
	)
	(segment
		(start 218.495 136.77)
		(end 218.475 136.75)
		(width 0.1)
		(layer "B.Cu")
		(net 519)
	)
	(segment
		(start 206.925 136.45)
		(end 206.925 137.7)
		(width 0.256)
		(layer "In2.Cu")
		(net 519)
	)
	(segment
		(start 211.075 138.825)
		(end 212.15 139.9)
		(width 0.256)
		(layer "In2.Cu")
		(net 519)
	)
	(segment
		(start 204.9 134.15)
		(end 204.9 131.23)
		(width 0.2)
		(layer "In2.Cu")
		(net 519)
	)
	(segment
		(start 204.9 134.15)
		(end 204.9 134.3)
		(width 0.256)
		(layer "In2.Cu")
		(net 519)
	)
	(segment
		(start 206.4 135.925)
		(end 206.925 136.45)
		(width 0.256)
		(layer "In2.Cu")
		(net 519)
	)
	(segment
		(start 204.9 134.3)
		(end 204.69 134.51)
		(width 0.256)
		(layer "In2.Cu")
		(net 519)
	)
	(segment
		(start 205.075 135.925)
		(end 206.4 135.925)
		(width 0.256)
		(layer "In2.Cu")
		(net 519)
	)
	(segment
		(start 204.69 135.54)
		(end 205.075 135.925)
		(width 0.256)
		(layer "In2.Cu")
		(net 519)
	)
	(segment
		(start 212.15 139.9)
		(end 212.675 139.9)
		(width 0.256)
		(layer "In2.Cu")
		(net 519)
	)
	(segment
		(start 204.9 131.23)
		(end 204.76 131.09)
		(width 0.2)
		(layer "In2.Cu")
		(net 519)
	)
	(segment
		(start 208.05 138.825)
		(end 211.075 138.825)
		(width 0.256)
		(layer "In2.Cu")
		(net 519)
	)
	(segment
		(start 206.925 137.7)
		(end 208.05 138.825)
		(width 0.256)
		(layer "In2.Cu")
		(net 519)
	)
	(segment
		(start 204.69 134.51)
		(end 204.69 135.54)
		(width 0.256)
		(layer "In2.Cu")
		(net 519)
	)
	(segment
		(start 196.889 131.09)
		(end 196.5 130.701)
		(width 0.2)
		(layer "In2.Cu")
		(net 519)
	)
	(segment
		(start 204.76 131.09)
		(end 196.889 131.09)
		(width 0.2)
		(layer "In2.Cu")
		(net 519)
	)
	(segment
		(start 212.675 139.655071)
		(end 215.580071 136.75)
		(width 0.256)
		(layer "In9.Cu")
		(net 519)
	)
	(segment
		(start 215.580071 136.75)
		(end 218.5 136.75)
		(width 0.256)
		(layer "In9.Cu")
		(net 519)
	)
	(segment
		(start 212.675 139.9)
		(end 212.675 139.655071)
		(width 0.256)
		(layer "In9.Cu")
		(net 519)
	)
	(segment
		(start 223.635 148.935)
		(end 223.0015 148.3015)
		(width 0.1)
		(layer "F.Cu")
		(net 520)
	)
	(segment
		(start 223.635 149.23)
		(end 223.635 148.935)
		(width 0.1)
		(layer "F.Cu")
		(net 520)
	)
	(segment
		(start 223.0015 148.3015)
		(end 223.0015 147.817)
		(width 0.1)
		(layer "F.Cu")
		(net 520)
	)
	(segment
		(start 228.095 149.405)
		(end 224.805 149.405)
		(width 0.1)
		(layer "F.Cu")
		(net 521)
	)
	(segment
		(start 224.805 149.405)
		(end 223.6015 148.2015)
		(width 0.1)
		(layer "F.Cu")
		(net 521)
	)
	(segment
		(start 228.47 149.03)
		(end 228.095 149.405)
		(width 0.1)
		(layer "F.Cu")
		(net 521)
	)
	(segment
		(start 223.6015 148.2015)
		(end 223.6015 147.817)
		(width 0.1)
		(layer "F.Cu")
		(net 521)
	)
	(segment
		(start 181.803968 151.146032)
		(end 181.859904 151.201968)
		(width 0.174)
		(layer "F.Cu")
		(net 522)
	)
	(segment
		(start 181.859904 151.201968)
		(end 181.859904 151.984531)
		(width 0.174)
		(layer "F.Cu")
		(net 522)
	)
	(via
		(at 188.184404 148.123281)
		(size 0.35)
		(drill 0.15)
		(layers "F.Cu" "B.Cu")
		(remove_unused_layers yes)
		(keep_end_layers yes)
		(zone_layer_connections)
		(net 522)
	)
	(via
		(at 187.184404 148.123281)
		(size 0.35)
		(drill 0.15)
		(layers "F.Cu" "B.Cu")
		(remove_unused_layers yes)
		(keep_end_layers yes)
		(zone_layer_connections)
		(net 522)
	)
	(via
		(at 188.184404 148.698281)
		(size 0.35)
		(drill 0.15)
		(layers "F.Cu" "B.Cu")
		(remove_unused_layers yes)
		(keep_end_layers yes)
		(zone_layer_connections)
		(net 522)
	)
	(via
		(at 186.684904 148.385281)
		(size 0.35)
		(drill 0.15)
		(layers "F.Cu" "B.Cu")
		(remove_unused_layers yes)
		(keep_end_layers yes)
		(zone_layer_connections)
		(net 522)
	)
	(via
		(at 181.803968 151.146032)
		(size 0.35)
		(drill 0.15)
		(layers "F.Cu" "B.Cu")
		(remove_unused_layers yes)
		(keep_end_layers yes)
		(zone_layer_connections)
		(net 522)
	)
	(via
		(at 187.684904 148.381281)
		(size 0.35)
		(drill 0.15)
		(layers "F.Cu" "B.Cu")
		(remove_unused_layers yes)
		(keep_end_layers yes)
		(zone_layer_connections)
		(net 522)
	)
	(via
		(at 186.184404 148.123281)
		(size 0.35)
		(drill 0.15)
		(layers "F.Cu" "B.Cu")
		(remove_unused_layers yes)
		(keep_end_layers yes)
		(zone_layer_connections)
		(net 522)
	)
	(via
		(at 188.684904 148.381281)
		(size 0.35)
		(drill 0.15)
		(layers "F.Cu" "B.Cu")
		(remove_unused_layers yes)
		(keep_end_layers yes)
		(zone_layer_connections)
		(net 522)
	)
	(via
		(at 186.184404 148.698281)
		(size 0.35)
		(drill 0.15)
		(layers "F.Cu" "B.Cu")
		(remove_unused_layers yes)
		(keep_end_layers yes)
		(zone_layer_connections)
		(net 522)
	)
	(via
		(at 187.184404 148.698281)
		(size 0.35)
		(drill 0.15)
		(layers "F.Cu" "B.Cu")
		(remove_unused_layers yes)
		(keep_end_layers yes)
		(zone_layer_connections)
		(net 522)
	)
	(segment
		(start 181.803968 151.146032)
		(end 181.45 151.5)
		(width 0.174)
		(layer "B.Cu")
		(net 522)
	)
	(segment
		(start 183.3 151.404)
		(end 183.3 151.545)
		(width 0.174)
		(layer "B.Cu")
		(net 522)
	)
	(segment
		(start 181.803968 151.146032)
		(end 181.896 151.054)
		(width 0.174)
		(layer "B.Cu")
		(net 522)
	)
	(segment
		(start 181.896 151.054)
		(end 182.95 151.054)
		(width 0.174)
		(layer "B.Cu")
		(net 522)
	)
	(segment
		(start 181.45 151.5)
		(end 181.45 151.569)
		(width 0.174)
		(layer "B.Cu")
		(net 522)
	)
	(segment
		(start 182.95 151.054)
		(end 183.3 151.404)
		(width 0.174)
		(layer "B.Cu")
		(net 522)
	)
	(segment
		(start 181.803968 151.146032)
		(end 181.896 151.054)
		(width 0.174)
		(layer "In7.Cu")
		(net 522)
	)
	(segment
		(start 181.896 151.054)
		(end 183.9 151.054)
		(width 0.174)
		(layer "In7.Cu")
		(net 522)
	)
	(segment
		(start 183.9 151.054)
		(end 184.75 150.204)
		(width 0.174)
		(layer "In7.Cu")
		(net 522)
	)
	(segment
		(start 185.861123 148.375)
		(end 186.184404 148.698281)
		(width 0.174)
		(layer "In7.Cu")
		(net 522)
	)
	(segment
		(start 185.05 148.375)
		(end 185.861123 148.375)
		(width 0.174)
		(layer "In7.Cu")
		(net 522)
	)
	(segment
		(start 184.75 150.204)
		(end 184.75 148.675)
		(width 0.174)
		(layer "In7.Cu")
		(net 522)
	)
	(segment
		(start 184.75 148.675)
		(end 185.05 148.375)
		(width 0.174)
		(layer "In7.Cu")
		(net 522)
	)
	(segment
		(start 225.092 146.242)
		(end 224.792 145.942)
		(width 0.1)
		(layer "F.Cu")
		(net 524)
	)
	(segment
		(start 227.2 147.18)
		(end 226.262 146.242)
		(width 0.1)
		(layer "F.Cu")
		(net 524)
	)
	(segment
		(start 226.262 146.242)
		(end 225.092 146.242)
		(width 0.1)
		(layer "F.Cu")
		(net 524)
	)
	(segment
		(start 224.792 145.942)
		(end 224.3765 145.942)
		(width 0.1)
		(layer "F.Cu")
		(net 524)
	)
	(segment
		(start 226.945 146.545)
		(end 226.25 145.85)
		(width 0.1)
		(layer "F.Cu")
		(net 525)
	)
	(segment
		(start 225.942 145.042)
		(end 225.09225 145.042)
		(width 0.1)
		(layer "F.Cu")
		(net 525)
	)
	(segment
		(start 225.09225 145.042)
		(end 224.79225 145.342)
		(width 0.1)
		(layer "F.Cu")
		(net 525)
	)
	(segment
		(start 226.25 145.85)
		(end 226.25 145.35)
		(width 0.1)
		(layer "F.Cu")
		(net 525)
	)
	(segment
		(start 226.25 145.35)
		(end 225.942 145.042)
		(width 0.1)
		(layer "F.Cu")
		(net 525)
	)
	(segment
		(start 228.47 146.545)
		(end 226.945 146.545)
		(width 0.1)
		(layer "F.Cu")
		(net 525)
	)
	(segment
		(start 224.79225 145.342)
		(end 224.3765 145.342)
		(width 0.1)
		(layer "F.Cu")
		(net 525)
	)
	(segment
		(start 226.032 144.742)
		(end 225.5765 144.742)
		(width 0.1)
		(layer "F.Cu")
		(net 526)
	)
	(segment
		(start 227.2 145.91)
		(end 226.032 144.742)
		(width 0.1)
		(layer "F.Cu")
		(net 526)
	)
	(segment
		(start 226.45 144.75916)
		(end 226.45 144.5)
		(width 0.1)
		(layer "F.Cu")
		(net 527)
	)
	(segment
		(start 226.092 144.142)
		(end 225.5765 144.142)
		(width 0.1)
		(layer "F.Cu")
		(net 527)
	)
	(segment
		(start 228.47 145.275)
		(end 226.96584 145.275)
		(width 0.1)
		(layer "F.Cu")
		(net 527)
	)
	(segment
		(start 226.45 144.5)
		(end 226.092 144.142)
		(width 0.1)
		(layer "F.Cu")
		(net 527)
	)
	(segment
		(start 226.96584 145.275)
		(end 226.45 144.75916)
		(width 0.1)
		(layer "F.Cu")
		(net 527)
	)
	(segment
		(start 226.102 143.542)
		(end 225.5765 143.542)
		(width 0.1)
		(layer "F.Cu")
		(net 528)
	)
	(segment
		(start 227.2 144.64)
		(end 226.102 143.542)
		(width 0.1)
		(layer "F.Cu")
		(net 528)
	)
	(segment
		(start 228.47 144.005)
		(end 227.305 144.005)
		(width 0.1)
		(layer "F.Cu")
		(net 529)
	)
	(segment
		(start 225.8345 143.2)
		(end 225.5765 142.942)
		(width 0.1)
		(layer "F.Cu")
		(net 529)
	)
	(segment
		(start 227.305 144.005)
		(end 226.5 143.2)
		(width 0.1)
		(layer "F.Cu")
		(net 529)
	)
	(segment
		(start 226.5 143.2)
		(end 225.8345 143.2)
		(width 0.1)
		(layer "F.Cu")
		(net 529)
	)
	(segment
		(start 219.7 149.75)
		(end 219.7 149.15)
		(width 0.1)
		(layer "F.Cu")
		(net 530)
	)
	(segment
		(start 220.3115 148.5385)
		(end 220.3115 146.907)
		(width 0.1)
		(layer "F.Cu")
		(net 530)
	)
	(segment
		(start 221.73 150.5)
		(end 221.28 150.05)
		(width 0.1)
		(layer "F.Cu")
		(net 530)
	)
	(segment
		(start 220 150.05)
		(end 219.7 149.75)
		(width 0.1)
		(layer "F.Cu")
		(net 530)
	)
	(segment
		(start 221.28 150.05)
		(end 220 150.05)
		(width 0.1)
		(layer "F.Cu")
		(net 530)
	)
	(segment
		(start 219.7 149.15)
		(end 220.3115 148.5385)
		(width 0.1)
		(layer "F.Cu")
		(net 530)
	)
	(segment
		(start 220.3115 146.907)
		(end 220.6015 146.617)
		(width 0.1)
		(layer "F.Cu")
		(net 530)
	)
	(via
		(at 203.75 132.25)
		(size 0.35)
		(drill 0.15)
		(layers "F.Cu" "B.Cu")
		(remove_unused_layers yes)
		(keep_end_layers yes)
		(zone_layer_connections)
		(net 537)
	)
	(via
		(at 205.649 144.151)
		(size 0.35)
		(drill 0.15)
		(layers "F.Cu" "B.Cu")
		(remove_unused_layers yes)
		(keep_end_layers yes)
		(zone_layer_connections)
		(net 537)
	)
	(segment
		(start 203.75 133.45)
		(end 203.75 132.25)
		(width 0.1)
		(layer "In2.Cu")
		(net 537)
	)
	(segment
		(start 204.625 136.725)
		(end 204.325 136.725)
		(width 0.1)
		(layer "In2.Cu")
		(net 537)
	)
	(segment
		(start 205.649 143.249)
		(end 204.9 142.5)
		(width 0.1)
		(layer "In2.Cu")
		(net 537)
	)
	(segment
		(start 204.325 136.725)
		(end 204.05 136.45)
		(width 0.1)
		(layer "In2.Cu")
		(net 537)
	)
	(segment
		(start 204.9 137)
		(end 204.625 136.725)
		(width 0.1)
		(layer "In2.Cu")
		(net 537)
	)
	(segment
		(start 205.649 144.151)
		(end 205.649 143.249)
		(width 0.1)
		(layer "In2.Cu")
		(net 537)
	)
	(segment
		(start 204.9 142.5)
		(end 204.9 137)
		(width 0.1)
		(layer "In2.Cu")
		(net 537)
	)
	(segment
		(start 204.05 133.75)
		(end 203.75 133.45)
		(width 0.1)
		(layer "In2.Cu")
		(net 537)
	)
	(segment
		(start 204.05 136.45)
		(end 204.05 133.75)
		(width 0.1)
		(layer "In2.Cu")
		(net 537)
	)
	(via
		(at 228.175 127.149999)
		(size 0.35)
		(drill 0.15)
		(layers "F.Cu" "B.Cu")
		(remove_unused_layers yes)
		(keep_end_layers yes)
		(zone_layer_connections)
		(net 538)
	)
	(segment
		(start 228.175 127.149999)
		(end 228.174999 127.15)
		(width 0.1)
		(layer "B.Cu")
		(net 538)
	)
	(segment
		(start 224.9 127.15)
		(end 223.85 128.2)
		(width 0.1)
		(layer "B.Cu")
		(net 538)
	)
	(segment
		(start 228.174999 127.15)
		(end 224.9 127.15)
		(width 0.1)
		(layer "B.Cu")
		(net 538)
	)
	(via
		(at 228.675 128.499999)
		(size 0.35)
		(drill 0.15)
		(layers "F.Cu" "B.Cu")
		(remove_unused_layers yes)
		(keep_end_layers yes)
		(zone_layer_connections)
		(net 539)
	)
	(segment
		(start 222.58 127.27)
		(end 221.65 128.2)
		(width 0.1)
		(layer "B.Cu")
		(net 539)
	)
	(segment
		(start 229.15 128.024999)
		(end 229.15 126.475)
		(width 0.1)
		(layer "B.Cu")
		(net 539)
	)
	(segment
		(start 227.975 125.3)
		(end 225.89 125.3)
		(width 0.1)
		(layer "B.Cu")
		(net 539)
	)
	(segment
		(start 228.675 128.499999)
		(end 229.15 128.024999)
		(width 0.1)
		(layer "B.Cu")
		(net 539)
	)
	(segment
		(start 225.89 125.3)
		(end 223.92 127.27)
		(width 0.1)
		(layer "B.Cu")
		(net 539)
	)
	(segment
		(start 223.92 127.27)
		(end 222.58 127.27)
		(width 0.1)
		(layer "B.Cu")
		(net 539)
	)
	(segment
		(start 229.15 126.475)
		(end 227.975 125.3)
		(width 0.1)
		(layer "B.Cu")
		(net 539)
	)
	(segment
		(start 222.61 128.64)
		(end 222.61 128.2)
		(width 0.15)
		(layer "B.Cu")
		(net 540)
	)
	(segment
		(start 222.08 129.248)
		(end 222.08 129.17)
		(width 0.15)
		(layer "B.Cu")
		(net 540)
	)
	(segment
		(start 222.08 129.17)
		(end 222.61 128.64)
		(width 0.15)
		(layer "B.Cu")
		(net 540)
	)
	(segment
		(start 224.38 129.22)
		(end 224.81 128.79)
		(width 0.15)
		(layer "B.Cu")
		(net 541)
	)
	(segment
		(start 224.81 128.79)
		(end 224.81 128.2)
		(width 0.15)
		(layer "B.Cu")
		(net 541)
	)
	(segment
		(start 224.38 129.248)
		(end 224.38 129.22)
		(width 0.15)
		(layer "B.Cu")
		(net 541)
	)
	(segment
		(start 226.68 129.248)
		(end 226.68 129.17)
		(width 0.15)
		(layer "B.Cu")
		(net 542)
	)
	(segment
		(start 227.11 128.74)
		(end 227.11 128.2)
		(width 0.15)
		(layer "B.Cu")
		(net 542)
	)
	(segment
		(start 226.68 129.17)
		(end 227.11 128.74)
		(width 0.15)
		(layer "B.Cu")
		(net 542)
	)
	(via
		(at 203.699 139.5)
		(size 0.35)
		(drill 0.15)
		(layers "F.Cu" "B.Cu")
		(remove_unused_layers yes)
		(keep_end_layers yes)
		(zone_layer_connections)
		(net 543)
	)
	(segment
		(start 203.9 139.5)
		(end 204.31 139.09)
		(width 0.15)
		(layer "B.Cu")
		(net 543)
	)
	(segment
		(start 204.31 139.09)
		(end 206.51 139.09)
		(width 0.15)
		(layer "B.Cu")
		(net 543)
	)
	(segment
		(start 203.699 139.5)
		(end 203.9 139.5)
		(width 0.15)
		(layer "B.Cu")
		(net 543)
	)
	(segment
		(start 207.4 138.2)
		(end 207.7 138.2)
		(width 0.15)
		(layer "B.Cu")
		(net 543)
	)
	(segment
		(start 206.51 139.09)
		(end 207.4 138.2)
		(width 0.15)
		(layer "B.Cu")
		(net 543)
	)
	(via
		(at 203.699 140.3)
		(size 0.35)
		(drill 0.15)
		(layers "F.Cu" "B.Cu")
		(remove_unused_layers yes)
		(keep_end_layers yes)
		(zone_layer_connections)
		(net 544)
	)
	(segment
		(start 207.7 137.3)
		(end 207.45 137.3)
		(width 0.15)
		(layer "B.Cu")
		(net 544)
	)
	(segment
		(start 203.3 139.901)
		(end 203.699 140.3)
		(width 0.15)
		(layer "B.Cu")
		(net 544)
	)
	(segment
		(start 207.45 137.3)
		(end 206.47 138.28)
		(width 0.15)
		(layer "B.Cu")
		(net 544)
	)
	(segment
		(start 204.27 138.28)
		(end 204.1 138.45)
		(width 0.15)
		(layer "B.Cu")
		(net 544)
	)
	(segment
		(start 203.3 139.3)
		(end 203.3 139.901)
		(width 0.15)
		(layer "B.Cu")
		(net 544)
	)
	(segment
		(start 204.1 138.45)
		(end 204.1 138.908452)
		(width 0.15)
		(layer "B.Cu")
		(net 544)
	)
	(segment
		(start 206.47 138.28)
		(end 204.27 138.28)
		(width 0.15)
		(layer "B.Cu")
		(net 544)
	)
	(segment
		(start 203.928452 139.08)
		(end 203.52 139.08)
		(width 0.15)
		(layer "B.Cu")
		(net 544)
	)
	(segment
		(start 203.52 139.08)
		(end 203.3 139.3)
		(width 0.15)
		(layer "B.Cu")
		(net 544)
	)
	(segment
		(start 204.1 138.908452)
		(end 203.928452 139.08)
		(width 0.15)
		(layer "B.Cu")
		(net 544)
	)
	(via
		(at 202.9 131.501)
		(size 0.35)
		(drill 0.15)
		(layers "F.Cu" "B.Cu")
		(remove_unused_layers yes)
		(keep_end_layers yes)
		(zone_layer_connections)
		(net 545)
	)
	(via
		(at 206.299 144.801)
		(size 0.35)
		(drill 0.15)
		(layers "F.Cu" "B.Cu")
		(remove_unused_layers yes)
		(keep_end_layers yes)
		(zone_layer_connections)
		(net 545)
	)
	(segment
		(start 206.624 145.58562)
		(end 206.624 145.126)
		(width 0.1)
		(layer "In2.Cu")
		(net 545)
	)
	(segment
		(start 202.45 142.3)
		(end 204.024 143.874)
		(width 0.1)
		(layer "In2.Cu")
		(net 545)
	)
	(segment
		(start 204.674 145.274)
		(end 205.176 145.776)
		(width 0.1)
		(layer "In2.Cu")
		(net 545)
	)
	(segment
		(start 204.36238 145.274)
		(end 204.674 145.274)
		(width 0.1)
		(layer "In2.Cu")
		(net 545)
	)
	(segment
		(start 201.7 133.575)
		(end 202.45 134.325)
		(width 0.1)
		(layer "In2.Cu")
		(net 545)
	)
	(segment
		(start 202.501 131.9)
		(end 201.9 131.9)
		(width 0.1)
		(layer "In2.Cu")
		(net 545)
	)
	(segment
		(start 202.45 134.325)
		(end 202.45 142.3)
		(width 0.1)
		(layer "In2.Cu")
		(net 545)
	)
	(segment
		(start 206.624 145.126)
		(end 206.299 144.801)
		(width 0.1)
		(layer "In2.Cu")
		(net 545)
	)
	(segment
		(start 204.024 143.874)
		(end 204.024 144.93562)
		(width 0.1)
		(layer "In2.Cu")
		(net 545)
	)
	(segment
		(start 201.9 131.9)
		(end 201.7 132.1)
		(width 0.1)
		(layer "In2.Cu")
		(net 545)
	)
	(segment
		(start 204.024 144.93562)
		(end 204.36238 145.274)
		(width 0.1)
		(layer "In2.Cu")
		(net 545)
	)
	(segment
		(start 205.176 145.776)
		(end 206.43362 145.776)
		(width 0.1)
		(layer "In2.Cu")
		(net 545)
	)
	(segment
		(start 201.7 132.1)
		(end 201.7 133.575)
		(width 0.1)
		(layer "In2.Cu")
		(net 545)
	)
	(segment
		(start 206.43362 145.776)
		(end 206.624 145.58562)
		(width 0.1)
		(layer "In2.Cu")
		(net 545)
	)
	(segment
		(start 202.9 131.501)
		(end 202.501 131.9)
		(width 0.1)
		(layer "In2.Cu")
		(net 545)
	)
	(segment
		(start 194.7225 145.3075)
		(end 194.7225 144.9)
		(width 0.1)
		(layer "F.Cu")
		(net 546)
	)
	(segment
		(start 194.59 145.44)
		(end 194.7225 145.3075)
		(width 0.1)
		(layer "F.Cu")
		(net 546)
	)
	(segment
		(start 194.59 145.9)
		(end 194.59 145.44)
		(width 0.1)
		(layer "F.Cu")
		(net 546)
	)
	(segment
		(start 193.335 145.085)
		(end 193.335 144.9)
		(width 0.1)
		(layer "F.Cu")
		(net 547)
	)
	(segment
		(start 193.79 145.9)
		(end 193.79 145.54)
		(width 0.1)
		(layer "F.Cu")
		(net 547)
	)
	(segment
		(start 193.79 145.54)
		(end 193.335 145.085)
		(width 0.1)
		(layer "F.Cu")
		(net 547)
	)
	(segment
		(start 192.89 145.42)
		(end 192.32 145.42)
		(width 0.1)
		(layer "F.Cu")
		(net 548)
	)
	(segment
		(start 192.1975 145.2975)
		(end 192.1975 144.9)
		(width 0.1)
		(layer "F.Cu")
		(net 548)
	)
	(segment
		(start 192.99 145.52)
		(end 192.89 145.42)
		(width 0.1)
		(layer "F.Cu")
		(net 548)
	)
	(segment
		(start 192.99 145.9)
		(end 192.99 145.52)
		(width 0.1)
		(layer "F.Cu")
		(net 548)
	)
	(segment
		(start 192.32 145.42)
		(end 192.1975 145.2975)
		(width 0.1)
		(layer "F.Cu")
		(net 548)
	)
	(segment
		(start 196.4975 144.9425)
		(end 196.06 145.38)
		(width 0.1)
		(layer "F.Cu")
		(net 549)
	)
	(segment
		(start 196.4975 144.9)
		(end 196.4975 144.9425)
		(width 0.1)
		(layer "F.Cu")
		(net 549)
	)
	(segment
		(start 196.06 145.38)
		(end 195.98 145.38)
		(width 0.1)
		(layer "F.Cu")
		(net 549)
	)
	(segment
		(start 195.79 145.57)
		(end 195.79 145.9)
		(width 0.1)
		(layer "F.Cu")
		(net 549)
	)
	(segment
		(start 195.98 145.38)
		(end 195.79 145.57)
		(width 0.1)
		(layer "F.Cu")
		(net 549)
	)
	(segment
		(start 194.99 145.56)
		(end 195.36 145.19)
		(width 0.1)
		(layer "F.Cu")
		(net 550)
	)
	(segment
		(start 195.36 145.19)
		(end 195.36 144.9)
		(width 0.1)
		(layer "F.Cu")
		(net 550)
	)
	(segment
		(start 194.99 145.9)
		(end 194.99 145.56)
		(width 0.1)
		(layer "F.Cu")
		(net 550)
	)
	(segment
		(start 193.9725 145.3225)
		(end 193.9725 144.9)
		(width 0.1)
		(layer "F.Cu")
		(net 551)
	)
	(segment
		(start 194.19 145.54)
		(end 193.9725 145.3225)
		(width 0.1)
		(layer "F.Cu")
		(net 551)
	)
	(segment
		(start 194.19 145.9)
		(end 194.19 145.54)
		(width 0.1)
		(layer "F.Cu")
		(net 551)
	)
	(segment
		(start 193.33 145.4)
		(end 193.2 145.4)
		(width 0.1)
		(layer "F.Cu")
		(net 552)
	)
	(segment
		(start 193.39 145.46)
		(end 193.33 145.4)
		(width 0.1)
		(layer "F.Cu")
		(net 552)
	)
	(segment
		(start 192.835 145.175)
		(end 192.835 144.9)
		(width 0.1)
		(layer "F.Cu")
		(net 552)
	)
	(segment
		(start 193.02 145.22)
		(end 192.88 145.22)
		(width 0.1)
		(layer "F.Cu")
		(net 552)
	)
	(segment
		(start 192.88 145.22)
		(end 192.835 145.175)
		(width 0.1)
		(layer "F.Cu")
		(net 552)
	)
	(segment
		(start 193.2 145.4)
		(end 193.02 145.22)
		(width 0.1)
		(layer "F.Cu")
		(net 552)
	)
	(segment
		(start 193.39 145.9)
		(end 193.39 145.46)
		(width 0.1)
		(layer "F.Cu")
		(net 552)
	)
	(segment
		(start 196.99 146.36)
		(end 196.98 146.35)
		(width 0.201)
		(layer "F.Cu")
		(net 553)
	)
	(segment
		(start 196.98 146.35)
		(end 196.64 146.35)
		(width 0.201)
		(layer "F.Cu")
		(net 553)
	)
	(via
		(at 196.99 146.36)
		(size 0.35)
		(drill 0.15)
		(layers "F.Cu" "B.Cu")
		(remove_unused_layers yes)
		(keep_end_layers yes)
		(zone_layer_connections)
		(net 553)
	)
	(via
		(at 194.19 148.05)
		(size 0.35)
		(drill 0.15)
		(layers "F.Cu" "B.Cu")
		(remove_unused_layers yes)
		(keep_end_layers yes)
		(zone_layer_connections)
		(net 553)
	)
	(segment
		(start 193.605 147.23)
		(end 194.19 147.815)
		(width 0.256)
		(layer "B.Cu")
		(net 553)
	)
	(segment
		(start 194.42 146.27)
		(end 194.96 146.27)
		(width 0.256)
		(layer "B.Cu")
		(net 553)
	)
	(segment
		(start 193.45 147.23)
		(end 193.46 147.23)
		(width 0.256)
		(layer "B.Cu")
		(net 553)
	)
	(segment
		(start 194.37 146.27)
		(end 193.4 145.3)
		(width 0.256)
		(layer "B.Cu")
		(net 553)
	)
	(segment
		(start 192.45 147.23)
		(end 193.605 147.23)
		(width 0.256)
		(layer "B.Cu")
		(net 553)
	)
	(segment
		(start 194.42 146.27)
		(end 194.37 146.27)
		(width 0.256)
		(layer "B.Cu")
		(net 553)
	)
	(segment
		(start 194.19 147.815)
		(end 194.19 148.05)
		(width 0.256)
		(layer "B.Cu")
		(net 553)
	)
	(segment
		(start 196.9 146.27)
		(end 194.85 146.27)
		(width 0.256)
		(layer "B.Cu")
		(net 553)
	)
	(segment
		(start 196.99 146.36)
		(end 196.9 146.27)
		(width 0.256)
		(layer "B.Cu")
		(net 553)
	)
	(segment
		(start 193.46 147.23)
		(end 194.42 146.27)
		(width 0.256)
		(layer "B.Cu")
		(net 553)
	)
	(segment
		(start 196.19 145.9)
		(end 196.64 145.9)
		(width 0.15)
		(layer "F.Cu")
		(net 554)
	)
	(segment
		(start 197.040989 145.499011)
		(end 197.040989 144.200521)
		(width 0.15)
		(layer "F.Cu")
		(net 554)
	)
	(segment
		(start 196.64 145.9)
		(end 197.040989 145.499011)
		(width 0.15)
		(layer "F.Cu")
		(net 554)
	)
	(via
		(at 197.040989 144.200521)
		(size 0.35)
		(drill 0.15)
		(layers "F.Cu" "B.Cu")
		(remove_unused_layers yes)
		(keep_end_layers yes)
		(zone_layer_connections)
		(net 554)
	)
	(segment
		(start 197.040989 144.879011)
		(end 197.040989 144.200521)
		(width 0.15)
		(layer "B.Cu")
		(net 554)
	)
	(segment
		(start 196.62 145.3)
		(end 197.040989 144.879011)
		(width 0.15)
		(layer "B.Cu")
		(net 554)
	)
	(segment
		(start 196.2 145.3)
		(end 196.62 145.3)
		(width 0.15)
		(layer "B.Cu")
		(net 554)
	)
	(segment
		(start 192.14 147.55)
		(end 190.77 147.55)
		(width 0.15)
		(layer "F.Cu")
		(net 555)
	)
	(segment
		(start 190.5 147.28)
		(end 190.35 147.28)
		(width 0.15)
		(layer "F.Cu")
		(net 555)
	)
	(segment
		(start 190.77 147.55)
		(end 190.5 147.28)
		(width 0.15)
		(layer "F.Cu")
		(net 555)
	)
	(segment
		(start 197.233099 146.925582)
		(end 197.784418 146.925582)
		(width 0.09)
		(layer "F.Cu")
		(net 556)
	)
	(segment
		(start 197.85 146.86)
		(end 198.31 146.86)
		(width 0.09)
		(layer "F.Cu")
		(net 556)
	)
	(segment
		(start 197.057517 146.75)
		(end 197.233099 146.925582)
		(width 0.09)
		(layer "F.Cu")
		(net 556)
	)
	(segment
		(start 197.784418 146.925582)
		(end 197.85 146.86)
		(width 0.09)
		(layer "F.Cu")
		(net 556)
	)
	(segment
		(start 196.64 146.75)
		(end 197.057517 146.75)
		(width 0.09)
		(layer "F.Cu")
		(net 556)
	)
	(segment
		(start 192.14 147.95)
		(end 190.78 147.95)
		(width 0.15)
		(layer "F.Cu")
		(net 557)
	)
	(segment
		(start 190.78 147.95)
		(end 190.34 148.39)
		(width 0.15)
		(layer "F.Cu")
		(net 557)
	)
	(segment
		(start 180.85 120.5)
		(end 180.67 120.68)
		(width 0.1)
		(layer "F.Cu")
		(net 560)
	)
	(segment
		(start 180.67 120.68)
		(end 180.67 121.45)
		(width 0.1)
		(layer "F.Cu")
		(net 560)
	)
	(via
		(at 215.55 116.4)
		(size 0.35)
		(drill 0.15)
		(layers "F.Cu" "B.Cu")
		(remove_unused_layers yes)
		(keep_end_layers yes)
		(zone_layer_connections)
		(net 560)
	)
	(via
		(at 180.85 120.5)
		(size 0.35)
		(drill 0.15)
		(layers "F.Cu" "B.Cu")
		(remove_unused_layers yes)
		(keep_end_layers yes)
		(zone_layer_connections)
		(net 560)
	)
	(segment
		(start 206.465 116.515)
		(end 207.175 117.225)
		(width 0.1)
		(layer "In11.Cu")
		(net 560)
	)
	(segment
		(start 181.15 117.86)
		(end 181.58 117.43)
		(width 0.1)
		(layer "In11.Cu")
		(net 560)
	)
	(segment
		(start 190.374 117.374)
		(end 204.826 117.374)
		(width 0.1)
		(layer "In11.Cu")
		(net 560)
	)
	(segment
		(start 181.15 120.2)
		(end 181.15 117.86)
		(width 0.1)
		(layer "In11.Cu")
		(net 560)
	)
	(segment
		(start 210.375 117.225)
		(end 211.25 116.35)
		(width 0.1)
		(layer "In11.Cu")
		(net 560)
	)
	(segment
		(start 215.2 116.75)
		(end 215.55 116.4)
		(width 0.1)
		(layer "In11.Cu")
		(net 560)
	)
	(segment
		(start 212.95 116.75)
		(end 215.2 116.75)
		(width 0.1)
		(layer "In11.Cu")
		(net 560)
	)
	(segment
		(start 212.55 116.35)
		(end 212.95 116.75)
		(width 0.1)
		(layer "In11.Cu")
		(net 560)
	)
	(segment
		(start 207.175 117.225)
		(end 210.375 117.225)
		(width 0.1)
		(layer "In11.Cu")
		(net 560)
	)
	(segment
		(start 181.58 117.43)
		(end 184.81 117.43)
		(width 0.1)
		(layer "In11.Cu")
		(net 560)
	)
	(segment
		(start 180.85 120.5)
		(end 181.15 120.2)
		(width 0.1)
		(layer "In11.Cu")
		(net 560)
	)
	(segment
		(start 205.685 116.515)
		(end 206.465 116.515)
		(width 0.1)
		(layer "In11.Cu")
		(net 560)
	)
	(segment
		(start 190.1 117.1)
		(end 190.374 117.374)
		(width 0.1)
		(layer "In11.Cu")
		(net 560)
	)
	(segment
		(start 204.826 117.374)
		(end 205.685 116.515)
		(width 0.1)
		(layer "In11.Cu")
		(net 560)
	)
	(segment
		(start 185.14 117.1)
		(end 190.1 117.1)
		(width 0.1)
		(layer "In11.Cu")
		(net 560)
	)
	(segment
		(start 184.81 117.43)
		(end 185.14 117.1)
		(width 0.1)
		(layer "In11.Cu")
		(net 560)
	)
	(segment
		(start 211.25 116.35)
		(end 212.55 116.35)
		(width 0.1)
		(layer "In11.Cu")
		(net 560)
	)
	(segment
		(start 221.48 154.585)
		(end 221.6225 154.7275)
		(width 0.125)
		(layer "F.Cu")
		(net 562)
	)
	(segment
		(start 221.48 154.385)
		(end 221.48 154.585)
		(width 0.125)
		(layer "F.Cu")
		(net 562)
	)
	(segment
		(start 221.6225 154.91353)
		(end 221.847134 155.138164)
		(width 0.125)
		(layer "F.Cu")
		(net 562)
	)
	(segment
		(start 221.847134 155.138164)
		(end 222.777864 155.138164)
		(width 0.125)
		(layer "F.Cu")
		(net 562)
	)
	(segment
		(start 221.6225 154.7275)
		(end 221.6225 154.91353)
		(width 0.125)
		(layer "F.Cu")
		(net 562)
	)
	(segment
		(start 222.777864 155.138164)
		(end 222.931265 154.984763)
		(width 0.125)
		(layer "F.Cu")
		(net 562)
	)
	(segment
		(start 222.931265 154.984763)
		(end 223.090365 154.984763)
		(width 0.125)
		(layer "F.Cu")
		(net 562)
	)
	(via
		(at 223.090365 154.984763)
		(size 0.35)
		(drill 0.15)
		(layers "F.Cu" "B.Cu")
		(remove_unused_layers yes)
		(keep_end_layers yes)
		(zone_layer_connections)
		(net 562)
	)
	(via
		(at 198.1 139.5)
		(size 0.35)
		(drill 0.15)
		(layers "F.Cu" "B.Cu")
		(remove_unused_layers yes)
		(keep_end_layers yes)
		(zone_layer_connections)
		(net 562)
	)
	(segment
		(start 214.878578 150.91)
		(end 214.208578 150.24)
		(width 0.1)
		(layer "In2.Cu")
		(net 562)
	)
	(segment
		(start 199.46 144.173578)
		(end 200.25 143.383578)
		(width 0.1)
		(layer "In2.Cu")
		(net 562)
	)
	(segment
		(start 199.46 144.751422)
		(end 199.46 144.173578)
		(width 0.1)
		(layer "In2.Cu")
		(net 562)
	)
	(segment
		(start 206.048578 151.35)
		(end 205.418578 150.72)
		(width 0.1)
		(layer "In2.Cu")
		(net 562)
	)
	(segment
		(start 200.25 143.383578)
		(end 200.25 142.291422)
		(width 0.1)
		(layer "In2.Cu")
		(net 562)
	)
	(segment
		(start 203.68 149.191422)
		(end 203.308578 148.82)
		(width 0.1)
		(layer "In2.Cu")
		(net 562)
	)
	(segment
		(start 199.599 141.640422)
		(end 199.599 141.474)
		(width 0.1)
		(layer "In2.Cu")
		(net 562)
	)
	(segment
		(start 211.261422 151.35)
		(end 206.048578 151.35)
		(width 0.1)
		(layer "In2.Cu")
		(net 562)
	)
	(segment
		(start 221.338578 155.26)
		(end 216.988578 150.91)
		(width 0.1)
		(layer "In2.Cu")
		(net 562)
	)
	(segment
		(start 214.208578 150.24)
		(end 212.371422 150.24)
		(width 0.1)
		(layer "In2.Cu")
		(net 562)
	)
	(segment
		(start 201.61 148.301422)
		(end 201.61 147.851422)
		(width 0.1)
		(layer "In2.Cu")
		(net 562)
	)
	(segment
		(start 199.483578 139.625)
		(end 199.275 139.625)
		(width 0.1)
		(layer "In2.Cu")
		(net 562)
	)
	(segment
		(start 201.188578 147.43)
		(end 200.158578 147.43)
		(width 0.1)
		(layer "In2.Cu")
		(net 562)
	)
	(segment
		(start 203.68 149.691422)
		(end 203.68 149.191422)
		(width 0.1)
		(layer "In2.Cu")
		(net 562)
	)
	(segment
		(start 200.158578 147.43)
		(end 199.72 146.991422)
		(width 0.1)
		(layer "In2.Cu")
		(net 562)
	)
	(segment
		(start 204.708578 150.72)
		(end 203.68 149.691422)
		(width 0.1)
		(layer "In2.Cu")
		(net 562)
	)
	(segment
		(start 222.914294 154.984763)
		(end 222.639057 155.26)
		(width 0.1)
		(layer "In2.Cu")
		(net 562)
	)
	(segment
		(start 197.96 139.785)
		(end 197.96 139.64)
		(width 0.1)
		(layer "In2.Cu")
		(net 562)
	)
	(segment
		(start 199.72 146.991422)
		(end 199.72 145.011422)
		(width 0.1)
		(layer "In2.Cu")
		(net 562)
	)
	(segment
		(start 202.128578 148.82)
		(end 201.61 148.301422)
		(width 0.1)
		(layer "In2.Cu")
		(net 562)
	)
	(segment
		(start 198.025 139.85)
		(end 197.96 139.785)
		(width 0.1)
		(layer "In2.Cu")
		(net 562)
	)
	(segment
		(start 201.61 147.851422)
		(end 201.188578 147.43)
		(width 0.1)
		(layer "In2.Cu")
		(net 562)
	)
	(segment
		(start 199.374 141.249)
		(end 199.374 140.151)
		(width 0.1)
		(layer "In2.Cu")
		(net 562)
	)
	(segment
		(start 203.308578 148.82)
		(end 202.128578 148.82)
		(width 0.1)
		(layer "In2.Cu")
		(net 562)
	)
	(segment
		(start 212.371422 150.24)
		(end 211.261422 151.35)
		(width 0.1)
		(layer "In2.Cu")
		(net 562)
	)
	(segment
		(start 223.090365 154.984763)
		(end 222.914294 154.984763)
		(width 0.1)
		(layer "In2.Cu")
		(net 562)
	)
	(segment
		(start 199.599 141.474)
		(end 199.374 141.249)
		(width 0.1)
		(layer "In2.Cu")
		(net 562)
	)
	(segment
		(start 199.374 140.151)
		(end 199.599 139.926)
		(width 0.1)
		(layer "In2.Cu")
		(net 562)
	)
	(segment
		(start 199.275 139.625)
		(end 199.05 139.85)
		(width 0.1)
		(layer "In2.Cu")
		(net 562)
	)
	(segment
		(start 216.988578 150.91)
		(end 214.878578 150.91)
		(width 0.1)
		(layer "In2.Cu")
		(net 562)
	)
	(segment
		(start 199.72 145.011422)
		(end 199.46 144.751422)
		(width 0.1)
		(layer "In2.Cu")
		(net 562)
	)
	(segment
		(start 205.418578 150.72)
		(end 204.708578 150.72)
		(width 0.1)
		(layer "In2.Cu")
		(net 562)
	)
	(segment
		(start 199.599 139.926)
		(end 199.599 139.740422)
		(width 0.1)
		(layer "In2.Cu")
		(net 562)
	)
	(segment
		(start 200.25 142.291422)
		(end 199.599 141.640422)
		(width 0.1)
		(layer "In2.Cu")
		(net 562)
	)
	(segment
		(start 197.96 139.64)
		(end 198.1 139.5)
		(width 0.1)
		(layer "In2.Cu")
		(net 562)
	)
	(segment
		(start 199.599 139.740422)
		(end 199.483578 139.625)
		(width 0.1)
		(layer "In2.Cu")
		(net 562)
	)
	(segment
		(start 222.639057 155.26)
		(end 221.338578 155.26)
		(width 0.1)
		(layer "In2.Cu")
		(net 562)
	)
	(segment
		(start 199.05 139.85)
		(end 198.025 139.85)
		(width 0.1)
		(layer "In2.Cu")
		(net 562)
	)
	(via
		(at 206.299 144.151)
		(size 0.35)
		(drill 0.15)
		(layers "F.Cu" "B.Cu")
		(remove_unused_layers yes)
		(keep_end_layers yes)
		(zone_layer_connections)
		(net 563)
	)
	(via
		(at 202.1 131.501)
		(size 0.35)
		(drill 0.15)
		(layers "F.Cu" "B.Cu")
		(remove_unused_layers yes)
		(keep_end_layers yes)
		(zone_layer_connections)
		(net 563)
	)
	(segment
		(start 203.374 143.824)
		(end 201.7 142.15)
		(width 0.1)
		(layer "In2.Cu")
		(net 563)
	)
	(segment
		(start 204.5 145.6)
		(end 203.85 145.6)
		(width 0.1)
		(layer "In2.Cu")
		(net 563)
	)
	(segment
		(start 200.9 133.525)
		(end 200.9 132.075)
		(width 0.1)
		(layer "In2.Cu")
		(net 563)
	)
	(segment
		(start 206.43362 146.426)
		(end 205.326 146.426)
		(width 0.1)
		(layer "In2.Cu")
		(net 563)
	)
	(segment
		(start 206.85 144.702)
		(end 206.85 146.00962)
		(width 0.1)
		(layer "In2.Cu")
		(net 563)
	)
	(segment
		(start 201.7 142.15)
		(end 201.7 134.325)
		(width 0.1)
		(layer "In2.Cu")
		(net 563)
	)
	(segment
		(start 201.4 131.9)
		(end 201.799 131.501)
		(width 0.1)
		(layer "In2.Cu")
		(net 563)
	)
	(segment
		(start 205.326 146.426)
		(end 204.5 145.6)
		(width 0.1)
		(layer "In2.Cu")
		(net 563)
	)
	(segment
		(start 201.799 131.501)
		(end 202.1 131.501)
		(width 0.1)
		(layer "In2.Cu")
		(net 563)
	)
	(segment
		(start 201.075 131.9)
		(end 201.4 131.9)
		(width 0.1)
		(layer "In2.Cu")
		(net 563)
	)
	(segment
		(start 203.85 145.6)
		(end 203.374 145.124)
		(width 0.1)
		(layer "In2.Cu")
		(net 563)
	)
	(segment
		(start 206.85 146.00962)
		(end 206.43362 146.426)
		(width 0.1)
		(layer "In2.Cu")
		(net 563)
	)
	(segment
		(start 200.9 132.075)
		(end 201.075 131.9)
		(width 0.1)
		(layer "In2.Cu")
		(net 563)
	)
	(segment
		(start 201.7 134.325)
		(end 200.9 133.525)
		(width 0.1)
		(layer "In2.Cu")
		(net 563)
	)
	(segment
		(start 206.299 144.151)
		(end 206.85 144.702)
		(width 0.1)
		(layer "In2.Cu")
		(net 563)
	)
	(segment
		(start 203.374 145.124)
		(end 203.374 143.824)
		(width 0.1)
		(layer "In2.Cu")
		(net 563)
	)
	(via
		(at 206.299 148.051)
		(size 0.35)
		(drill 0.15)
		(layers "F.Cu" "B.Cu")
		(remove_unused_layers yes)
		(keep_end_layers yes)
		(zone_layer_connections)
		(net 564)
	)
	(via
		(at 202.1 133.101)
		(size 0.35)
		(drill 0.15)
		(layers "F.Cu" "B.Cu")
		(remove_unused_layers yes)
		(keep_end_layers yes)
		(zone_layer_connections)
		(net 564)
	)
	(segment
		(start 204.1 136.9)
		(end 204.1 142.55)
		(width 0.1)
		(layer "In2.Cu")
		(net 564)
	)
	(segment
		(start 202.1 133.101)
		(end 202.476 132.725)
		(width 0.1)
		(layer "In2.Cu")
		(net 564)
	)
	(segment
		(start 205.324 144.28562)
		(end 205.51438 144.476)
		(width 0.1)
		(layer "In2.Cu")
		(net 564)
	)
	(segment
		(start 207.14 147.21)
		(end 206.299 148.051)
		(width 0.1)
		(layer "In2.Cu")
		(net 564)
	)
	(segment
		(start 203.2625 136.0625)
		(end 204.1 136.9)
		(width 0.1)
		(layer "In2.Cu")
		(net 564)
	)
	(segment
		(start 205.78362 144.476)
		(end 205.974 144.28562)
		(width 0.1)
		(layer "In2.Cu")
		(net 564)
	)
	(segment
		(start 205.324 143.774)
		(end 205.324 144.28562)
		(width 0.1)
		(layer "In2.Cu")
		(net 564)
	)
	(segment
		(start 205.974 144.28562)
		(end 205.974 144.01638)
		(width 0.1)
		(layer "In2.Cu")
		(net 564)
	)
	(segment
		(start 206.16438 143.826)
		(end 206.526 143.826)
		(width 0.1)
		(layer "In2.Cu")
		(net 564)
	)
	(segment
		(start 206.526 143.826)
		(end 207.14 144.44)
		(width 0.1)
		(layer "In2.Cu")
		(net 564)
	)
	(segment
		(start 203.2625 133.00388)
		(end 203.2625 136.0625)
		(width 0.1)
		(layer "In2.Cu")
		(net 564)
	)
	(segment
		(start 204.1 142.55)
		(end 205.324 143.774)
		(width 0.1)
		(layer "In2.Cu")
		(net 564)
	)
	(segment
		(start 202.476 132.725)
		(end 202.98362 132.725)
		(width 0.1)
		(layer "In2.Cu")
		(net 564)
	)
	(segment
		(start 202.98362 132.725)
		(end 203.2625 133.00388)
		(width 0.1)
		(layer "In2.Cu")
		(net 564)
	)
	(segment
		(start 205.974 144.01638)
		(end 206.16438 143.826)
		(width 0.1)
		(layer "In2.Cu")
		(net 564)
	)
	(segment
		(start 207.14 144.44)
		(end 207.14 147.21)
		(width 0.1)
		(layer "In2.Cu")
		(net 564)
	)
	(segment
		(start 205.51438 144.476)
		(end 205.78362 144.476)
		(width 0.1)
		(layer "In2.Cu")
		(net 564)
	)
	(via
		(at 202.1 135.5)
		(size 0.35)
		(drill 0.15)
		(layers "F.Cu" "B.Cu")
		(remove_unused_layers yes)
		(keep_end_layers yes)
		(zone_layer_connections)
		(net 565)
	)
	(via
		(at 226.2 123)
		(size 0.35)
		(drill 0.15)
		(layers "F.Cu" "B.Cu")
		(remove_unused_layers yes)
		(keep_end_layers yes)
		(zone_layer_connections)
		(net 565)
	)
	(segment
		(start 203.425 132.475)
		(end 203.425 131.975)
		(width 0.1)
		(layer "In9.Cu")
		(net 565)
	)
	(segment
		(start 202.74 135.5)
		(end 203.25 134.99)
		(width 0.1)
		(layer "In9.Cu")
		(net 565)
	)
	(segment
		(start 219.75 124.85)
		(end 222.5 124.85)
		(width 0.1)
		(layer "In9.Cu")
		(net 565)
	)
	(segment
		(start 202.1 135.5)
		(end 202.74 135.5)
		(width 0.1)
		(layer "In9.Cu")
		(net 565)
	)
	(segment
		(start 203.425 131.975)
		(end 203.55 131.85)
		(width 0.1)
		(layer "In9.Cu")
		(net 565)
	)
	(segment
		(start 204.85 130.80962)
		(end 204.85 130.69038)
		(width 0.1)
		(layer "In9.Cu")
		(net 565)
	)
	(segment
		(start 212.32812 130.025)
		(end 212.94312 129.41)
		(width 0.1)
		(layer "In9.Cu")
		(net 565)
	)
	(segment
		(start 203.25 133.75)
		(end 203.6 133.4)
		(width 0.1)
		(layer "In9.Cu")
		(net 565)
	)
	(segment
		(start 203.6 133.4)
		(end 203.6 132.65)
		(width 0.1)
		(layer "In9.Cu")
		(net 565)
	)
	(segment
		(start 204.08 131.57962)
		(end 204.08 131.46038)
		(width 0.1)
		(layer "In9.Cu")
		(net 565)
	)
	(segment
		(start 222.75 125.1)
		(end 225.75 125.1)
		(width 0.1)
		(layer "In9.Cu")
		(net 565)
	)
	(segment
		(start 216.18388 126.25)
		(end 218.35 126.25)
		(width 0.1)
		(layer "In9.Cu")
		(net 565)
	)
	(segment
		(start 226.75 124.1)
		(end 226.75 123.55)
		(width 0.1)
		(layer "In9.Cu")
		(net 565)
	)
	(segment
		(start 212.94312 129.41)
		(end 213.44312 129.41)
		(width 0.1)
		(layer "In9.Cu")
		(net 565)
	)
	(segment
		(start 203.6 132.65)
		(end 203.425 132.475)
		(width 0.1)
		(layer "In9.Cu")
		(net 565)
	)
	(segment
		(start 225.75 125.1)
		(end 226.75 124.1)
		(width 0.1)
		(layer "In9.Cu")
		(net 565)
	)
	(segment
		(start 205.24038 130.3)
		(end 206.35 130.3)
		(width 0.1)
		(layer "In9.Cu")
		(net 565)
	)
	(segment
		(start 203.55 131.85)
		(end 203.80962 131.85)
		(width 0.1)
		(layer "In9.Cu")
		(net 565)
	)
	(segment
		(start 203.80962 131.85)
		(end 204.08 131.57962)
		(width 0.1)
		(layer "In9.Cu")
		(net 565)
	)
	(segment
		(start 213.94 128.49388)
		(end 216.18388 126.25)
		(width 0.1)
		(layer "In9.Cu")
		(net 565)
	)
	(segment
		(start 203.25 134.99)
		(end 203.25 133.75)
		(width 0.1)
		(layer "In9.Cu")
		(net 565)
	)
	(segment
		(start 222.5 124.85)
		(end 222.75 125.1)
		(width 0.1)
		(layer "In9.Cu")
		(net 565)
	)
	(segment
		(start 204.38038 131.16)
		(end 204.49962 131.16)
		(width 0.1)
		(layer "In9.Cu")
		(net 565)
	)
	(segment
		(start 206.35 130.3)
		(end 206.625 130.025)
		(width 0.1)
		(layer "In9.Cu")
		(net 565)
	)
	(segment
		(start 218.35 126.25)
		(end 219.75 124.85)
		(width 0.1)
		(layer "In9.Cu")
		(net 565)
	)
	(segment
		(start 204.85 130.69038)
		(end 205.24038 130.3)
		(width 0.1)
		(layer "In9.Cu")
		(net 565)
	)
	(segment
		(start 213.94 128.91312)
		(end 213.94 128.49388)
		(width 0.1)
		(layer "In9.Cu")
		(net 565)
	)
	(segment
		(start 204.49962 131.16)
		(end 204.85 130.80962)
		(width 0.1)
		(layer "In9.Cu")
		(net 565)
	)
	(segment
		(start 206.625 130.025)
		(end 212.32812 130.025)
		(width 0.1)
		(layer "In9.Cu")
		(net 565)
	)
	(segment
		(start 226.75 123.55)
		(end 226.2 123)
		(width 0.1)
		(layer "In9.Cu")
		(net 565)
	)
	(segment
		(start 204.08 131.46038)
		(end 204.38038 131.16)
		(width 0.1)
		(layer "In9.Cu")
		(net 565)
	)
	(segment
		(start 213.44312 129.41)
		(end 213.94 128.91312)
		(width 0.1)
		(layer "In9.Cu")
		(net 565)
	)
	(via
		(at 226.2 123.9)
		(size 0.35)
		(drill 0.15)
		(layers "F.Cu" "B.Cu")
		(remove_unused_layers yes)
		(keep_end_layers yes)
		(zone_layer_connections)
		(net 566)
	)
	(via
		(at 201.3 134.7)
		(size 0.35)
		(drill 0.15)
		(layers "F.Cu" "B.Cu")
		(remove_unused_layers yes)
		(keep_end_layers yes)
		(zone_layer_connections)
		(net 566)
	)
	(segment
		(start 214.16538 127.275)
		(end 214.525 127.275)
		(width 0.1)
		(layer "In9.Cu")
		(net 566)
	)
	(segment
		(start 208.815 129.51)
		(end 209.385 128.94)
		(width 0.1)
		(layer "In9.Cu")
		(net 566)
	)
	(segment
		(start 203.3 130.85)
		(end 203.3 129.84038)
		(width 0.1)
		(layer "In9.Cu")
		(net 566)
	)
	(segment
		(start 210.06 128.94)
		(end 211.55 127.45)
		(width 0.1)
		(layer "In9.Cu")
		(net 566)
	)
	(segment
		(start 214.525 127.275)
		(end 215.95 125.85)
		(width 0.1)
		(layer "In9.Cu")
		(net 566)
	)
	(segment
		(start 203.3 129.84038)
		(end 203.63038 129.51)
		(width 0.1)
		(layer "In9.Cu")
		(net 566)
	)
	(segment
		(start 225.5 124.6)
		(end 226.2 123.9)
		(width 0.1)
		(layer "In9.Cu")
		(net 566)
	)
	(segment
		(start 213.99038 127.45)
		(end 214.16538 127.275)
		(width 0.1)
		(layer "In9.Cu")
		(net 566)
	)
	(segment
		(start 211.55 127.45)
		(end 213.99038 127.45)
		(width 0.1)
		(layer "In9.Cu")
		(net 566)
	)
	(segment
		(start 218.75 124.6)
		(end 225.5 124.6)
		(width 0.1)
		(layer "In9.Cu")
		(net 566)
	)
	(segment
		(start 202.5 133.5)
		(end 202.5 131.3)
		(width 0.1)
		(layer "In9.Cu")
		(net 566)
	)
	(segment
		(start 215.95 125.85)
		(end 217.5 125.85)
		(width 0.1)
		(layer "In9.Cu")
		(net 566)
	)
	(segment
		(start 202.5 131.3)
		(end 202.75 131.05)
		(width 0.1)
		(layer "In9.Cu")
		(net 566)
	)
	(segment
		(start 217.5 125.85)
		(end 218.75 124.6)
		(width 0.1)
		(layer "In9.Cu")
		(net 566)
	)
	(segment
		(start 201.3 134.7)
		(end 202.5 133.5)
		(width 0.1)
		(layer "In9.Cu")
		(net 566)
	)
	(segment
		(start 203.1 131.05)
		(end 203.3 130.85)
		(width 0.1)
		(layer "In9.Cu")
		(net 566)
	)
	(segment
		(start 202.75 131.05)
		(end 203.1 131.05)
		(width 0.1)
		(layer "In9.Cu")
		(net 566)
	)
	(segment
		(start 209.385 128.94)
		(end 210.06 128.94)
		(width 0.1)
		(layer "In9.Cu")
		(net 566)
	)
	(segment
		(start 203.63038 129.51)
		(end 208.815 129.51)
		(width 0.1)
		(layer "In9.Cu")
		(net 566)
	)
	(segment
		(start 182.004 135.766)
		(end 181.6045 136.0905)
		(width 0.174)
		(layer "F.Cu")
		(net 567)
	)
	(via
		(at 195.7 129.901)
		(size 0.35)
		(drill 0.15)
		(layers "F.Cu" "B.Cu")
		(remove_unused_layers yes)
		(keep_end_layers yes)
		(zone_layer_connections)
		(net 567)
	)
	(via
		(at 181.6045 136.0905)
		(size 0.35)
		(drill 0.15)
		(layers "F.Cu" "B.Cu")
		(remove_unused_layers yes)
		(keep_end_layers yes)
		(zone_layer_connections)
		(net 567)
	)
	(segment
		(start 195.3 132.82)
		(end 195.3 130.301)
		(width 0.09)
		(layer "In4.Cu")
		(net 567)
	)
	(segment
		(start 195.3 130.301)
		(end 195.7 129.901)
		(width 0.09)
		(layer "In4.Cu")
		(net 567)
	)
	(segment
		(start 181.399999 137.367487)
		(end 181.4 137.367487)
		(width 0.09)
		(layer "In4.Cu")
		(net 567)
	)
	(segment
		(start 181.894973 137.862461)
		(end 181.894974 137.862461)
		(width 0.09)
		(layer "In4.Cu")
		(net 567)
	)
	(segment
		(start 181.589666 137.672794)
		(end 181.647486 137.614973)
		(width 0.09)
		(layer "In4.Cu")
		(net 567)
	)
	(segment
		(start 181.6045 136.0905)
		(end 181.2795 136.4155)
		(width 0.09)
		(layer "In4.Cu")
		(net 567)
	)
	(segment
		(start 188.48 138.24)
		(end 190.1 136.62)
		(width 0.09)
		(layer "In4.Cu")
		(net 567)
	)
	(segment
		(start 181.894973 137.614974)
		(end 181.894973 137.614973)
		(width 0.09)
		(layer "In4.Cu")
		(net 567)
	)
	(segment
		(start 181.837128 138.167792)
		(end 181.837129 138.167793)
		(width 0.09)
		(layer "In4.Cu")
		(net 567)
	)
	(segment
		(start 182.084616 138.167792)
		(end 182.084616 138.167793)
		(width 0.09)
		(layer "In4.Cu")
		(net 567)
	)
	(segment
		(start 181.589666 137.672793)
		(end 181.589666 137.672794)
		(width 0.09)
		(layer "In4.Cu")
		(net 567)
	)
	(segment
		(start 190.1 136.62)
		(end 191.5 136.62)
		(width 0.09)
		(layer "In4.Cu")
		(net 567)
	)
	(segment
		(start 182.52 138.24)
		(end 188.48 138.24)
		(width 0.09)
		(layer "In4.Cu")
		(net 567)
	)
	(segment
		(start 181.34218 137.672794)
		(end 181.342179 137.672794)
		(width 0.09)
		(layer "In4.Cu")
		(net 567)
	)
	(segment
		(start 181.2795 136.4155)
		(end 181.2795 136.9995)
		(width 0.09)
		(layer "In4.Cu")
		(net 567)
	)
	(segment
		(start 182.084616 138.167793)
		(end 182.14246 138.109948)
		(width 0.09)
		(layer "In4.Cu")
		(net 567)
	)
	(segment
		(start 182.389947 138.109947)
		(end 182.52 138.24)
		(width 0.09)
		(layer "In4.Cu")
		(net 567)
	)
	(segment
		(start 181.2795 136.9995)
		(end 181.4 137.12)
		(width 0.09)
		(layer "In4.Cu")
		(net 567)
	)
	(segment
		(start 191.5 136.62)
		(end 195.3 132.82)
		(width 0.09)
		(layer "In4.Cu")
		(net 567)
	)
	(segment
		(start 181.894973 137.614973)
		(end 181.894974 137.614974)
		(width 0.09)
		(layer "In4.Cu")
		(net 567)
	)
	(segment
		(start 181.4 137.367487)
		(end 181.342179 137.425307)
		(width 0.09)
		(layer "In4.Cu")
		(net 567)
	)
	(segment
		(start 181.894974 137.862461)
		(end 181.837129 137.920305)
		(width 0.09)
		(layer "In4.Cu")
		(net 567)
	)
	(arc
		(start 181.342179 137.672794)
		(mid 181.465923 137.72405)
		(end 181.589666 137.672793)
		(width 0.09)
		(layer "In4.Cu")
		(net 567)
	)
	(arc
		(start 181.837129 138.167793)
		(mid 181.960873 138.219049)
		(end 182.084616 138.167792)
		(width 0.09)
		(layer "In4.Cu")
		(net 567)
	)
	(arc
		(start 181.647486 137.614973)
		(mid 181.77123 137.563717)
		(end 181.894973 137.614974)
		(width 0.09)
		(layer "In4.Cu")
		(net 567)
	)
	(arc
		(start 181.342179 137.425307)
		(mid 181.290923 137.549051)
		(end 181.34218 137.672794)
		(width 0.09)
		(layer "In4.Cu")
		(net 567)
	)
	(arc
		(start 181.4 137.12)
		(mid 181.451256 137.243744)
		(end 181.399999 137.367487)
		(width 0.09)
		(layer "In4.Cu")
		(net 567)
	)
	(arc
		(start 181.837129 137.920305)
		(mid 181.785872 138.044048)
		(end 181.837128 138.167792)
		(width 0.09)
		(layer "In4.Cu")
		(net 567)
	)
	(arc
		(start 182.14246 138.109948)
		(mid 182.266203 138.058691)
		(end 182.389947 138.109947)
		(width 0.09)
		(layer "In4.Cu")
		(net 567)
	)
	(arc
		(start 181.894974 137.614974)
		(mid 181.94623 137.738718)
		(end 181.894973 137.862461)
		(width 0.09)
		(layer "In4.Cu")
		(net 567)
	)
	(segment
		(start 183.604 131.216)
		(end 184.0035 130.8915)
		(width 0.174)
		(layer "F.Cu")
		(net 568)
	)
	(segment
		(start 183.604 127.967)
		(end 184.0035 128.2915)
		(width 0.174)
		(layer "F.Cu")
		(net 568)
	)
	(via
		(at 194.9 127.5)
		(size 0.35)
		(drill 0.15)
		(layers "F.Cu" "B.Cu")
		(remove_unused_layers yes)
		(keep_end_layers yes)
		(zone_layer_connections)
		(net 568)
	)
	(via
		(at 184.0035 130.8915)
		(size 0.35)
		(drill 0.15)
		(layers "F.Cu" "B.Cu")
		(remove_unused_layers yes)
		(keep_end_layers yes)
		(zone_layer_connections)
		(net 568)
	)
	(via
		(at 184.0035 128.2915)
		(size 0.35)
		(drill 0.15)
		(layers "F.Cu" "B.Cu")
		(remove_unused_layers yes)
		(keep_end_layers yes)
		(zone_layer_connections)
		(net 568)
	)
	(segment
		(start 183.600287 130.429713)
		(end 183.47 130.56)
		(width 0.09)
		(layer "In9.Cu")
		(net 568)
	)
	(segment
		(start 183.47 130.56)
		(end 183.47 130.95)
		(width 0.09)
		(layer "In9.Cu")
		(net 568)
	)
	(segment
		(start 183.805 131.09)
		(end 184.0035 130.8915)
		(width 0.09)
		(layer "In9.Cu")
		(net 568)
	)
	(segment
		(start 183.47 130.95)
		(end 183.61 131.09)
		(width 0.09)
		(layer "In9.Cu")
		(net 568)
	)
	(segment
		(start 183.600287 130.038211)
		(end 183.600287 130.429713)
		(width 0.09)
		(layer "In9.Cu")
		(net 568)
	)
	(segment
		(start 184.0035 128.2915)
		(end 183.6285 128.2915)
		(width 0.09)
		(layer "In9.Cu")
		(net 568)
	)
	(segment
		(start 183.49 128.43)
		(end 183.49 129.14)
		(width 0.09)
		(layer "In9.Cu")
		(net 568)
	)
	(segment
		(start 183.6285 128.2915)
		(end 183.49 128.43)
		(width 0.09)
		(layer "In9.Cu")
		(net 568)
	)
	(segment
		(start 184.12 129.59)
		(end 183.49 129.59)
		(width 0.09)
		(layer "In9.Cu")
		(net 568)
	)
	(segment
		(start 183.64 129.29)
		(end 183.641789 129.291789)
		(width 0.09)
		(layer "In9.Cu")
		(net 568)
	)
	(segment
		(start 183.641789 129.291789)
		(end 184.159713 129.291789)
		(width 0.09)
		(layer "In9.Cu")
		(net 568)
	)
	(segment
		(start 183.61 131.09)
		(end 183.805 131.09)
		(width 0.09)
		(layer "In9.Cu")
		(net 568)
	)
	(arc
		(start 184.27 129.44)
		(mid 184.226066 129.546066)
		(end 184.12 129.59)
		(width 0.09)
		(layer "In9.Cu")
		(net 568)
	)
	(arc
		(start 184.159713 129.291789)
		(mid 184.239003 129.348686)
		(end 184.27 129.44)
		(width 0.09)
		(layer "In9.Cu")
		(net 568)
	)
	(arc
		(start 183.49 129.59)
		(mid 183.383934 129.633934)
		(end 183.34 129.74)
		(width 0.09)
		(layer "In9.Cu")
		(net 568)
	)
	(arc
		(start 183.49 129.14)
		(mid 183.533934 129.246066)
		(end 183.64 129.29)
		(width 0.09)
		(layer "In9.Cu")
		(net 568)
	)
	(arc
		(start 183.34 129.74)
		(mid 183.383934 129.846066)
		(end 183.49 129.89)
		(width 0.09)
		(layer "In9.Cu")
		(net 568)
	)
	(arc
		(start 183.49 129.89)
		(mid 183.56929 129.946897)
		(end 183.600287 130.038211)
		(width 0.09)
		(layer "In9.Cu")
		(net 568)
	)
	(segment
		(start 183.21 133.56)
		(end 183.55 133.22)
		(width 0.09)
		(layer "In11.Cu")
		(net 568)
	)
	(segment
		(start 193.35962 131.1)
		(end 193.624 130.83562)
		(width 0.09)
		(layer "In11.Cu")
		(net 568)
	)
	(segment
		(start 194.924 129.576)
		(end 195.225 129.275)
		(width 0.09)
		(layer "In11.Cu")
		(net 568)
	)
	(segment
		(start 195.225 127.825)
		(end 194.9 127.5)
		(width 0.09)
		(layer "In11.Cu")
		(net 568)
	)
	(segment
		(start 194.424 130.03562)
		(end 194.424 129.9)
		(width 0.09)
		(layer "In11.Cu")
		(net 568)
	)
	(segment
		(start 183.7885 131.2115)
		(end 185.3015 131.2115)
		(width 0.09)
		(layer "In11.Cu")
		(net 568)
	)
	(segment
		(start 191.27 132.49)
		(end 191.27 131.29)
		(width 0.09)
		(layer "In11.Cu")
		(net 568)
	)
	(segment
		(start 194.748 129.576)
		(end 194.924 129.576)
		(width 0.09)
		(layer "In11.Cu")
		(net 568)
	)
	(segment
		(start 183.59 128.705)
		(end 183.59 129.21)
		(width 0.09)
		(layer "In11.Cu")
		(net 568)
	)
	(segment
		(start 182.44 133.56)
		(end 183.21 133.56)
		(width 0.09)
		(layer "In11.Cu")
		(net 568)
	)
	(segment
		(start 183.55 131.45)
		(end 183.7885 131.2115)
		(width 0.09)
		(layer "In11.Cu")
		(net 568)
	)
	(segment
		(start 185.3015 131.2115)
		(end 185.49 131.4)
		(width 0.09)
		(layer "In11.Cu")
		(net 568)
	)
	(segment
		(start 182.08 133.2)
		(end 182.44 133.56)
		(width 0.09)
		(layer "In11.Cu")
		(net 568)
	)
	(segment
		(start 186.06 133.07)
		(end 190.02 133.07)
		(width 0.09)
		(layer "In11.Cu")
		(net 568)
	)
	(segment
		(start 182.87 129.44)
		(end 182.08 130.23)
		(width 0.09)
		(layer "In11.Cu")
		(net 568)
	)
	(segment
		(start 194.074 130.3)
		(end 194.15962 130.3)
		(width 0.09)
		(layer "In11.Cu")
		(net 568)
	)
	(segment
		(start 193.624 130.75)
		(end 194.074 130.3)
		(width 0.09)
		(layer "In11.Cu")
		(net 568)
	)
	(segment
		(start 184.0035 128.2915)
		(end 183.59 128.705)
		(width 0.09)
		(layer "In11.Cu")
		(net 568)
	)
	(segment
		(start 185.49 131.4)
		(end 185.49 132.5)
		(width 0.09)
		(layer "In11.Cu")
		(net 568)
	)
	(segment
		(start 190.02 133.07)
		(end 190.33 132.76)
		(width 0.09)
		(layer "In11.Cu")
		(net 568)
	)
	(segment
		(start 193.624 130.83562)
		(end 193.624 130.75)
		(width 0.09)
		(layer "In11.Cu")
		(net 568)
	)
	(segment
		(start 194.15962 130.3)
		(end 194.424 130.03562)
		(width 0.09)
		(layer "In11.Cu")
		(net 568)
	)
	(segment
		(start 191.27 131.29)
		(end 191.46 131.1)
		(width 0.09)
		(layer "In11.Cu")
		(net 568)
	)
	(segment
		(start 195.225 129.275)
		(end 195.225 127.825)
		(width 0.09)
		(layer "In11.Cu")
		(net 568)
	)
	(segment
		(start 183.59 129.21)
		(end 183.36 129.44)
		(width 0.09)
		(layer "In11.Cu")
		(net 568)
	)
	(segment
		(start 182.08 130.23)
		(end 182.08 133.2)
		(width 0.09)
		(layer "In11.Cu")
		(net 568)
	)
	(segment
		(start 194.424 129.9)
		(end 194.748 129.576)
		(width 0.09)
		(layer "In11.Cu")
		(net 568)
	)
	(segment
		(start 191 132.76)
		(end 191.27 132.49)
		(width 0.09)
		(layer "In11.Cu")
		(net 568)
	)
	(segment
		(start 185.49 132.5)
		(end 186.06 133.07)
		(width 0.09)
		(layer "In11.Cu")
		(net 568)
	)
	(segment
		(start 183.36 129.44)
		(end 182.87 129.44)
		(width 0.09)
		(layer "In11.Cu")
		(net 568)
	)
	(segment
		(start 183.55 133.22)
		(end 183.55 131.45)
		(width 0.09)
		(layer "In11.Cu")
		(net 568)
	)
	(segment
		(start 190.33 132.76)
		(end 191 132.76)
		(width 0.09)
		(layer "In11.Cu")
		(net 568)
	)
	(segment
		(start 191.46 131.1)
		(end 193.35962 131.1)
		(width 0.09)
		(layer "In11.Cu")
		(net 568)
	)
	(segment
		(start 176.91 146.56)
		(end 176.949999 146.599999)
		(width 0.1)
		(layer "F.Cu")
		(net 576)
	)
	(segment
		(start 176.949999 146.599999)
		(end 176.949999 147.15)
		(width 0.1)
		(layer "F.Cu")
		(net 576)
	)
	(segment
		(start 176.91 146.15)
		(end 176.91 146.56)
		(width 0.1)
		(layer "F.Cu")
		(net 576)
	)
	(via
		(at 176.91 146.15)
		(size 0.35)
		(drill 0.15)
		(layers "F.Cu" "B.Cu")
		(remove_unused_layers yes)
		(keep_end_layers yes)
		(zone_layer_connections)
		(net 576)
	)
	(via
		(at 177.99 138.26)
		(size 0.35)
		(drill 0.15)
		(layers "F.Cu" "B.Cu")
		(remove_unused_layers yes)
		(keep_end_layers yes)
		(zone_layer_connections)
		(net 576)
	)
	(segment
		(start 177.99 138.26)
		(end 177.99 138.27)
		(width 0.09)
		(layer "B.Cu")
		(net 576)
	)
	(segment
		(start 177.99 138.27)
		(end 178.51 138.79)
		(width 0.09)
		(layer "B.Cu")
		(net 576)
	)
	(segment
		(start 179 144.3)
		(end 178.32 144.98)
		(width 0.1)
		(layer "In7.Cu")
		(net 576)
	)
	(segment
		(start 178.55 140.55)
		(end 179 141)
		(width 0.1)
		(layer "In7.Cu")
		(net 576)
	)
	(segment
		(start 179 141)
		(end 179 144.3)
		(width 0.1)
		(layer "In7.Cu")
		(net 576)
	)
	(segment
		(start 178.55 138.82)
		(end 178.55 140.55)
		(width 0.1)
		(layer "In7.Cu")
		(net 576)
	)
	(segment
		(start 176.91 145.87)
		(end 176.91 146.15)
		(width 0.1)
		(layer "In7.Cu")
		(net 576)
	)
	(segment
		(start 178.32 144.98)
		(end 177.8 144.98)
		(width 0.1)
		(layer "In7.Cu")
		(net 576)
	)
	(segment
		(start 177.8 144.98)
		(end 176.91 145.87)
		(width 0.1)
		(layer "In7.Cu")
		(net 576)
	)
	(segment
		(start 177.99 138.26)
		(end 178.55 138.82)
		(width 0.1)
		(layer "In7.Cu")
		(net 576)
	)
	(segment
		(start 175.925999 147.126)
		(end 175.95 147.150001)
		(width 0.1)
		(layer "F.Cu")
		(net 577)
	)
	(segment
		(start 175.34203 147.126)
		(end 175.925999 147.126)
		(width 0.1)
		(layer "F.Cu")
		(net 577)
	)
	(segment
		(start 175.095001 146.95)
		(end 175.16603 146.95)
		(width 0.1)
		(layer "F.Cu")
		(net 577)
	)
	(segment
		(start 175.16603 146.95)
		(end 175.34203 147.126)
		(width 0.1)
		(layer "F.Cu")
		(net 577)
	)
	(via
		(at 177.65 145.98)
		(size 0.35)
		(drill 0.15)
		(layers "F.Cu" "B.Cu")
		(remove_unused_layers yes)
		(keep_end_layers yes)
		(zone_layer_connections)
		(net 577)
	)
	(via
		(at 175.095001 146.95)
		(size 0.35)
		(drill 0.15)
		(layers "F.Cu" "B.Cu")
		(remove_unused_layers yes)
		(keep_end_layers yes)
		(zone_layer_connections)
		(net 577)
	)
	(segment
		(start 177.65 146.17)
		(end 177.31 146.51)
		(width 0.09)
		(layer "In7.Cu")
		(net 577)
	)
	(segment
		(start 177.31 146.51)
		(end 175.97 146.51)
		(width 0.09)
		(layer "In7.Cu")
		(net 577)
	)
	(segment
		(start 175.97 146.51)
		(end 175.53 146.95)
		(width 0.09)
		(layer "In7.Cu")
		(net 577)
	)
	(segment
		(start 177.65 145.98)
		(end 177.65 146.17)
		(width 0.09)
		(layer "In7.Cu")
		(net 577)
	)
	(segment
		(start 175.53 146.95)
		(end 175.095001 146.95)
		(width 0.09)
		(layer "In7.Cu")
		(net 577)
	)
	(segment
		(start 175.337946 148.674)
		(end 175.926001 148.674)
		(width 0.1)
		(layer "F.Cu")
		(net 578)
	)
	(segment
		(start 175.105047 148.849974)
		(end 175.161972 148.849974)
		(width 0.1)
		(layer "F.Cu")
		(net 578)
	)
	(segment
		(start 175.926001 148.674)
		(end 175.950001 148.65)
		(width 0.1)
		(layer "F.Cu")
		(net 578)
	)
	(segment
		(start 175.161972 148.849974)
		(end 175.337946 148.674)
		(width 0.1)
		(layer "F.Cu")
		(net 578)
	)
	(via
		(at 175.105047 148.849974)
		(size 0.35)
		(drill 0.15)
		(layers "F.Cu" "B.Cu")
		(remove_unused_layers yes)
		(keep_end_layers yes)
		(zone_layer_connections)
		(net 578)
	)
	(via
		(at 181.825 139.595)
		(size 0.35)
		(drill 0.15)
		(layers "F.Cu" "B.Cu")
		(remove_unused_layers yes)
		(keep_end_layers yes)
		(zone_layer_connections)
		(net 578)
	)
	(segment
		(start 181.825 139.595)
		(end 182.01 139.78)
		(width 0.09)
		(layer "B.Cu")
		(net 578)
	)
	(segment
		(start 182.01 139.78)
		(end 182.41 139.78)
		(width 0.09)
		(layer "B.Cu")
		(net 578)
	)
	(segment
		(start 181.7 143.19944)
		(end 179.92544 144.974)
		(width 0.1)
		(layer "In7.Cu")
		(net 578)
	)
	(segment
		(start 181.7 139.72)
		(end 181.7 143.19944)
		(width 0.1)
		(layer "In7.Cu")
		(net 578)
	)
	(segment
		(start 175.462 148.126054)
		(end 175.462 148.549946)
		(width 0.1)
		(layer "In7.Cu")
		(net 578)
	)
	(segment
		(start 176.262054 147.326)
		(end 175.462 148.126054)
		(width 0.1)
		(layer "In7.Cu")
		(net 578)
	)
	(segment
		(start 175.161972 148.849974)
		(end 175.105047 148.849974)
		(width 0.1)
		(layer "In7.Cu")
		(net 578)
	)
	(segment
		(start 179.706 144.974)
		(end 177.354 147.326)
		(width 0.1)
		(layer "In7.Cu")
		(net 578)
	)
	(segment
		(start 177.354 147.326)
		(end 176.262054 147.326)
		(width 0.1)
		(layer "In7.Cu")
		(net 578)
	)
	(segment
		(start 179.92544 144.974)
		(end 179.706 144.974)
		(width 0.1)
		(layer "In7.Cu")
		(net 578)
	)
	(segment
		(start 181.825 139.595)
		(end 181.7 139.72)
		(width 0.1)
		(layer "In7.Cu")
		(net 578)
	)
	(segment
		(start 175.462 148.549946)
		(end 175.161972 148.849974)
		(width 0.1)
		(layer "In7.Cu")
		(net 578)
	)
	(segment
		(start 176.85 149.386982)
		(end 176.85 148.75)
		(width 0.1)
		(layer "F.Cu")
		(net 579)
	)
	(segment
		(start 176.949075 149.486057)
		(end 176.85 149.386982)
		(width 0.1)
		(layer "F.Cu")
		(net 579)
	)
	(segment
		(start 176.85 148.75)
		(end 176.95 148.65)
		(width 0.1)
		(layer "F.Cu")
		(net 579)
	)
	(via
		(at 176.949075 149.486057)
		(size 0.35)
		(drill 0.15)
		(layers "F.Cu" "B.Cu")
		(remove_unused_layers yes)
		(keep_end_layers yes)
		(zone_layer_connections)
		(net 579)
	)
	(via
		(at 182.05 144.699997)
		(size 0.35)
		(drill 0.15)
		(layers "F.Cu" "B.Cu")
		(remove_unused_layers yes)
		(keep_end_layers yes)
		(zone_layer_connections)
		(net 579)
	)
	(segment
		(start 182.570589 144.670589)
		(end 182.079408 144.670589)
		(width 0.09)
		(layer "B.Cu")
		(net 579)
	)
	(segment
		(start 182.511181 144.699997)
		(end 182.05 144.699997)
		(width 0.09)
		(layer "B.Cu")
		(net 579)
	)
	(segment
		(start 182.079408 144.670589)
		(end 182.05 144.699997)
		(width 0.09)
		(layer "B.Cu")
		(net 579)
	)
	(segment
		(start 182.580589 144.630589)
		(end 182.511181 144.699997)
		(width 0.09)
		(layer "B.Cu")
		(net 579)
	)
	(segment
		(start 180.85 144.8)
		(end 178.65 147)
		(width 0.1)
		(layer "In7.Cu")
		(net 579)
	)
	(segment
		(start 182.05 144.699997)
		(end 181.949997 144.8)
		(width 0.1)
		(layer "In7.Cu")
		(net 579)
	)
	(segment
		(start 178.65 147)
		(end 178.65 148.761946)
		(width 0.1)
		(layer "In7.Cu")
		(net 579)
	)
	(segment
		(start 176.963943 149.486057)
		(end 176.949075 149.486057)
		(width 0.1)
		(layer "In7.Cu")
		(net 579)
	)
	(segment
		(start 178.65 148.761946)
		(end 178.399946 149.012)
		(width 0.1)
		(layer "In7.Cu")
		(net 579)
	)
	(segment
		(start 181.949997 144.8)
		(end 180.85 144.8)
		(width 0.1)
		(layer "In7.Cu")
		(net 579)
	)
	(segment
		(start 177.438 149.012)
		(end 176.963943 149.486057)
		(width 0.1)
		(layer "In7.Cu")
		(net 579)
	)
	(segment
		(start 178.399946 149.012)
		(end 177.438 149.012)
		(width 0.1)
		(layer "In7.Cu")
		(net 579)
	)
	(segment
		(start 183.604 131.867)
		(end 184.0035 131.5425)
		(width 0.174)
		(layer "F.Cu")
		(net 583)
	)
	(segment
		(start 183.604 127.316)
		(end 184.0035 127.6405)
		(width 0.174)
		(layer "F.Cu")
		(net 583)
	)
	(via
		(at 184.0035 131.5425)
		(size 0.35)
		(drill 0.15)
		(layers "F.Cu" "B.Cu")
		(remove_unused_layers yes)
		(keep_end_layers yes)
		(zone_layer_connections)
		(net 583)
	)
	(via
		(at 184.0035 127.6405)
		(size 0.35)
		(drill 0.15)
		(layers "F.Cu" "B.Cu")
		(remove_unused_layers yes)
		(keep_end_layers yes)
		(zone_layer_connections)
		(net 583)
	)
	(via
		(at 194.9 128.3)
		(size 0.35)
		(drill 0.15)
		(layers "F.Cu" "B.Cu")
		(remove_unused_layers yes)
		(keep_end_layers yes)
		(zone_layer_connections)
		(net 583)
	)
	(segment
		(start 184.45 131.33)
		(end 184.2375 131.5425)
		(width 0.09)
		(layer "In9.Cu")
		(net 583)
	)
	(segment
		(start 184.6 129.42)
		(end 184.85 129.42)
		(width 0.09)
		(layer "In9.Cu")
		(net 583)
	)
	(segment
		(start 184.85 129.72)
		(end 184.6 129.72)
		(width 0.09)
		(layer "In9.Cu")
		(net 583)
	)
	(segment
		(start 184.2705 127.6405)
		(end 184.45 127.82)
		(width 0.09)
		(layer "In9.Cu")
		(net 583)
	)
	(segment
		(start 184.45 129.87)
		(end 184.45 131.33)
		(width 0.09)
		(layer "In9.Cu")
		(net 583)
	)
	(segment
		(start 184.45 127.82)
		(end 184.45 129.27)
		(width 0.09)
		(layer "In9.Cu")
		(net 583)
	)
	(segment
		(start 184.2375 131.5425)
		(end 184.0035 131.5425)
		(width 0.09)
		(layer "In9.Cu")
		(net 583)
	)
	(segment
		(start 184.0035 127.6405)
		(end 184.2705 127.6405)
		(width 0.09)
		(layer "In9.Cu")
		(net 583)
	)
	(arc
		(start 184.45 129.27)
		(mid 184.493934 129.376066)
		(end 184.6 129.42)
		(width 0.09)
		(layer "In9.Cu")
		(net 583)
	)
	(arc
		(start 184.85 129.42)
		(mid 184.956066 129.463934)
		(end 185 129.57)
		(width 0.09)
		(layer "In9.Cu")
		(net 583)
	)
	(arc
		(start 184.6 129.72)
		(mid 184.493934 129.763934)
		(end 184.45 129.87)
		(width 0.09)
		(layer "In9.Cu")
		(net 583)
	)
	(arc
		(start 185 129.57)
		(mid 184.956066 129.676066)
		(end 184.85 129.72)
		(width 0.09)
		(layer "In9.Cu")
		(net 583)
	)
	(segment
		(start 193.369 130.381)
		(end 193.7 130.05)
		(width 0.09)
		(layer "In11.Cu")
		(net 583)
	)
	(segment
		(start 193.7 129.5)
		(end 194.9 128.3)
		(width 0.09)
		(layer "In11.Cu")
		(net 583)
	)
	(segment
		(start 187.605 132.164248)
		(end 187.605 131.65575)
		(width 0.09)
		(layer "In11.Cu")
		(net 583)
	)
	(segment
		(start 182.996951 130.5715)
		(end 185.2215 130.5715)
		(width 0.09)
		(layer "In11.Cu")
		(net 583)
	)
	(segment
		(start 193.7 130.05)
		(end 193.7 129.5)
		(width 0.09)
		(layer "In11.Cu")
		(net 583)
	)
	(segment
		(start 188.48 131.91)
		(end 190.34 131.91)
		(width 0.09)
		(layer "In11.Cu")
		(net 583)
	)
	(segment
		(start 186.17 131.91)
		(end 186.38 131.91)
		(width 0.09)
		(layer "In11.Cu")
		(net 583)
	)
	(segment
		(start 182.81 130.758451)
		(end 182.996951 130.5715)
		(width 0.09)
		(layer "In11.Cu")
		(net 583)
	)
	(segment
		(start 187.255 131.65575)
		(end 187.255 132.164248)
		(width 0.09)
		(layer "In11.Cu")
		(net 583)
	)
	(segment
		(start 184.07 129.86)
		(end 182.93 129.86)
		(width 0.09)
		(layer "In11.Cu")
		(net 583)
	)
	(segment
		(start 185.2215 130.5715)
		(end 185.81 131.16)
		(width 0.09)
		(layer "In11.Cu")
		(net 583)
	)
	(segment
		(start 182.56 132.46)
		(end 182.68 132.46)
		(width 0.09)
		(layer "In11.Cu")
		(net 583)
	)
	(segment
		(start 184.37 129.56)
		(end 184.07 129.86)
		(width 0.09)
		(layer "In11.Cu")
		(net 583)
	)
	(segment
		(start 187.955 131.65575)
		(end 187.955 132.164248)
		(width 0.09)
		(layer "In11.Cu")
		(net 583)
	)
	(segment
		(start 184.0035 127.6405)
		(end 184.37 128.007)
		(width 0.09)
		(layer "In11.Cu")
		(net 583)
	)
	(segment
		(start 184.37 128.007)
		(end 184.37 129.56)
		(width 0.09)
		(layer "In11.Cu")
		(net 583)
	)
	(segment
		(start 182.44 130.35)
		(end 182.44 132.34)
		(width 0.09)
		(layer "In11.Cu")
		(net 583)
	)
	(segment
		(start 182.81 132.33)
		(end 182.81 130.758451)
		(width 0.09)
		(layer "In11.Cu")
		(net 583)
	)
	(segment
		(start 182.44 132.34)
		(end 182.56 132.46)
		(width 0.09)
		(layer "In11.Cu")
		(net 583)
	)
	(segment
		(start 185.81 131.16)
		(end 185.81 131.55)
		(width 0.09)
		(layer "In11.Cu")
		(net 583)
	)
	(segment
		(start 190.34 131.91)
		(end 190.5 131.75)
		(width 0.09)
		(layer "In11.Cu")
		(net 583)
	)
	(segment
		(start 186.905 132.164248)
		(end 186.905 131.65575)
		(width 0.09)
		(layer "In11.Cu")
		(net 583)
	)
	(segment
		(start 182.68 132.46)
		(end 182.81 132.33)
		(width 0.09)
		(layer "In11.Cu")
		(net 583)
	)
	(segment
		(start 190.767451 130.381)
		(end 193.369 130.381)
		(width 0.09)
		(layer "In11.Cu")
		(net 583)
	)
	(segment
		(start 185.81 131.55)
		(end 186.17 131.91)
		(width 0.09)
		(layer "In11.Cu")
		(net 583)
	)
	(segment
		(start 182.93 129.86)
		(end 182.44 130.35)
		(width 0.09)
		(layer "In11.Cu")
		(net 583)
	)
	(segment
		(start 188.305 132.164248)
		(end 188.305 132.085)
		(width 0.09)
		(layer "In11.Cu")
		(net 583)
	)
	(segment
		(start 186.555 132.085)
		(end 186.555 132.164248)
		(width 0.09)
		(layer "In11.Cu")
		(net 583)
	)
	(segment
		(start 190.5 130.648451)
		(end 190.767451 130.381)
		(width 0.09)
		(layer "In11.Cu")
		(net 583)
	)
	(segment
		(start 190.5 131.75)
		(end 190.5 130.648451)
		(width 0.09)
		(layer "In11.Cu")
		(net 583)
	)
	(arc
		(start 187.78 131.48075)
		(mid 187.903744 131.532006)
		(end 187.955 131.65575)
		(width 0.09)
		(layer "In11.Cu")
		(net 583)
	)
	(arc
		(start 186.555 132.164248)
		(mid 186.606256 132.287992)
		(end 186.73 132.339248)
		(width 0.09)
		(layer "In11.Cu")
		(net 583)
	)
	(arc
		(start 187.43 132.339248)
		(mid 187.553744 132.287992)
		(end 187.605 132.164248)
		(width 0.09)
		(layer "In11.Cu")
		(net 583)
	)
	(arc
		(start 186.38 131.91)
		(mid 186.503744 131.961256)
		(end 186.555 132.085)
		(width 0.09)
		(layer "In11.Cu")
		(net 583)
	)
	(arc
		(start 188.305 132.085)
		(mid 188.356256 131.961256)
		(end 188.48 131.91)
		(width 0.09)
		(layer "In11.Cu")
		(net 583)
	)
	(arc
		(start 188.13 132.339248)
		(mid 188.253744 132.287992)
		(end 188.305 132.164248)
		(width 0.09)
		(layer "In11.Cu")
		(net 583)
	)
	(arc
		(start 187.255 132.164248)
		(mid 187.306256 132.287992)
		(end 187.43 132.339248)
		(width 0.09)
		(layer "In11.Cu")
		(net 583)
	)
	(arc
		(start 187.08 131.48075)
		(mid 187.203744 131.532006)
		(end 187.255 131.65575)
		(width 0.09)
		(layer "In11.Cu")
		(net 583)
	)
	(arc
		(start 187.605 131.65575)
		(mid 187.656256 131.532006)
		(end 187.78 131.48075)
		(width 0.09)
		(layer "In11.Cu")
		(net 583)
	)
	(arc
		(start 187.955 132.164248)
		(mid 188.006256 132.287992)
		(end 188.13 132.339248)
		(width 0.09)
		(layer "In11.Cu")
		(net 583)
	)
	(arc
		(start 186.905 131.65575)
		(mid 186.956256 131.532006)
		(end 187.08 131.48075)
		(width 0.09)
		(layer "In11.Cu")
		(net 583)
	)
	(arc
		(start 186.73 132.339248)
		(mid 186.853744 132.287992)
		(end 186.905 132.164248)
		(width 0.09)
		(layer "In11.Cu")
		(net 583)
	)
	(segment
		(start 182.004 135.117)
		(end 181.6045 135.4415)
		(width 0.174)
		(layer "F.Cu")
		(net 584)
	)
	(via
		(at 194.9 129.901)
		(size 0.35)
		(drill 0.15)
		(layers "F.Cu" "B.Cu")
		(remove_unused_layers yes)
		(keep_end_layers yes)
		(zone_layer_connections)
		(net 584)
	)
	(via
		(at 181.6045 135.4415)
		(size 0.35)
		(drill 0.15)
		(layers "F.Cu" "B.Cu")
		(remove_unused_layers yes)
		(keep_end_layers yes)
		(zone_layer_connections)
		(net 584)
	)
	(segment
		(start 180.5515 135.7615)
		(end 181.2845 135.7615)
		(width 0.09)
		(layer "In4.Cu")
		(net 584)
	)
	(segment
		(start 180.34 131.554451)
		(end 180.34 135.55)
		(width 0.09)
		(layer "In4.Cu")
		(net 584)
	)
	(segment
		(start 194.9 129.901)
		(end 194.395001 129.396001)
		(width 0.09)
		(layer "In4.Cu")
		(net 584)
	)
	(segment
		(start 194.395001 129.396001)
		(end 193.35145 129.396001)
		(width 0.09)
		(layer "In4.Cu")
		(net 584)
	)
	(segment
		(start 185.11 131.22)
		(end 180.674451 131.22)
		(width 0.09)
		(layer "In4.Cu")
		(net 584)
	)
	(segment
		(start 185.25 131.36)
		(end 185.11 131.22)
		(width 0.09)
		(layer "In4.Cu")
		(net 584)
	)
	(segment
		(start 190.933549 131.12)
		(end 189.92 131.12)
		(width 0.09)
		(layer "In4.Cu")
		(net 584)
	)
	(segment
		(start 192.91 129.93)
		(end 192.67 130.17)
		(width 0.09)
		(layer "In4.Cu")
		(net 584)
	)
	(segment
		(start 189.68 131.36)
		(end 189.68 131.572549)
		(width 0.09)
		(layer "In4.Cu")
		(net 584)
	)
	(segment
		(start 180.34 135.55)
		(end 180.5515 135.7615)
		(width 0.09)
		(layer "In4.Cu")
		(net 584)
	)
	(segment
		(start 188.705451 131.36)
		(end 185.25 131.36)
		(width 0.09)
		(layer "In4.Cu")
		(net 584)
	)
	(segment
		(start 192.67 130.17)
		(end 191.778451 130.17)
		(width 0.09)
		(layer "In4.Cu")
		(net 584)
	)
	(segment
		(start 191.35 130.703549)
		(end 190.933549 131.12)
		(width 0.09)
		(layer "In4.Cu")
		(net 584)
	)
	(segment
		(start 191.35 130.598451)
		(end 191.35 130.703549)
		(width 0.09)
		(layer "In4.Cu")
		(net 584)
	)
	(segment
		(start 189.68 131.572549)
		(end 189.431549 131.821)
		(width 0.09)
		(layer "In4.Cu")
		(net 584)
	)
	(segment
		(start 193.35145 129.396001)
		(end 192.91 129.837451)
		(width 0.09)
		(layer "In4.Cu")
		(net 584)
	)
	(segment
		(start 189.431549 131.821)
		(end 189.166451 131.821)
		(width 0.09)
		(layer "In4.Cu")
		(net 584)
	)
	(segment
		(start 181.2845 135.7615)
		(end 181.6045 135.4415)
		(width 0.09)
		(layer "In4.Cu")
		(net 584)
	)
	(segment
		(start 191.778451 130.17)
		(end 191.35 130.598451)
		(width 0.09)
		(layer "In4.Cu")
		(net 584)
	)
	(segment
		(start 189.166451 131.821)
		(end 188.705451 131.36)
		(width 0.09)
		(layer "In4.Cu")
		(net 584)
	)
	(segment
		(start 189.92 131.12)
		(end 189.68 131.36)
		(width 0.09)
		(layer "In4.Cu")
		(net 584)
	)
	(segment
		(start 180.674451 131.22)
		(end 180.34 131.554451)
		(width 0.09)
		(layer "In4.Cu")
		(net 584)
	)
	(segment
		(start 192.91 129.837451)
		(end 192.91 129.93)
		(width 0.09)
		(layer "In4.Cu")
		(net 584)
	)
	(segment
		(start 182.004 133.817)
		(end 181.6045 134.1415)
		(width 0.174)
		(layer "F.Cu")
		(net 585)
	)
	(via
		(at 181.6045 134.1415)
		(size 0.35)
		(drill 0.15)
		(layers "F.Cu" "B.Cu")
		(remove_unused_layers yes)
		(keep_end_layers yes)
		(zone_layer_connections)
		(net 585)
	)
	(via
		(at 194.9 131.501)
		(size 0.35)
		(drill 0.15)
		(layers "F.Cu" "B.Cu")
		(remove_unused_layers yes)
		(keep_end_layers yes)
		(zone_layer_connections)
		(net 585)
	)
	(segment
		(start 194.5 132.73)
		(end 192.15 135.08)
		(width 0.09)
		(layer "In4.Cu")
		(net 585)
	)
	(segment
		(start 182.75 137.5)
		(end 182.2 136.95)
		(width 0.09)
		(layer "In4.Cu")
		(net 585)
	)
	(segment
		(start 182 134.9)
		(end 182 133.96)
		(width 0.09)
		(layer "In4.Cu")
		(net 585)
	)
	(segment
		(start 187.55 137.5)
		(end 187.85005 137.199952)
		(width 0.09)
		(layer "In4.Cu")
		(net 585)
	)
	(segment
		(start 188.396898 137.251826)
		(end 188.396897 137.251826)
		(width 0.09)
		(layer "In4.Cu")
		(net 585)
	)
	(segment
		(start 181.72 133.68)
		(end 181.54 133.68)
		(width 0.09)
		(layer "In4.Cu")
		(net 585)
	)
	(segment
		(start 188.644417 136.75688)
		(end 188.644417 136.756879)
		(width 0.09)
		(layer "In4.Cu")
		(net 585)
	)
	(segment
		(start 191.240329 135.955355)
		(end 191.24033 135.955355)
		(width 0.09)
		(layer "In4.Cu")
		(net 585)
	)
	(segment
		(start 188.345024 136.952464)
		(end 188.396898 137.004338)
		(width 0.09)
		(layer "In4.Cu")
		(net 585)
	)
	(segment
		(start 182 133.96)
		(end 181.72 133.68)
		(width 0.09)
		(layer "In4.Cu")
		(net 585)
	)
	(segment
		(start 190.957487 135.92)
		(end 190.957486 135.92)
		(width 0.09)
		(layer "In4.Cu")
		(net 585)
	)
	(segment
		(start 188.644417 136.756879)
		(end 188.592514 136.704976)
		(width 0.09)
		(layer "In4.Cu")
		(net 585)
	)
	(segment
		(start 194.5 131.901)
		(end 194.5 132.73)
		(width 0.09)
		(layer "In4.Cu")
		(net 585)
	)
	(segment
		(start 194.9 131.501)
		(end 194.5 131.901)
		(width 0.09)
		(layer "In4.Cu")
		(net 585)
	)
	(segment
		(start 181.44 133.78)
		(end 181.44 133.977)
		(width 0.09)
		(layer "In4.Cu")
		(net 585)
	)
	(segment
		(start 187.55 137.5)
		(end 182.75 137.5)
		(width 0.09)
		(layer "In4.Cu")
		(net 585)
	)
	(segment
		(start 190.71 135.92)
		(end 189.13 135.92)
		(width 0.09)
		(layer "In4.Cu")
		(net 585)
	)
	(segment
		(start 191.204973 135.672511)
		(end 191.240329 135.707867)
		(width 0.09)
		(layer "In4.Cu")
		(net 585)
	)
	(segment
		(start 188.149411 137.251826)
		(end 188.149411 137.251825)
		(width 0.09)
		(layer "In4.Cu")
		(net 585)
	)
	(segment
		(start 190.992842 135.955355)
		(end 190.957487 135.92)
		(width 0.09)
		(layer "In4.Cu")
		(net 585)
	)
	(segment
		(start 182.2 136.95)
		(end 182.2 135.1)
		(width 0.09)
		(layer "In4.Cu")
		(net 585)
	)
	(segment
		(start 181.44 133.977)
		(end 181.6045 134.1415)
		(width 0.09)
		(layer "In4.Cu")
		(net 585)
	)
	(segment
		(start 188.345027 136.704977)
		(end 188.345026 136.704977)
		(width 0.09)
		(layer "In4.Cu")
		(net 585)
	)
	(segment
		(start 182.2 135.1)
		(end 182 134.9)
		(width 0.09)
		(layer "In4.Cu")
		(net 585)
	)
	(segment
		(start 188.149411 137.251825)
		(end 188.097538 137.199952)
		(width 0.09)
		(layer "In4.Cu")
		(net 585)
	)
	(segment
		(start 181.54 133.68)
		(end 181.44 133.78)
		(width 0.09)
		(layer "In4.Cu")
		(net 585)
	)
	(segment
		(start 188.84 136.457488)
		(end 188.891904 136.509392)
		(width 0.09)
		(layer "In4.Cu")
		(net 585)
	)
	(segment
		(start 189.13 135.92)
		(end 188.84 136.21)
		(width 0.09)
		(layer "In4.Cu")
		(net 585)
	)
	(segment
		(start 192.15 135.08)
		(end 191.55 135.08)
		(width 0.09)
		(layer "In4.Cu")
		(net 585)
	)
	(segment
		(start 188.345026 136.704977)
		(end 188.345024 136.704976)
		(width 0.09)
		(layer "In4.Cu")
		(net 585)
	)
	(segment
		(start 191.55 135.08)
		(end 191.204973 135.425023)
		(width 0.09)
		(layer "In4.Cu")
		(net 585)
	)
	(segment
		(start 188.891903 136.756879)
		(end 188.891903 136.75688)
		(width 0.09)
		(layer "In4.Cu")
		(net 585)
	)
	(arc
		(start 191.204973 135.425023)
		(mid 191.153717 135.548767)
		(end 191.204973 135.672511)
		(width 0.09)
		(layer "In4.Cu")
		(net 585)
	)
	(arc
		(start 188.396898 137.004338)
		(mid 188.448154 137.128082)
		(end 188.396898 137.251826)
		(width 0.09)
		(layer "In4.Cu")
		(net 585)
	)
	(arc
		(start 188.097538 137.199952)
		(mid 187.973794 137.148696)
		(end 187.85005 137.199952)
		(width 0.09)
		(layer "In4.Cu")
		(net 585)
	)
	(arc
		(start 190.957486 135.92)
		(mid 190.833743 135.868744)
		(end 190.71 135.92)
		(width 0.09)
		(layer "In4.Cu")
		(net 585)
	)
	(arc
		(start 191.240329 135.707867)
		(mid 191.291585 135.831611)
		(end 191.240329 135.955355)
		(width 0.09)
		(layer "In4.Cu")
		(net 585)
	)
	(arc
		(start 188.891904 136.509392)
		(mid 188.94316 136.633136)
		(end 188.891903 136.756879)
		(width 0.09)
		(layer "In4.Cu")
		(net 585)
	)
	(arc
		(start 191.24033 135.955355)
		(mid 191.116586 136.006611)
		(end 190.992842 135.955355)
		(width 0.09)
		(layer "In4.Cu")
		(net 585)
	)
	(arc
		(start 188.84 136.21)
		(mid 188.788744 136.333744)
		(end 188.84 136.457488)
		(width 0.09)
		(layer "In4.Cu")
		(net 585)
	)
	(arc
		(start 188.891903 136.75688)
		(mid 188.768161 136.808135)
		(end 188.644417 136.75688)
		(width 0.09)
		(layer "In4.Cu")
		(net 585)
	)
	(arc
		(start 188.396897 137.251826)
		(mid 188.273155 137.303081)
		(end 188.149411 137.251826)
		(width 0.09)
		(layer "In4.Cu")
		(net 585)
	)
	(arc
		(start 188.592514 136.704976)
		(mid 188.46877 136.65372)
		(end 188.345027 136.704977)
		(width 0.09)
		(layer "In4.Cu")
		(net 585)
	)
	(arc
		(start 188.345024 136.704976)
		(mid 188.293768 136.82872)
		(end 188.345024 136.952464)
		(width 0.09)
		(layer "In4.Cu")
		(net 585)
	)
	(segment
		(start 182.004 133.167)
		(end 181.6045 132.8425)
		(width 0.174)
		(layer "F.Cu")
		(net 586)
	)
	(via
		(at 181.6045 132.8425)
		(size 0.35)
		(drill 0.15)
		(layers "F.Cu" "B.Cu")
		(remove_unused_layers yes)
		(keep_end_layers yes)
		(zone_layer_connections)
		(net 586)
	)
	(via
		(at 194.9 132.3)
		(size 0.35)
		(drill 0.15)
		(layers "F.Cu" "B.Cu")
		(remove_unused_layers yes)
		(keep_end_layers yes)
		(zone_layer_connections)
		(net 586)
	)
	(segment
		(start 181.6045 132.8425)
		(end 181.2 133.247)
		(width 0.09)
		(layer "In4.Cu")
		(net 586)
	)
	(segment
		(start 191.282549 136.37)
		(end 194.9 132.752549)
		(width 0.09)
		(layer "In4.Cu")
		(net 586)
	)
	(segment
		(start 181.47088 135.1165)
		(end 181.7665 135.1165)
		(width 0.09)
		(layer "In4.Cu")
		(net 586)
	)
	(segment
		(start 182 137.25)
		(end 182.59 137.84)
		(width 0.09)
		(layer "In4.Cu")
		(net 586)
	)
	(segment
		(start 189.84 136.37)
		(end 191.282549 136.37)
		(width 0.09)
		(layer "In4.Cu")
		(net 586)
	)
	(segment
		(start 181.2 133.247)
		(end 181.2 134.84562)
		(width 0.09)
		(layer "In4.Cu")
		(net 586)
	)
	(segment
		(start 181.2 134.84562)
		(end 181.47088 135.1165)
		(width 0.09)
		(layer "In4.Cu")
		(net 586)
	)
	(segment
		(start 182 135.35)
		(end 182 137.25)
		(width 0.09)
		(layer "In4.Cu")
		(net 586)
	)
	(segment
		(start 182.59 137.84)
		(end 188.37 137.84)
		(width 0.09)
		(layer "In4.Cu")
		(net 586)
	)
	(segment
		(start 194.9 132.752549)
		(end 194.9 132.3)
		(width 0.09)
		(layer "In4.Cu")
		(net 586)
	)
	(segment
		(start 181.7665 135.1165)
		(end 182 135.35)
		(width 0.09)
		(layer "In4.Cu")
		(net 586)
	)
	(segment
		(start 188.37 137.84)
		(end 189.84 136.37)
		(width 0.09)
		(layer "In4.Cu")
		(net 586)
	)
	(segment
		(start 176.403 131.867)
		(end 176.0035 131.5425)
		(width 0.174)
		(layer "F.Cu")
		(net 587)
	)
	(segment
		(start 176.404 127.316)
		(end 176.0045 127.6405)
		(width 0.174)
		(layer "F.Cu")
		(net 587)
	)
	(via
		(at 176.0035 131.5425)
		(size 0.35)
		(drill 0.15)
		(layers "F.Cu" "B.Cu")
		(remove_unused_layers yes)
		(keep_end_layers yes)
		(zone_layer_connections)
		(net 587)
	)
	(via
		(at 176.0045 127.6405)
		(size 0.35)
		(drill 0.15)
		(layers "F.Cu" "B.Cu")
		(remove_unused_layers yes)
		(keep_end_layers yes)
		(zone_layer_connections)
		(net 587)
	)
	(via
		(at 194.099 127.5)
		(size 0.35)
		(drill 0.15)
		(layers "F.Cu" "B.Cu")
		(remove_unused_layers yes)
		(keep_end_layers yes)
		(zone_layer_connections)
		(net 587)
	)
	(segment
		(start 176.3805 127.6405)
		(end 176.885 128.145)
		(width 0.09)
		(layer "In9.Cu")
		(net 587)
	)
	(segment
		(start 176.81 130.44)
		(end 176.81 131.13)
		(width 0.09)
		(layer "In9.Cu")
		(net 587)
	)
	(segment
		(start 176.885 128.805)
		(end 177.28 129.2)
		(width 0.09)
		(layer "In9.Cu")
		(net 587)
	)
	(segment
		(start 177.28 129.97)
		(end 176.81 130.44)
		(width 0.09)
		(layer "In9.Cu")
		(net 587)
	)
	(segment
		(start 176.885 128.145)
		(end 176.885 128.805)
		(width 0.09)
		(layer "In9.Cu")
		(net 587)
	)
	(segment
		(start 177.28 129.2)
		(end 177.28 129.97)
		(width 0.09)
		(layer "In9.Cu")
		(net 587)
	)
	(segment
		(start 176.0045 127.6405)
		(end 176.3805 127.6405)
		(width 0.09)
		(layer "In9.Cu")
		(net 587)
	)
	(segment
		(start 176.81 131.13)
		(end 176.3975 131.5425)
		(width 0.09)
		(layer "In9.Cu")
		(net 587)
	)
	(segment
		(start 176.3975 131.5425)
		(end 176.0035 131.5425)
		(width 0.09)
		(layer "In9.Cu")
		(net 587)
	)
	(segment
		(start 182.5425 124.7175)
		(end 186.4775 124.7175)
		(width 0.09)
		(layer "In11.Cu")
		(net 587)
	)
	(segment
		(start 179.78 126.90638)
		(end 181.302138 125.384242)
		(width 0.09)
		(layer "In11.Cu")
		(net 587)
	)
	(segment
		(start 195.47 126.95)
		(end 195.24 127.18)
		(width 0.09)
		(layer "In11.Cu")
		(net 587)
	)
	(segment
		(start 194.419 127.18)
		(end 194.099 127.5)
		(width 0.09)
		(layer "In11.Cu")
		(net 587)
	)
	(segment
		(start 179.2085 128.6215)
		(end 179.78 128.05)
		(width 0.09)
		(layer "In11.Cu")
		(net 587)
	)
	(segment
		(start 177.4205 127.6405)
		(end 177.71 127.93)
		(width 0.09)
		(layer "In11.Cu")
		(net 587)
	)
	(segment
		(start 177.71 128.34)
		(end 177.9915 128.6215)
		(width 0.09)
		(layer "In11.Cu")
		(net 587)
	)
	(segment
		(start 187.336 125.576)
		(end 195.226 125.576)
		(width 0.09)
		(layer "In11.Cu")
		(net 587)
	)
	(segment
		(start 179.78 128.05)
		(end 179.78 126.90638)
		(width 0.09)
		(layer "In11.Cu")
		(net 587)
	)
	(segment
		(start 195.47 125.82)
		(end 195.47 126.95)
		(width 0.09)
		(layer "In11.Cu")
		(net 587)
	)
	(segment
		(start 177.9915 128.6215)
		(end 179.2085 128.6215)
		(width 0.09)
		(layer "In11.Cu")
		(net 587)
	)
	(segment
		(start 195.226 125.576)
		(end 195.47 125.82)
		(width 0.09)
		(layer "In11.Cu")
		(net 587)
	)
	(segment
		(start 177.71 127.93)
		(end 177.71 128.34)
		(width 0.09)
		(layer "In11.Cu")
		(net 587)
	)
	(segment
		(start 181.302138 125.384242)
		(end 181.875758 125.384242)
		(width 0.09)
		(layer "In11.Cu")
		(net 587)
	)
	(segment
		(start 181.875758 125.384242)
		(end 182.5425 124.7175)
		(width 0.09)
		(layer "In11.Cu")
		(net 587)
	)
	(segment
		(start 195.24 127.18)
		(end 194.419 127.18)
		(width 0.09)
		(layer "In11.Cu")
		(net 587)
	)
	(segment
		(start 176.0045 127.6405)
		(end 177.4205 127.6405)
		(width 0.09)
		(layer "In11.Cu")
		(net 587)
	)
	(segment
		(start 186.4775 124.7175)
		(end 187.336 125.576)
		(width 0.09)
		(layer "In11.Cu")
		(net 587)
	)
	(segment
		(start 176.15 128.2)
		(end 176.171 128.2)
		(width 0.174)
		(layer "F.Cu")
		(net 588)
	)
	(segment
		(start 176.15 130.95)
		(end 176.15 130.962)
		(width 0.174)
		(layer "F.Cu")
		(net 588)
	)
	(segment
		(start 176.171 128.2)
		(end 176.404 127.967)
		(width 0.174)
		(layer "F.Cu")
		(net 588)
	)
	(segment
		(start 176.15 130.962)
		(end 176.404 131.216)
		(width 0.174)
		(layer "F.Cu")
		(net 588)
	)
	(via
		(at 194.099 128.3)
		(size 0.35)
		(drill 0.15)
		(layers "F.Cu" "B.Cu")
		(remove_unused_layers yes)
		(keep_end_layers yes)
		(zone_layer_connections)
		(net 588)
	)
	(via
		(at 176.15 130.95)
		(size 0.35)
		(drill 0.15)
		(layers "F.Cu" "B.Cu")
		(remove_unused_layers yes)
		(keep_end_layers yes)
		(zone_layer_connections)
		(net 588)
	)
	(via
		(at 176.15 128.2)
		(size 0.35)
		(drill 0.15)
		(layers "F.Cu" "B.Cu")
		(remove_unused_layers yes)
		(keep_end_layers yes)
		(zone_layer_connections)
		(net 588)
	)
	(segment
		(start 176.82 130.01)
		(end 176.731431 130.01)
		(width 0.09)
		(layer "In9.Cu")
		(net 588)
	)
	(segment
		(start 176.15 128.2)
		(end 176.47 128.52)
		(width 0.09)
		(layer "In9.Cu")
		(net 588)
	)
	(segment
		(start 176.82 129.41)
		(end 176.12 129.41)
		(width 0.09)
		(layer "In9.Cu")
		(net 588)
	)
	(segment
		(start 176.47 130.271431)
		(end 176.47 130.63)
		(width 0.09)
		(layer "In9.Cu")
		(net 588)
	)
	(segment
		(start 176.47 128.52)
		(end 176.47 128.854224)
		(width 0.09)
		(layer "In9.Cu")
		(net 588)
	)
	(segment
		(start 176.47 130.63)
		(end 176.15 130.95)
		(width 0.09)
		(layer "In9.Cu")
		(net 588)
	)
	(segment
		(start 176.725776 129.11)
		(end 176.82 129.11)
		(width 0.09)
		(layer "In9.Cu")
		(net 588)
	)
	(segment
		(start 176.12 129.71)
		(end 176.82 129.71)
		(width 0.09)
		(layer "In9.Cu")
		(net 588)
	)
	(arc
		(start 175.97 129.56)
		(mid 176.013934 129.666066)
		(end 176.12 129.71)
		(width 0.09)
		(layer "In9.Cu")
		(net 588)
	)
	(arc
		(start 176.12 129.41)
		(mid 176.013934 129.453934)
		(end 175.97 129.56)
		(width 0.09)
		(layer "In9.Cu")
		(net 588)
	)
	(arc
		(start 176.82 129.71)
		(mid 176.926066 129.753934)
		(end 176.97 129.86)
		(width 0.09)
		(layer "In9.Cu")
		(net 588)
	)
	(arc
		(start 176.731431 130.01)
		(mid 176.546571 130.086571)
		(end 176.47 130.271431)
		(width 0.09)
		(layer "In9.Cu")
		(net 588)
	)
	(arc
		(start 176.47 128.854224)
		(mid 176.544915 129.035085)
		(end 176.725776 129.11)
		(width 0.09)
		(layer "In9.Cu")
		(net 588)
	)
	(arc
		(start 176.82 129.11)
		(mid 176.926066 129.153934)
		(end 176.97 129.26)
		(width 0.09)
		(layer "In9.Cu")
		(net 588)
	)
	(arc
		(start 176.97 129.26)
		(mid 176.926066 129.366066)
		(end 176.82 129.41)
		(width 0.09)
		(layer "In9.Cu")
		(net 588)
	)
	(arc
		(start 176.97 129.86)
		(mid 176.926066 129.966066)
		(end 176.82 130.01)
		(width 0.09)
		(layer "In9.Cu")
		(net 588)
	)
	(segment
		(start 182.31 129.2)
		(end 182.31 128.52)
		(width 0.09)
		(layer "In11.Cu")
		(net 588)
	)
	(segment
		(start 186.26 131.16)
		(end 189.46 131.16)
		(width 0.09)
		(layer "In11.Cu")
		(net 588)
	)
	(segment
		(start 184.42 127.709549)
		(end 184.681951 127.9715)
		(width 0.09)
		(layer "In11.Cu")
		(net 588)
	)
	(segment
		(start 176.72 129.35)
		(end 177.19 129.82)
		(width 0.09)
		(layer "In11.Cu")
		(net 588)
	)
	(segment
		(start 182.31 128.52)
		(end 182.8695 127.9605)
		(width 0.09)
		(layer "In11.Cu")
		(net 588)
	)
	(segment
		(start 176.5 128.2)
		(end 176.72 128.42)
		(width 0.09)
		(layer "In11.Cu")
		(net 588)
	)
	(segment
		(start 184.42 127.52)
		(end 184.42 127.709549)
		(width 0.09)
		(layer "In11.Cu")
		(net 588)
	)
	(segment
		(start 183.56 127.51)
		(end 183.79 127.28)
		(width 0.09)
		(layer "In11.Cu")
		(net 588)
	)
	(segment
		(start 189.71 130.63)
		(end 190.02 130.32)
		(width 0.09)
		(layer "In11.Cu")
		(net 588)
	)
	(segment
		(start 183.56 127.85)
		(end 183.56 127.51)
		(width 0.09)
		(layer "In11.Cu")
		(net 588)
	)
	(segment
		(start 190.49 129.73)
		(end 190.75 129.47)
		(width 0.09)
		(layer "In11.Cu")
		(net 588)
	)
	(segment
		(start 185.29 130.19)
		(end 186.26 131.16)
		(width 0.09)
		(layer "In11.Cu")
		(net 588)
	)
	(segment
		(start 190.293549 130.32)
		(end 190.49 130.123549)
		(width 0.09)
		(layer "In11.Cu")
		(net 588)
	)
	(segment
		(start 192.929 129.47)
		(end 194.099 128.3)
		(width 0.09)
		(layer "In11.Cu")
		(net 588)
	)
	(segment
		(start 176.15 128.2)
		(end 176.5 128.2)
		(width 0.09)
		(layer "In11.Cu")
		(net 588)
	)
	(segment
		(start 183.79 127.28)
		(end 184.18 127.28)
		(width 0.09)
		(layer "In11.Cu")
		(net 588)
	)
	(segment
		(start 184.681951 127.9715)
		(end 184.9915 127.9715)
		(width 0.09)
		(layer "In11.Cu")
		(net 588)
	)
	(segment
		(start 190.75 129.47)
		(end 192.929 129.47)
		(width 0.09)
		(layer "In11.Cu")
		(net 588)
	)
	(segment
		(start 184.9915 127.9715)
		(end 185.29 128.27)
		(width 0.09)
		(layer "In11.Cu")
		(net 588)
	)
	(segment
		(start 183.4495 127.9605)
		(end 183.56 127.85)
		(width 0.09)
		(layer "In11.Cu")
		(net 588)
	)
	(segment
		(start 189.46 131.16)
		(end 189.71 130.91)
		(width 0.09)
		(layer "In11.Cu")
		(net 588)
	)
	(segment
		(start 176.72 128.42)
		(end 176.72 129.35)
		(width 0.09)
		(layer "In11.Cu")
		(net 588)
	)
	(segment
		(start 190.49 130.123549)
		(end 190.49 129.73)
		(width 0.09)
		(layer "In11.Cu")
		(net 588)
	)
	(segment
		(start 189.71 130.91)
		(end 189.71 130.63)
		(width 0.09)
		(layer "In11.Cu")
		(net 588)
	)
	(segment
		(start 181.69 129.82)
		(end 182.31 129.2)
		(width 0.09)
		(layer "In11.Cu")
		(net 588)
	)
	(segment
		(start 185.29 128.27)
		(end 185.29 130.19)
		(width 0.09)
		(layer "In11.Cu")
		(net 588)
	)
	(segment
		(start 190.02 130.32)
		(end 190.293549 130.32)
		(width 0.09)
		(layer "In11.Cu")
		(net 588)
	)
	(segment
		(start 182.8695 127.9605)
		(end 183.4495 127.9605)
		(width 0.09)
		(layer "In11.Cu")
		(net 588)
	)
	(segment
		(start 184.18 127.28)
		(end 184.42 127.52)
		(width 0.09)
		(layer "In11.Cu")
		(net 588)
	)
	(segment
		(start 177.19 129.82)
		(end 181.69 129.82)
		(width 0.09)
		(layer "In11.Cu")
		(net 588)
	)
	(segment
		(start 183.604 135.117)
		(end 184.0035 135.4415)
		(width 0.174)
		(layer "F.Cu")
		(net 589)
	)
	(via
		(at 194.099 129.901)
		(size 0.35)
		(drill 0.15)
		(layers "F.Cu" "B.Cu")
		(remove_unused_layers yes)
		(keep_end_layers yes)
		(zone_layer_connections)
		(net 589)
	)
	(via
		(at 184.0035 135.4415)
		(size 0.35)
		(drill 0.15)
		(layers "F.Cu" "B.Cu")
		(remove_unused_layers yes)
		(keep_end_layers yes)
		(zone_layer_connections)
		(net 589)
	)
	(segment
		(start 185.3 134.97)
		(end 185.56 134.97)
		(width 0.09)
		(layer "In4.Cu")
		(net 589)
	)
	(segment
		(start 185.71 135.12)
		(end 185.71 135.208347)
		(width 0.09)
		(layer "In4.Cu")
		(net 589)
	)
	(segment
		(start 193.83 131.31)
		(end 193.83 130.17)
		(width 0.09)
		(layer "In4.Cu")
		(net 589)
	)
	(segment
		(start 193.18 131.91)
		(end 193.342549 131.91)
		(width 0.09)
		(layer "In4.Cu")
		(net 589)
	)
	(segment
		(start 191.38 133.48)
		(end 192.06 132.8)
		(width 0.09)
		(layer "In4.Cu")
		(net 589)
	)
	(segment
		(start 186.01 135.208347)
		(end 186.01 135.12)
		(width 0.09)
		(layer "In4.Cu")
		(net 589)
	)
	(segment
		(start 188.71 133.63)
		(end 188.71 133.73)
		(width 0.09)
		(layer "In4.Cu")
		(net 589)
	)
	(segment
		(start 184.4 133.97)
		(end 184.6 133.77)
		(width 0.09)
		(layer "In4.Cu")
		(net 589)
	)
	(segment
		(start 189.01 133.73)
		(end 189.01 133.63)
		(width 0.09)
		(layer "In4.Cu")
		(net 589)
	)
	(segment
		(start 189.16 133.48)
		(end 191.38 133.48)
		(width 0.09)
		(layer "In4.Cu")
		(net 589)
	)
	(segment
		(start 185.65 134.07)
		(end 185.3 134.07)
		(width 0.09)
		(layer "In4.Cu")
		(net 589)
	)
	(segment
		(start 192.93 132.63)
		(end 192.93 132.16)
		(width 0.09)
		(layer "In4.Cu")
		(net 589)
	)
	(segment
		(start 186.61 135.208347)
		(end 186.61 134.48)
		(width 0.09)
		(layer "In4.Cu")
		(net 589)
	)
	(segment
		(start 192.06 132.8)
		(end 192.76 132.8)
		(width 0.09)
		(layer "In4.Cu")
		(net 589)
	)
	(segment
		(start 184.0035 135.4415)
		(end 184.4 135.045)
		(width 0.09)
		(layer "In4.Cu")
		(net 589)
	)
	(segment
		(start 187.96 134.33)
		(end 188.039513 134.33)
		(width 0.09)
		(layer "In4.Cu")
		(net 589)
	)
	(segment
		(start 192.93 132.16)
		(end 193.18 131.91)
		(width 0.09)
		(layer "In4.Cu")
		(net 589)
	)
	(segment
		(start 193.342549 131.91)
		(end 193.779 131.473549)
		(width 0.09)
		(layer "In4.Cu")
		(net 589)
	)
	(segment
		(start 192.76 132.8)
		(end 192.93 132.63)
		(width 0.09)
		(layer "In4.Cu")
		(net 589)
	)
	(segment
		(start 187.81 134.58)
		(end 187.81 134.48)
		(width 0.09)
		(layer "In4.Cu")
		(net 589)
	)
	(segment
		(start 185.3 134.37)
		(end 186.1 134.37)
		(width 0.09)
		(layer "In4.Cu")
		(net 589)
	)
	(segment
		(start 184.4 135.045)
		(end 184.4 133.97)
		(width 0.09)
		(layer "In4.Cu")
		(net 589)
	)
	(segment
		(start 193.779 131.473549)
		(end 193.779 131.361)
		(width 0.09)
		(layer "In4.Cu")
		(net 589)
	)
	(segment
		(start 193.779 131.361)
		(end 193.83 131.31)
		(width 0.09)
		(layer "In4.Cu")
		(net 589)
	)
	(segment
		(start 187.51 134.48)
		(end 187.51 134.58)
		(width 0.09)
		(layer "In4.Cu")
		(net 589)
	)
	(segment
		(start 193.83 130.17)
		(end 194.099 129.901)
		(width 0.09)
		(layer "In4.Cu")
		(net 589)
	)
	(segment
		(start 187.21 134.78)
		(end 187.21 134.48)
		(width 0.09)
		(layer "In4.Cu")
		(net 589)
	)
	(segment
		(start 184.6 133.77)
		(end 185.65 133.77)
		(width 0.09)
		(layer "In4.Cu")
		(net 589)
	)
	(segment
		(start 186.1 134.67)
		(end 185.3 134.67)
		(width 0.09)
		(layer "In4.Cu")
		(net 589)
	)
	(segment
		(start 186.31 135.12)
		(end 186.31 135.208347)
		(width 0.09)
		(layer "In4.Cu")
		(net 589)
	)
	(segment
		(start 188.41 133.959513)
		(end 188.41 133.63)
		(width 0.09)
		(layer "In4.Cu")
		(net 589)
	)
	(segment
		(start 186.91 134.48)
		(end 186.91 134.78)
		(width 0.09)
		(layer "In4.Cu")
		(net 589)
	)
	(arc
		(start 187.36 134.33)
		(mid 187.466066 134.373934)
		(end 187.51 134.48)
		(width 0.09)
		(layer "In4.Cu")
		(net 589)
	)
	(arc
		(start 189.01 133.63)
		(mid 189.053934 133.523934)
		(end 189.16 133.48)
		(width 0.09)
		(layer "In4.Cu")
		(net 589)
	)
	(arc
		(start 186.46 135.358347)
		(mid 186.566066 135.314413)
		(end 186.61 135.208347)
		(width 0.09)
		(layer "In4.Cu")
		(net 589)
	)
	(arc
		(start 185.8 133.92)
		(mid 185.756066 134.026066)
		(end 185.65 134.07)
		(width 0.09)
		(layer "In4.Cu")
		(net 589)
	)
	(arc
		(start 187.66 134.73)
		(mid 187.766066 134.686066)
		(end 187.81 134.58)
		(width 0.09)
		(layer "In4.Cu")
		(net 589)
	)
	(arc
		(start 185.86 135.358347)
		(mid 185.966066 135.314413)
		(end 186.01 135.208347)
		(width 0.09)
		(layer "In4.Cu")
		(net 589)
	)
	(arc
		(start 185.15 134.22)
		(mid 185.193934 134.326066)
		(end 185.3 134.37)
		(width 0.09)
		(layer "In4.Cu")
		(net 589)
	)
	(arc
		(start 187.21 134.48)
		(mid 187.253934 134.373934)
		(end 187.36 134.33)
		(width 0.09)
		(layer "In4.Cu")
		(net 589)
	)
	(arc
		(start 186.31 135.208347)
		(mid 186.353934 135.314413)
		(end 186.46 135.358347)
		(width 0.09)
		(layer "In4.Cu")
		(net 589)
	)
	(arc
		(start 186.01 135.12)
		(mid 186.053934 135.013934)
		(end 186.16 134.97)
		(width 0.09)
		(layer "In4.Cu")
		(net 589)
	)
	(arc
		(start 186.91 134.78)
		(mid 186.953934 134.886066)
		(end 187.06 134.93)
		(width 0.09)
		(layer "In4.Cu")
		(net 589)
	)
	(arc
		(start 187.81 134.48)
		(mid 187.853934 134.373934)
		(end 187.96 134.33)
		(width 0.09)
		(layer "In4.Cu")
		(net 589)
	)
	(arc
		(start 185.65 133.77)
		(mid 185.756066 133.813934)
		(end 185.8 133.92)
		(width 0.09)
		(layer "In4.Cu")
		(net 589)
	)
	(arc
		(start 186.16 134.97)
		(mid 186.266066 135.013934)
		(end 186.31 135.12)
		(width 0.09)
		(layer "In4.Cu")
		(net 589)
	)
	(arc
		(start 186.1 134.37)
		(mid 186.206066 134.413934)
		(end 186.25 134.52)
		(width 0.09)
		(layer "In4.Cu")
		(net 589)
	)
	(arc
		(start 187.06 134.93)
		(mid 187.166066 134.886066)
		(end 187.21 134.78)
		(width 0.09)
		(layer "In4.Cu")
		(net 589)
	)
	(arc
		(start 185.15 134.82)
		(mid 185.193934 134.926066)
		(end 185.3 134.97)
		(width 0.09)
		(layer "In4.Cu")
		(net 589)
	)
	(arc
		(start 188.86 133.88)
		(mid 188.966066 133.836066)
		(end 189.01 133.73)
		(width 0.09)
		(layer "In4.Cu")
		(net 589)
	)
	(arc
		(start 185.71 135.208347)
		(mid 185.753934 135.314413)
		(end 185.86 135.358347)
		(width 0.09)
		(layer "In4.Cu")
		(net 589)
	)
	(arc
		(start 188.039513 134.33)
		(mid 188.301487 134.221487)
		(end 188.41 133.959513)
		(width 0.09)
		(layer "In4.Cu")
		(net 589)
	)
	(arc
		(start 188.71 133.73)
		(mid 188.753934 133.836066)
		(end 188.86 133.88)
		(width 0.09)
		(layer "In4.Cu")
		(net 589)
	)
	(arc
		(start 185.3 134.67)
		(mid 185.193934 134.713934)
		(end 185.15 134.82)
		(width 0.09)
		(layer "In4.Cu")
		(net 589)
	)
	(arc
		(start 186.61 134.48)
		(mid 186.653934 134.373934)
		(end 186.76 134.33)
		(width 0.09)
		(layer "In4.Cu")
		(net 589)
	)
	(arc
		(start 186.25 134.52)
		(mid 186.206066 134.626066)
		(end 186.1 134.67)
		(width 0.09)
		(layer "In4.Cu")
		(net 589)
	)
	(arc
		(start 185.3 134.07)
		(mid 185.193934 134.113934)
		(end 185.15 134.22)
		(width 0.09)
		(layer "In4.Cu")
		(net 589)
	)
	(arc
		(start 188.41 133.63)
		(mid 188.453934 133.523934)
		(end 188.56 133.48)
		(width 0.09)
		(layer "In4.Cu")
		(net 589)
	)
	(arc
		(start 185.56 134.97)
		(mid 185.666066 135.013934)
		(end 185.71 135.12)
		(width 0.09)
		(layer "In4.Cu")
		(net 589)
	)
	(arc
		(start 188.56 133.48)
		(mid 188.666066 133.523934)
		(end 188.71 133.63)
		(width 0.09)
		(layer "In4.Cu")
		(net 589)
	)
	(arc
		(start 186.76 134.33)
		(mid 186.866066 134.373934)
		(end 186.91 134.48)
		(width 0.09)
		(layer "In4.Cu")
		(net 589)
	)
	(arc
		(start 187.51 134.58)
		(mid 187.553934 134.686066)
		(end 187.66 134.73)
		(width 0.09)
		(layer "In4.Cu")
		(net 589)
	)
	(segment
		(start 182.805 135.117)
		(end 183.2045 135.4415)
		(width 0.174)
		(layer "F.Cu")
		(net 590)
	)
	(via
		(at 194.099 131.501)
		(size 0.35)
		(drill 0.15)
		(layers "F.Cu" "B.Cu")
		(remove_unused_layers yes)
		(keep_end_layers yes)
		(zone_layer_connections)
		(net 590)
	)
	(via
		(at 183.2045 135.4415)
		(size 0.35)
		(drill 0.15)
		(layers "F.Cu" "B.Cu")
		(remove_unused_layers yes)
		(keep_end_layers yes)
		(zone_layer_connections)
		(net 590)
	)
	(segment
		(start 187.4185 135.7615)
		(end 187.555 135.625)
		(width 0.09)
		(layer "In4.Cu")
		(net 590)
	)
	(segment
		(start 184.4985 135.7615)
		(end 184.67 135.7615)
		(width 0.09)
		(layer "In4.Cu")
		(net 590)
	)
	(segment
		(start 188.537131 134.854999)
		(end 188.669084 134.986953)
		(width 0.09)
		(layer "In4.Cu")
		(net 590)
	)
	(segment
		(start 191.55 133.75)
		(end 192.19 133.11)
		(width 0.09)
		(layer "In4.Cu")
		(net 590)
	)
	(segment
		(start 188.749262 134.642865)
		(end 188.881217 134.77482)
		(width 0.09)
		(layer "In4.Cu")
		(net 590)
	)
	(segment
		(start 188.53713 134.855)
		(end 188.537131 134.854999)
		(width 0.09)
		(layer "In4.Cu")
		(net 590)
	)
	(segment
		(start 187.767134 135.236093)
		(end 187.767133 135.236093)
		(width 0.09)
		(layer "In4.Cu")
		(net 590)
	)
	(segment
		(start 183.2045 135.4415)
		(end 183.2045 135.574342)
		(width 0.09)
		(layer "In4.Cu")
		(net 590)
	)
	(segment
		(start 192.19 133.11)
		(end 192.99 133.11)
		(width 0.09)
		(layer "In4.Cu")
		(net 590)
	)
	(segment
		(start 184.36 135.9)
		(end 184.4985 135.7615)
		(width 0.09)
		(layer "In4.Cu")
		(net 590)
	)
	(segment
		(start 193.575 132.025)
		(end 194.099 131.501)
		(width 0.09)
		(layer "In4.Cu")
		(net 590)
	)
	(segment
		(start 189.43 133.75)
		(end 191.55 133.75)
		(width 0.09)
		(layer "In4.Cu")
		(net 590)
	)
	(segment
		(start 187.767133 135.236093)
		(end 187.943908 135.412868)
		(width 0.09)
		(layer "In4.Cu")
		(net 590)
	)
	(segment
		(start 184.36 136.37)
		(end 184.36 135.9)
		(width 0.09)
		(layer "In4.Cu")
		(net 590)
	)
	(segment
		(start 193.575 132.525)
		(end 193.575 132.025)
		(width 0.09)
		(layer "In4.Cu")
		(net 590)
	)
	(segment
		(start 187.07 135.7615)
		(end 187.4185 135.7615)
		(width 0.09)
		(layer "In4.Cu")
		(net 590)
	)
	(segment
		(start 187.555 135.271448)
		(end 187.590357 135.236092)
		(width 0.09)
		(layer "In4.Cu")
		(net 590)
	)
	(segment
		(start 186.92 136.4115)
		(end 186.92 135.9115)
		(width 0.09)
		(layer "In4.Cu")
		(net 590)
	)
	(segment
		(start 188.156039 135.023958)
		(end 188.324999 134.854999)
		(width 0.09)
		(layer "In4.Cu")
		(net 590)
	)
	(segment
		(start 188.749263 134.430734)
		(end 188.749262 134.430733)
		(width 0.09)
		(layer "In4.Cu")
		(net 590)
	)
	(segment
		(start 183.55 136.21)
		(end 183.89 136.55)
		(width 0.09)
		(layer "In4.Cu")
		(net 590)
	)
	(segment
		(start 186.02 135.9115)
		(end 186.02 136.4115)
		(width 0.09)
		(layer "In4.Cu")
		(net 590)
	)
	(segment
		(start 185.42 135.9115)
		(end 185.42 136.4115)
		(width 0.09)
		(layer "In4.Cu")
		(net 590)
	)
	(segment
		(start 183.2045 135.574342)
		(end 183.55 135.919842)
		(width 0.09)
		(layer "In4.Cu")
		(net 590)
	)
	(segment
		(start 192.99 133.11)
		(end 193.575 132.525)
		(width 0.09)
		(layer "In4.Cu")
		(net 590)
	)
	(segment
		(start 188.120684 135.412868)
		(end 188.120685 135.412868)
		(width 0.09)
		(layer "In4.Cu")
		(net 590)
	)
	(segment
		(start 189.173527 134.006471)
		(end 189.43 133.75)
		(width 0.09)
		(layer "In4.Cu")
		(net 590)
	)
	(segment
		(start 185.12 136.4115)
		(end 185.12 135.9115)
		(width 0.09)
		(layer "In4.Cu")
		(net 590)
	)
	(segment
		(start 186.62 135.9115)
		(end 186.62 136.4115)
		(width 0.09)
		(layer "In4.Cu")
		(net 590)
	)
	(segment
		(start 189.305478 134.562686)
		(end 189.305478 134.562687)
		(width 0.09)
		(layer "In4.Cu")
		(net 590)
	)
	(segment
		(start 188.156039 135.200735)
		(end 188.15604 135.200735)
		(width 0.09)
		(layer "In4.Cu")
		(net 590)
	)
	(segment
		(start 189.305479 134.350554)
		(end 189.305478 134.350554)
		(width 0.09)
		(layer "In4.Cu")
		(net 590)
	)
	(segment
		(start 183.55 135.919842)
		(end 183.55 136.21)
		(width 0.09)
		(layer "In4.Cu")
		(net 590)
	)
	(segment
		(start 185.72 136.4115)
		(end 185.72 135.9115)
		(width 0.09)
		(layer "In4.Cu")
		(net 590)
	)
	(segment
		(start 189.305478 134.350554)
		(end 189.173526 134.218602)
		(width 0.09)
		(layer "In4.Cu")
		(net 590)
	)
	(segment
		(start 186.32 136.4115)
		(end 186.32 135.9115)
		(width 0.09)
		(layer "In4.Cu")
		(net 590)
	)
	(segment
		(start 189.173526 134.00647)
		(end 189.173527 134.006471)
		(width 0.09)
		(layer "In4.Cu")
		(net 590)
	)
	(segment
		(start 183.89 136.55)
		(end 184.18 136.55)
		(width 0.09)
		(layer "In4.Cu")
		(net 590)
	)
	(segment
		(start 188.749262 134.430733)
		(end 188.749263 134.430735)
		(width 0.09)
		(layer "In4.Cu")
		(net 590)
	)
	(segment
		(start 184.82 135.9115)
		(end 184.82 136.4115)
		(width 0.09)
		(layer "In4.Cu")
		(net 590)
	)
	(segment
		(start 188.961395 134.430735)
		(end 189.093346 134.562686)
		(width 0.09)
		(layer "In4.Cu")
		(net 590)
	)
	(segment
		(start 184.18 136.55)
		(end 184.36 136.37)
		(width 0.09)
		(layer "In4.Cu")
		(net 590)
	)
	(segment
		(start 188.120685 135.412868)
		(end 188.15604 135.377512)
		(width 0.09)
		(layer "In4.Cu")
		(net 590)
	)
	(segment
		(start 187.555001 135.271447)
		(end 187.555 135.271448)
		(width 0.09)
		(layer "In4.Cu")
		(net 590)
	)
	(segment
		(start 188.961394 134.430736)
		(end 188.961395 134.430735)
		(width 0.09)
		(layer "In4.Cu")
		(net 590)
	)
	(arc
		(start 185.72 135.9115)
		(mid 185.763934 135.805434)
		(end 185.87 135.7615)
		(width 0.09)
		(layer "In4.Cu")
		(net 590)
	)
	(arc
		(start 185.12 135.9115)
		(mid 185.163934 135.805434)
		(end 185.27 135.7615)
		(width 0.09)
		(layer "In4.Cu")
		(net 590)
	)
	(arc
		(start 186.92 135.9115)
		(mid 186.963934 135.805434)
		(end 187.07 135.7615)
		(width 0.09)
		(layer "In4.Cu")
		(net 590)
	)
	(arc
		(start 188.669084 134.986953)
		(mid 188.77515 135.030887)
		(end 188.881216 134.986953)
		(width 0.09)
		(layer "In4.Cu")
		(net 590)
	)
	(arc
		(start 189.173526 134.218602)
		(mid 189.129592 134.112536)
		(end 189.173526 134.00647)
		(width 0.09)
		(layer "In4.Cu")
		(net 590)
	)
	(arc
		(start 185.57 136.5615)
		(mid 185.676066 136.517566)
		(end 185.72 136.4115)
		(width 0.09)
		(layer "In4.Cu")
		(net 590)
	)
	(arc
		(start 187.555 135.448224)
		(mid 187.518389 135.359835)
		(end 187.555001 135.271447)
		(width 0.09)
		(layer "In4.Cu")
		(net 590)
	)
	(arc
		(start 185.42 136.4115)
		(mid 185.463934 136.517566)
		(end 185.57 136.5615)
		(width 0.09)
		(layer "In4.Cu")
		(net 590)
	)
	(arc
		(start 184.82 136.4115)
		(mid 184.863934 136.517566)
		(end 184.97 136.5615)
		(width 0.09)
		(layer "In4.Cu")
		(net 590)
	)
	(arc
		(start 188.15604 135.200735)
		(mid 188.119428 135.112347)
		(end 188.156039 135.023958)
		(width 0.09)
		(layer "In4.Cu")
		(net 590)
	)
	(arc
		(start 187.943908 135.412868)
		(mid 188.032296 135.44948)
		(end 188.120684 135.412868)
		(width 0.09)
		(layer "In4.Cu")
		(net 590)
	)
	(arc
		(start 186.02 136.4115)
		(mid 186.063934 136.517566)
		(end 186.17 136.5615)
		(width 0.09)
		(layer "In4.Cu")
		(net 590)
	)
	(arc
		(start 189.093346 134.562686)
		(mid 189.199412 134.60662)
		(end 189.305478 134.562686)
		(width 0.09)
		(layer "In4.Cu")
		(net 590)
	)
	(arc
		(start 187.590357 135.236092)
		(mid 187.678746 135.199481)
		(end 187.767134 135.236093)
		(width 0.09)
		(layer "In4.Cu")
		(net 590)
	)
	(arc
		(start 186.62 136.4115)
		(mid 186.663934 136.517566)
		(end 186.77 136.5615)
		(width 0.09)
		(layer "In4.Cu")
		(net 590)
	)
	(arc
		(start 186.47 135.7615)
		(mid 186.576066 135.805434)
		(end 186.62 135.9115)
		(width 0.09)
		(layer "In4.Cu")
		(net 590)
	)
	(arc
		(start 188.324999 134.854999)
		(mid 188.431065 134.811066)
		(end 188.53713 134.855)
		(width 0.09)
		(layer "In4.Cu")
		(net 590)
	)
	(arc
		(start 188.881216 134.986953)
		(mid 188.925151 134.880887)
		(end 188.881217 134.77482)
		(width 0.09)
		(layer "In4.Cu")
		(net 590)
	)
	(arc
		(start 186.17 136.5615)
		(mid 186.276066 136.517566)
		(end 186.32 136.4115)
		(width 0.09)
		(layer "In4.Cu")
		(net 590)
	)
	(arc
		(start 184.67 135.7615)
		(mid 184.776066 135.805434)
		(end 184.82 135.9115)
		(width 0.09)
		(layer "In4.Cu")
		(net 590)
	)
	(arc
		(start 186.77 136.5615)
		(mid 186.876066 136.517566)
		(end 186.92 136.4115)
		(width 0.09)
		(layer "In4.Cu")
		(net 590)
	)
	(arc
		(start 185.87 135.7615)
		(mid 185.976066 135.805434)
		(end 186.02 135.9115)
		(width 0.09)
		(layer "In4.Cu")
		(net 590)
	)
	(arc
		(start 189.305478 134.562687)
		(mid 189.349413 134.456621)
		(end 189.305479 134.350554)
		(width 0.09)
		(layer "In4.Cu")
		(net 590)
	)
	(arc
		(start 188.15604 135.377512)
		(mid 188.192651 135.289123)
		(end 188.156039 135.200735)
		(width 0.09)
		(layer "In4.Cu")
		(net 590)
	)
	(arc
		(start 188.749262 134.642865)
		(mid 188.705329 134.536799)
		(end 188.749263 134.430734)
		(width 0.09)
		(layer "In4.Cu")
		(net 590)
	)
	(arc
		(start 188.749263 134.430735)
		(mid 188.855329 134.386802)
		(end 188.961394 134.430736)
		(width 0.09)
		(layer "In4.Cu")
		(net 590)
	)
	(arc
		(start 185.27 135.7615)
		(mid 185.376066 135.805434)
		(end 185.42 135.9115)
		(width 0.09)
		(layer "In4.Cu")
		(net 590)
	)
	(arc
		(start 184.97 136.5615)
		(mid 185.076066 136.517566)
		(end 185.12 136.4115)
		(width 0.09)
		(layer "In4.Cu")
		(net 590)
	)
	(arc
		(start 186.32 135.9115)
		(mid 186.363934 135.805434)
		(end 186.47 135.7615)
		(width 0.09)
		(layer "In4.Cu")
		(net 590)
	)
	(arc
		(start 187.555 135.625)
		(mid 187.591612 135.536612)
		(end 187.555 135.448224)
		(width 0.09)
		(layer "In4.Cu")
		(net 590)
	)
	(segment
		(start 183.604 133.817)
		(end 184.0035 134.1415)
		(width 0.174)
		(layer "F.Cu")
		(net 591)
	)
	(via
		(at 184.0035 134.1415)
		(size 0.35)
		(drill 0.15)
		(layers "F.Cu" "B.Cu")
		(remove_unused_layers yes)
		(keep_end_layers yes)
		(zone_layer_connections)
		(net 591)
	)
	(via
		(at 194.099 132.3)
		(size 0.35)
		(drill 0.15)
		(layers "F.Cu" "B.Cu")
		(remove_unused_layers yes)
		(keep_end_layers yes)
		(zone_layer_connections)
		(net 591)
	)
	(segment
		(start 187.29 137.25)
		(end 182.82 137.25)
		(width 0.09)
		(layer "In4.Cu")
		(net 591)
	)
	(segment
		(start 182.45 136.18)
		(end 182.45 135.385833)
		(width 0.09)
		(layer "In4.Cu")
		(net 591)
	)
	(segment
		(start 189.78 135.69)
		(end 188.85 135.69)
		(width 0.09)
		(layer "In4.Cu")
		(net 591)
	)
	(segment
		(start 183.305049 134.742913)
		(end 183.411114 134.848979)
		(width 0.09)
		(layer "In4.Cu")
		(net 591)
	)
	(segment
		(start 188.85 135.69)
		(end 187.29 137.25)
		(width 0.09)
		(layer "In4.Cu")
		(net 591)
	)
	(segment
		(start 183.51718 134.530779)
		(end 183.623247 134.636846)
		(width 0.09)
		(layer "In4.Cu")
		(net 591)
	)
	(segment
		(start 183.694333 134.1415)
		(end 184.0035 134.1415)
		(width 0.09)
		(layer "In4.Cu")
		(net 591)
	)
	(segment
		(start 183.51718 134.318647)
		(end 183.517182 134.318649)
		(width 0.09)
		(layer "In4.Cu")
		(net 591)
	)
	(segment
		(start 182.45 135.385833)
		(end 183.092917 134.742916)
		(width 0.09)
		(layer "In4.Cu")
		(net 591)
	)
	(segment
		(start 190.83 135.07)
		(end 190.83 134.77)
		(width 0.09)
		(layer "In4.Cu")
		(net 591)
	)
	(segment
		(start 194.099 132.75962)
		(end 192.23862 134.62)
		(width 0.09)
		(layer "In4.Cu")
		(net 591)
	)
	(segment
		(start 183.305048 134.742914)
		(end 183.305049 134.742913)
		(width 0.09)
		(layer "In4.Cu")
		(net 591)
	)
	(segment
		(start 191.58 134.87)
		(end 191.53 134.87)
		(width 0.09)
		(layer "In4.Cu")
		(net 591)
	)
	(segment
		(start 192.23862 134.62)
		(end 191.83 134.62)
		(width 0.09)
		(layer "In4.Cu")
		(net 591)
	)
	(segment
		(start 190.53 134.77)
		(end 190.53 135.54)
		(width 0.09)
		(layer "In4.Cu")
		(net 591)
	)
	(segment
		(start 183.517182 134.318649)
		(end 183.694333 134.1415)
		(width 0.09)
		(layer "In4.Cu")
		(net 591)
	)
	(segment
		(start 183.092917 134.742916)
		(end 183.092917 134.742913)
		(width 0.09)
		(layer "In4.Cu")
		(net 591)
	)
	(segment
		(start 183.623247 134.84898)
		(end 183.623246 134.848979)
		(width 0.09)
		(layer "In4.Cu")
		(net 591)
	)
	(segment
		(start 189.93 135.352058)
		(end 189.93 135.54)
		(width 0.09)
		(layer "In4.Cu")
		(net 591)
	)
	(segment
		(start 190.23 135.54)
		(end 190.23 135.352058)
		(width 0.09)
		(layer "In4.Cu")
		(net 591)
	)
	(segment
		(start 182.45 136.88)
		(end 182.45 136.78)
		(width 0.09)
		(layer "In4.Cu")
		(net 591)
	)
	(segment
		(start 191.13 134.77)
		(end 191.13 135.07)
		(width 0.09)
		(layer "In4.Cu")
		(net 591)
	)
	(segment
		(start 182.82 137.25)
		(end 182.45 136.88)
		(width 0.09)
		(layer "In4.Cu")
		(net 591)
	)
	(segment
		(start 194.099 132.3)
		(end 194.099 132.75962)
		(width 0.09)
		(layer "In4.Cu")
		(net 591)
	)
	(arc
		(start 190.83 134.77)
		(mid 190.786066 134.663934)
		(end 190.68 134.62)
		(width 0.09)
		(layer "In4.Cu")
		(net 591)
	)
	(arc
		(start 190.98 135.22)
		(mid 190.873934 135.176066)
		(end 190.83 135.07)
		(width 0.09)
		(layer "In4.Cu")
		(net 591)
	)
	(arc
		(start 191.28 134.62)
		(mid 191.173934 134.663934)
		(end 191.13 134.77)
		(width 0.09)
		(layer "In4.Cu")
		(net 591)
	)
	(arc
		(start 191.53 134.87)
		(mid 191.441612 134.833388)
		(end 191.405 134.745)
		(width 0.09)
		(layer "In4.Cu")
		(net 591)
	)
	(arc
		(start 190.53 135.54)
		(mid 190.486051 135.646081)
		(end 190.38 135.69)
		(width 0.09)
		(layer "In4.Cu")
		(net 591)
	)
	(arc
		(start 189.93 135.54)
		(mid 189.886066 135.646066)
		(end 189.78 135.69)
		(width 0.09)
		(layer "In4.Cu")
		(net 591)
	)
	(arc
		(start 190.68 134.62)
		(mid 190.573949 134.663919)
		(end 190.53 134.77)
		(width 0.09)
		(layer "In4.Cu")
		(net 591)
	)
	(arc
		(start 182.6 136.33)
		(mid 182.493934 136.286066)
		(end 182.45 136.18)
		(width 0.09)
		(layer "In4.Cu")
		(net 591)
	)
	(arc
		(start 182.6 136.63)
		(mid 182.706066 136.586066)
		(end 182.75 136.48)
		(width 0.09)
		(layer "In4.Cu")
		(net 591)
	)
	(arc
		(start 190.38 135.69)
		(mid 190.273934 135.646066)
		(end 190.23 135.54)
		(width 0.09)
		(layer "In4.Cu")
		(net 591)
	)
	(arc
		(start 183.092917 134.742913)
		(mid 183.198983 134.69898)
		(end 183.305048 134.742914)
		(width 0.09)
		(layer "In4.Cu")
		(net 591)
	)
	(arc
		(start 182.75 136.48)
		(mid 182.706066 136.373934)
		(end 182.6 136.33)
		(width 0.09)
		(layer "In4.Cu")
		(net 591)
	)
	(arc
		(start 190.23 135.352058)
		(mid 190.186066 135.245992)
		(end 190.08 135.202058)
		(width 0.09)
		(layer "In4.Cu")
		(net 591)
	)
	(arc
		(start 183.623246 134.848979)
		(mid 183.667181 134.742913)
		(end 183.623247 134.636846)
		(width 0.09)
		(layer "In4.Cu")
		(net 591)
	)
	(arc
		(start 191.13 135.07)
		(mid 191.086066 135.176066)
		(end 190.98 135.22)
		(width 0.09)
		(layer "In4.Cu")
		(net 591)
	)
	(arc
		(start 183.51718 134.530779)
		(mid 183.473246 134.424713)
		(end 183.51718 134.318647)
		(width 0.09)
		(layer "In4.Cu")
		(net 591)
	)
	(arc
		(start 191.705 134.745)
		(mid 191.668388 134.833388)
		(end 191.58 134.87)
		(width 0.09)
		(layer "In4.Cu")
		(net 591)
	)
	(arc
		(start 183.411114 134.848979)
		(mid 183.51718 134.892914)
		(end 183.623247 134.84898)
		(width 0.09)
		(layer "In4.Cu")
		(net 591)
	)
	(arc
		(start 182.45 136.78)
		(mid 182.493934 136.673934)
		(end 182.6 136.63)
		(width 0.09)
		(layer "In4.Cu")
		(net 591)
	)
	(arc
		(start 190.08 135.202058)
		(mid 189.973934 135.245992)
		(end 189.93 135.352058)
		(width 0.09)
		(layer "In4.Cu")
		(net 591)
	)
	(arc
		(start 191.83 134.62)
		(mid 191.741612 134.656612)
		(end 191.705 134.745)
		(width 0.09)
		(layer "In4.Cu")
		(net 591)
	)
	(arc
		(start 191.405 134.745)
		(mid 191.368388 134.656612)
		(end 191.28 134.62)
		(width 0.09)
		(layer "In4.Cu")
		(net 591)
	)
	(segment
		(start 182.004 131.216)
		(end 181.6045 130.8915)
		(width 0.174)
		(layer "F.Cu")
		(net 592)
	)
	(segment
		(start 182.004 127.967)
		(end 181.6045 128.2915)
		(width 0.174)
		(layer "F.Cu")
		(net 592)
	)
	(via
		(at 181.6045 128.2915)
		(size 0.35)
		(drill 0.15)
		(layers "F.Cu" "B.Cu")
		(remove_unused_layers yes)
		(keep_end_layers yes)
		(zone_layer_connections)
		(net 592)
	)
	(via
		(at 181.6045 130.8915)
		(size 0.35)
		(drill 0.15)
		(layers "F.Cu" "B.Cu")
		(remove_unused_layers yes)
		(keep_end_layers yes)
		(zone_layer_connections)
		(net 592)
	)
	(via
		(at 193.299 126.701)
		(size 0.35)
		(drill 0.15)
		(layers "F.Cu" "B.Cu")
		(remove_unused_layers yes)
		(keep_end_layers yes)
		(zone_layer_connections)
		(net 592)
	)
	(segment
		(start 181.038121 129.016231)
		(end 180.722615 129.016231)
		(width 0.09)
		(layer "In9.Cu")
		(net 592)
	)
	(segment
		(start 180.03 129.071787)
		(end 180.03 130.189861)
		(width 0.09)
		(layer "In9.Cu")
		(net 592)
	)
	(segment
		(start 180.742662 130.178)
		(end 181.049352 130.178)
		(width 0.09)
		(layer "In9.Cu")
		(net 592)
	)
	(segment
		(start 181.3 130.587001)
		(end 181.6045 130.8915)
		(width 0.09)
		(layer "In9.Cu")
		(net 592)
	)
	(segment
		(start 181.3 130.428649)
		(end 181.3 130.587001)
		(width 0.09)
		(layer "In9.Cu")
		(net 592)
	)
	(segment
		(start 180.522715 128.816331)
		(end 180.285456 128.816331)
		(width 0.09)
		(layer "In9.Cu")
		(net 592)
	)
	(segment
		(start 181.049352 130.178)
		(end 181.3 130.428649)
		(width 0.09)
		(layer "In9.Cu")
		(net 592)
	)
	(segment
		(start 180.225139 130.385)
		(end 180.535662 130.385)
		(width 0.09)
		(layer "In9.Cu")
		(net 592)
	)
	(segment
		(start 181.6045 128.2915)
		(end 181.300001 128.595999)
		(width 0.09)
		(layer "In9.Cu")
		(net 592)
	)
	(segment
		(start 181.300001 128.595999)
		(end 181.300001 128.754351)
		(width 0.09)
		(layer "In9.Cu")
		(net 592)
	)
	(segment
		(start 180.722615 129.016231)
		(end 180.522715 128.816331)
		(width 0.09)
		(layer "In9.Cu")
		(net 592)
	)
	(segment
		(start 180.03 130.189861)
		(end 180.225139 130.385)
		(width 0.09)
		(layer "In9.Cu")
		(net 592)
	)
	(segment
		(start 181.300001 128.754351)
		(end 181.038121 129.016231)
		(width 0.09)
		(layer "In9.Cu")
		(net 592)
	)
	(segment
		(start 180.535662 130.385)
		(end 180.742662 130.178)
		(width 0.09)
		(layer "In9.Cu")
		(net 592)
	)
	(segment
		(start 180.285456 128.816331)
		(end 180.03 129.071787)
		(width 0.09)
		(layer "In9.Cu")
		(net 592)
	)
	(segment
		(start 181.9245 126.473049)
		(end 181.737049 126.6605)
		(width 0.09)
		(layer "In11.Cu")
		(net 592)
	)
	(segment
		(start 191.84 126.935)
		(end 191.84 127.005)
		(width 0.09)
		(layer "In11.Cu")
		(net 592)
	)
	(segment
		(start 181.737049 126.6605)
		(end 181.328915 126.6605)
		(width 0.09)
		(layer "In11.Cu")
		(net 592)
	)
	(segment
		(start 193.779 126.568451)
		(end 193.966451 126.381)
		(width 0.09)
		(layer "In11.Cu")
		(net 592)
	)
	(segment
		(start 185.579931 125.946376)
		(end 186.036015 125.490291)
		(width 0.09)
		(layer "In11.Cu")
		(net 592)
	)
	(segment
		(start 184.805648 125.66)
		(end 184.872823 125.727174)
		(width 0.09)
		(layer "In11.Cu")
		(net 592)
	)
	(segment
		(start 182.329415 125.66)
		(end 181.9245 126.064915)
		(width 0.09)
		(layer "In11.Cu")
		(net 592)
	)
	(segment
		(start 193.485499 127.005499)
		(end 193.610744 127.005499)
		(width 0.09)
		(layer "In11.Cu")
		(net 592)
	)
	(segment
		(start 194.302274 126.313969)
		(end 194.302274 126.115718)
		(width 0.09)
		(layer "In11.Cu")
		(net 592)
	)
	(segment
		(start 187.815 127.145)
		(end 187.815 126.255)
		(width 0.09)
		(layer "In11.Cu")
		(net 592)
	)
	(segment
		(start 193.610744 127.005499)
		(end 193.780847 126.835396)
		(width 0.09)
		(layer "In11.Cu")
		(net 592)
	)
	(segment
		(start 181.2845 127.9715)
		(end 181.6045 128.2915)
		(width 0.09)
		(layer "In11.Cu")
		(net 592)
	)
	(segment
		(start 185.360729 125.727175)
		(end 185.360729 125.727176)
		(width 0.09)
		(layer "In11.Cu")
		(net 592)
	)
	(segment
		(start 180.938049 127.3105)
		(end 180.678915 127.3105)
		(width 0.09)
		(layer "In11.Cu")
		(net 592)
	)
	(segment
		(start 186.505 126.255)
		(end 186.505 126.45)
		(width 0.09)
		(layer "In11.Cu")
		(net 592)
	)
	(segment
		(start 194.231549 126.381)
		(end 194.233396 126.382847)
		(width 0.09)
		(layer "In11.Cu")
		(net 592)
	)
	(segment
		(start 194.302274 126.115718)
		(end 194.16786 125.981304)
		(width 0.09)
		(layer "In11.Cu")
		(net 592)
	)
	(segment
		(start 181.1255 127.123049)
		(end 180.938049 127.3105)
		(width 0.09)
		(layer "In11.Cu")
		(net 592)
	)
	(segment
		(start 181.328915 126.6605)
		(end 181.1255 126.863915)
		(width 0.09)
		(layer "In11.Cu")
		(net 592)
	)
	(segment
		(start 193.299 126.701)
		(end 193.299 126.819)
		(width 0.09)
		(layer "In11.Cu")
		(net 592)
	)
	(segment
		(start 191.032549 127.021)
		(end 189.166451 127.021)
		(width 0.09)
		(layer "In11.Cu")
		(net 592)
	)
	(segment
		(start 180.485951 127.503464)
		(end 180.485951 127.781599)
		(width 0.09)
		(layer "In11.Cu")
		(net 592)
	)
	(segment
		(start 186.036015 125.490291)
		(end 186.036015 125.490292)
		(width 0.09)
		(layer "In11.Cu")
		(net 592)
	)
	(segment
		(start 192.366451 127.021)
		(end 192.140451 126.795)
		(width 0.09)
		(layer "In11.Cu")
		(net 592)
	)
	(segment
		(start 187.505 126.255)
		(end 187.505 127.145)
		(width 0.09)
		(layer "In11.Cu")
		(net 592)
	)
	(segment
		(start 180.675852 127.9715)
		(end 181.2845 127.9715)
		(width 0.09)
		(layer "In11.Cu")
		(net 592)
	)
	(segment
		(start 181.9245 126.064915)
		(end 181.9245 126.473049)
		(width 0.09)
		(layer "In11.Cu")
		(net 592)
	)
	(segment
		(start 194.16786 125.981304)
		(end 193.403048 125.981304)
		(width 0.09)
		(layer "In11.Cu")
		(net 592)
	)
	(segment
		(start 180.678915 127.3105)
		(end 180.485951 127.503464)
		(width 0.09)
		(layer "In11.Cu")
		(net 592)
	)
	(segment
		(start 191.56 127.005)
		(end 191.56 126.935)
		(width 0.09)
		(layer "In11.Cu")
		(net 592)
	)
	(segment
		(start 193.966451 126.381)
		(end 194.231549 126.381)
		(width 0.09)
		(layer "In11.Cu")
		(net 592)
	)
	(segment
		(start 193.779 126.833549)
		(end 193.779 126.568451)
		(width 0.09)
		(layer "In11.Cu")
		(net 592)
	)
	(segment
		(start 193.299 126.819)
		(end 193.485499 127.005499)
		(width 0.09)
		(layer "In11.Cu")
		(net 592)
	)
	(segment
		(start 188.505 126.95)
		(end 188.505 127.145)
		(width 0.09)
		(layer "In11.Cu")
		(net 592)
	)
	(segment
		(start 193.780847 126.835396)
		(end 193.779 126.833549)
		(width 0.09)
		(layer "In11.Cu")
		(net 592)
	)
	(segment
		(start 185.940648 126.795)
		(end 185.57993 126.434281)
		(width 0.09)
		(layer "In11.Cu")
		(net 592)
	)
	(segment
		(start 185.816814 125.271091)
		(end 185.360729 125.727175)
		(width 0.09)
		(layer "In11.Cu")
		(net 592)
	)
	(segment
		(start 194.233396 126.382847)
		(end 194.302274 126.313969)
		(width 0.09)
		(layer "In11.Cu")
		(net 592)
	)
	(segment
		(start 180.485951 127.781599)
		(end 180.675852 127.9715)
		(width 0.09)
		(layer "In11.Cu")
		(net 592)
	)
	(segment
		(start 192.140451 126.795)
		(end 191.98 126.795)
		(width 0.09)
		(layer "In11.Cu")
		(net 592)
	)
	(segment
		(start 186.16 126.795)
		(end 185.940648 126.795)
		(width 0.09)
		(layer "In11.Cu")
		(net 592)
	)
	(segment
		(start 186.815 127.145)
		(end 186.815 126.255)
		(width 0.09)
		(layer "In11.Cu")
		(net 592)
	)
	(segment
		(start 189.166451 127.021)
		(end 188.940451 126.795)
		(width 0.09)
		(layer "In11.Cu")
		(net 592)
	)
	(segment
		(start 192.819 126.568451)
		(end 192.819 126.833549)
		(width 0.09)
		(layer "In11.Cu")
		(net 592)
	)
	(segment
		(start 193.403048 125.981304)
		(end 192.81745 126.566902)
		(width 0.09)
		(layer "In11.Cu")
		(net 592)
	)
	(segment
		(start 192.81745 126.566902)
		(end 192.819 126.568451)
		(width 0.09)
		(layer "In11.Cu")
		(net 592)
	)
	(segment
		(start 191.258549 126.795)
		(end 191.032549 127.021)
		(width 0.09)
		(layer "In11.Cu")
		(net 592)
	)
	(segment
		(start 191.42 126.795)
		(end 191.258549 126.795)
		(width 0.09)
		(layer "In11.Cu")
		(net 592)
	)
	(segment
		(start 192.631549 127.021)
		(end 192.366451 127.021)
		(width 0.09)
		(layer "In11.Cu")
		(net 592)
	)
	(segment
		(start 188.940451 126.795)
		(end 188.66 126.795)
		(width 0.09)
		(layer "In11.Cu")
		(net 592)
	)
	(segment
		(start 184.805648 125.66)
		(end 182.329415 125.66)
		(width 0.09)
		(layer "In11.Cu")
		(net 592)
	)
	(segment
		(start 192.819 126.833549)
		(end 192.631549 127.021)
		(width 0.09)
		(layer "In11.Cu")
		(net 592)
	)
	(segment
		(start 181.1255 126.863915)
		(end 181.1255 127.123049)
		(width 0.09)
		(layer "In11.Cu")
		(net 592)
	)
	(arc
		(start 186.036015 125.490292)
		(mid 186.081413 125.380691)
		(end 186.036016 125.271091)
		(width 0.09)
		(layer "In11.Cu")
		(net 592)
	)
	(arc
		(start 191.84 127.005)
		(mid 191.798995 127.103995)
		(end 191.7 127.145)
		(width 0.09)
		(layer "In11.Cu")
		(net 592)
	)
	(arc
		(start 186.036016 125.271091)
		(mid 185.926414 125.225692)
		(end 185.816814 125.271091)
		(width 0.09)
		(layer "In11.Cu")
		(net 592)
	)
	(arc
		(start 191.7 127.145)
		(mid 191.601005 127.103995)
		(end 191.56 127.005)
		(width 0.09)
		(layer "In11.Cu")
		(net 592)
	)
	(arc
		(start 186.505 126.45)
		(mid 186.403952 126.693952)
		(end 186.16 126.795)
		(width 0.09)
		(layer "In11.Cu")
		(net 592)
	)
	(arc
		(start 187.66 126.1)
		(mid 187.550398 126.145398)
		(end 187.505 126.255)
		(width 0.09)
		(layer "In11.Cu")
		(net 592)
	)
	(arc
		(start 186.815 126.255)
		(mid 186.769602 126.145398)
		(end 186.66 126.1)
		(width 0.09)
		(layer "In11.Cu")
		(net 592)
	)
	(arc
		(start 188.66 126.795)
		(mid 188.550398 126.840398)
		(end 188.505 126.95)
		(width 0.09)
		(layer "In11.Cu")
		(net 592)
	)
	(arc
		(start 191.98 126.795)
		(mid 191.881005 126.836005)
		(end 191.84 126.935)
		(width 0.09)
		(layer "In11.Cu")
		(net 592)
	)
	(arc
		(start 187.505 127.145)
		(mid 187.403952 127.388952)
		(end 187.16 127.49)
		(width 0.09)
		(layer "In11.Cu")
		(net 592)
	)
	(arc
		(start 185.57993 126.434281)
		(mid 185.478881 126.190327)
		(end 185.579931 125.946376)
		(width 0.09)
		(layer "In11.Cu")
		(net 592)
	)
	(arc
		(start 191.56 126.935)
		(mid 191.518995 126.836005)
		(end 191.42 126.795)
		(width 0.09)
		(layer "In11.Cu")
		(net 592)
	)
	(arc
		(start 188.505 127.145)
		(mid 188.403952 127.388952)
		(end 188.16 127.49)
		(width 0.09)
		(layer "In11.Cu")
		(net 592)
	)
	(arc
		(start 187.815 126.255)
		(mid 187.769602 126.145398)
		(end 187.66 126.1)
		(width 0.09)
		(layer "In11.Cu")
		(net 592)
	)
	(arc
		(start 187.16 127.49)
		(mid 186.916048 127.388952)
		(end 186.815 127.145)
		(width 0.09)
		(layer "In11.Cu")
		(net 592)
	)
	(arc
		(start 188.16 127.49)
		(mid 187.916048 127.388952)
		(end 187.815 127.145)
		(width 0.09)
		(layer "In11.Cu")
		(net 592)
	)
	(arc
		(start 185.360729 125.727176)
		(mid 185.116777 125.828224)
		(end 184.872823 125.727174)
		(width 0.09)
		(layer "In11.Cu")
		(net 592)
	)
	(arc
		(start 186.66 126.1)
		(mid 186.550398 126.145398)
		(end 186.505 126.255)
		(width 0.09)
		(layer "In11.Cu")
		(net 592)
	)
	(segment
		(start 181.205 131.216)
		(end 180.8055 130.8915)
		(width 0.174)
		(layer "F.Cu")
		(net 593)
	)
	(segment
		(start 181.205 127.967)
		(end 180.8055 128.2915)
		(width 0.174)
		(layer "F.Cu")
		(net 593)
	)
	(via
		(at 193.299 127.5)
		(size 0.35)
		(drill 0.15)
		(layers "F.Cu" "B.Cu")
		(remove_unused_layers yes)
		(keep_end_layers yes)
		(zone_layer_connections)
		(net 593)
	)
	(via
		(at 180.8055 130.8915)
		(size 0.35)
		(drill 0.15)
		(layers "F.Cu" "B.Cu")
		(remove_unused_layers yes)
		(keep_end_layers yes)
		(zone_layer_connections)
		(net 593)
	)
	(via
		(at 180.8055 128.2915)
		(size 0.35)
		(drill 0.15)
		(layers "F.Cu" "B.Cu")
		(remove_unused_layers yes)
		(keep_end_layers yes)
		(zone_layer_connections)
		(net 593)
	)
	(segment
		(start 179.84 130.268565)
		(end 180.146435 130.575)
		(width 0.09)
		(layer "In9.Cu")
		(net 593)
	)
	(segment
		(start 181.109999 128.675649)
		(end 180.959417 128.826231)
		(width 0.09)
		(layer "In9.Cu")
		(net 593)
	)
	(segment
		(start 180.970648 130.368)
		(end 181.109999 130.507351)
		(width 0.09)
		(layer "In9.Cu")
		(net 593)
	)
	(segment
		(start 180.614366 130.575)
		(end 180.821366 130.368)
		(width 0.09)
		(layer "In9.Cu")
		(net 593)
	)
	(segment
		(start 180.8055 128.2915)
		(end 181.109999 128.595999)
		(width 0.09)
		(layer "In9.Cu")
		(net 593)
	)
	(segment
		(start 180.146435 130.575)
		(end 180.614366 130.575)
		(width 0.09)
		(layer "In9.Cu")
		(net 593)
	)
	(segment
		(start 179.84 128.993083)
		(end 179.84 130.268565)
		(width 0.09)
		(layer "In9.Cu")
		(net 593)
	)
	(segment
		(start 180.801319 128.826231)
		(end 180.601419 128.626331)
		(width 0.09)
		(layer "In9.Cu")
		(net 593)
	)
	(segment
		(start 180.821366 130.368)
		(end 180.970648 130.368)
		(width 0.09)
		(layer "In9.Cu")
		(net 593)
	)
	(segment
		(start 180.959417 128.826231)
		(end 180.801319 128.826231)
		(width 0.09)
		(layer "In9.Cu")
		(net 593)
	)
	(segment
		(start 181.109999 130.507351)
		(end 181.109999 130.587001)
		(width 0.09)
		(layer "In9.Cu")
		(net 593)
	)
	(segment
		(start 180.601419 128.626331)
		(end 180.206752 128.626331)
		(width 0.09)
		(layer "In9.Cu")
		(net 593)
	)
	(segment
		(start 180.206752 128.626331)
		(end 179.84 128.993083)
		(width 0.09)
		(layer "In9.Cu")
		(net 593)
	)
	(segment
		(start 181.109999 128.595999)
		(end 181.109999 128.675649)
		(width 0.09)
		(layer "In9.Cu")
		(net 593)
	)
	(segment
		(start 181.109999 130.587001)
		(end 180.8055 130.8915)
		(width 0.09)
		(layer "In9.Cu")
		(net 593)
	)
	(segment
		(start 193.299 127.5)
		(end 193.603499 127.195501)
		(width 0.09)
		(layer "In11.Cu")
		(net 593)
	)
	(segment
		(start 192.366451 126.381)
		(end 192.142451 126.605)
		(width 0.09)
		(layer "In11.Cu")
		(net 593)
	)
	(segment
		(start 188.942451 126.605)
		(end 188.66 126.605)
		(width 0.09)
		(layer "In11.Cu")
		(net 593)
	)
	(segment
		(start 186.170366 125.624644)
		(end 186.170366 125.624645)
		(width 0.09)
		(layer "In11.Cu")
		(net 593)
	)
	(segment
		(start 191.256549 126.605)
		(end 191.032549 126.381)
		(width 0.09)
		(layer "In11.Cu")
		(net 593)
	)
	(segment
		(start 184.884352 125.47)
		(end 182.250711 125.47)
		(width 0.09)
		(layer "In11.Cu")
		(net 593)
	)
	(segment
		(start 185.714282 126.080729)
		(end 186.170366 125.624644)
		(width 0.09)
		(layer "In11.Cu")
		(net 593)
	)
	(segment
		(start 194.231549 127.021)
		(end 194.419 126.833549)
		(width 0.09)
		(layer "In11.Cu")
		(net 593)
	)
	(segment
		(start 193.863947 127.021)
		(end 194.231549 127.021)
		(width 0.09)
		(layer "In11.Cu")
		(net 593)
	)
	(segment
		(start 192.734648 126.381)
		(end 192.366451 126.381)
		(width 0.09)
		(layer "In11.Cu")
		(net 593)
	)
	(segment
		(start 186.019352 126.605)
		(end 185.714282 126.299931)
		(width 0.09)
		(layer "In11.Cu")
		(net 593)
	)
	(segment
		(start 180.295951 127.42476)
		(end 180.295951 127.860303)
		(width 0.09)
		(layer "In11.Cu")
		(net 593)
	)
	(segment
		(start 189.166451 126.381)
		(end 188.942451 126.605)
		(width 0.09)
		(layer "In11.Cu")
		(net 593)
	)
	(segment
		(start 194.246564 125.791304)
		(end 193.324344 125.791304)
		(width 0.09)
		(layer "In11.Cu")
		(net 593)
	)
	(segment
		(start 181.2845 126.207951)
		(end 181.2845 126.436211)
		(width 0.09)
		(layer "In11.Cu")
		(net 593)
	)
	(segment
		(start 194.419 126.833549)
		(end 194.419 126.465947)
		(width 0.09)
		(layer "In11.Cu")
		(net 593)
	)
	(segment
		(start 185.682461 125.136739)
		(end 185.226378 125.592825)
		(width 0.09)
		(layer "In11.Cu")
		(net 593)
	)
	(segment
		(start 184.884352 125.47)
		(end 185.007174 125.592823)
		(width 0.09)
		(layer "In11.Cu")
		(net 593)
	)
	(segment
		(start 180.295951 127.860303)
		(end 180.727148 128.2915)
		(width 0.09)
		(layer "In11.Cu")
		(net 593)
	)
	(segment
		(start 180.4855 126.857951)
		(end 180.4855 127.235211)
		(width 0.09)
		(layer "In11.Cu")
		(net 593)
	)
	(segment
		(start 188.005 127.145)
		(end 188.005 126.255)
		(width 0.09)
		(layer "In11.Cu")
		(net 593)
	)
	(segment
		(start 193.689446 127.195501)
		(end 193.863947 127.021)
		(width 0.09)
		(layer "In11.Cu")
		(net 593)
	)
	(segment
		(start 194.492274 126.037014)
		(end 194.246564 125.791304)
		(width 0.09)
		(layer "In11.Cu")
		(net 593)
	)
	(segment
		(start 180.4855 127.235211)
		(end 180.295951 127.42476)
		(width 0.09)
		(layer "In11.Cu")
		(net 593)
	)
	(segment
		(start 180.672951 126.6705)
		(end 180.4855 126.857951)
		(width 0.09)
		(layer "In11.Cu")
		(net 593)
	)
	(segment
		(start 194.492274 126.392673)
		(end 194.492274 126.037014)
		(width 0.09)
		(layer "In11.Cu")
		(net 593)
	)
	(segment
		(start 181.2845 126.436211)
		(end 181.050211 126.6705)
		(width 0.09)
		(layer "In11.Cu")
		(net 593)
	)
	(segment
		(start 191.032549 126.381)
		(end 189.166451 126.381)
		(width 0.09)
		(layer "In11.Cu")
		(net 593)
	)
	(segment
		(start 193.324344 125.791304)
		(end 192.734648 126.381)
		(width 0.09)
		(layer "In11.Cu")
		(net 593)
	)
	(segment
		(start 181.700211 126.0205)
		(end 181.471951 126.0205)
		(width 0.09)
		(layer "In11.Cu")
		(net 593)
	)
	(segment
		(start 181.471951 126.0205)
		(end 181.2845 126.207951)
		(width 0.09)
		(layer "In11.Cu")
		(net 593)
	)
	(segment
		(start 186.315 126.255)
		(end 186.315 126.45)
		(width 0.09)
		(layer "In11.Cu")
		(net 593)
	)
	(segment
		(start 186.16 126.605)
		(end 186.019352 126.605)
		(width 0.09)
		(layer "In11.Cu")
		(net 593)
	)
	(segment
		(start 187.005 127.145)
		(end 187.005 126.255)
		(width 0.09)
		(layer "In11.Cu")
		(net 593)
	)
	(segment
		(start 192.142451 126.605)
		(end 191.256549 126.605)
		(width 0.09)
		(layer "In11.Cu")
		(net 593)
	)
	(segment
		(start 194.419 126.465947)
		(end 194.492274 126.392673)
		(width 0.09)
		(layer "In11.Cu")
		(net 593)
	)
	(segment
		(start 180.727148 128.2915)
		(end 180.8055 128.2915)
		(width 0.09)
		(layer "In11.Cu")
		(net 593)
	)
	(segment
		(start 182.250711 125.47)
		(end 181.700211 126.0205)
		(width 0.09)
		(layer "In11.Cu")
		(net 593)
	)
	(segment
		(start 188.315 126.95)
		(end 188.315 127.145)
		(width 0.09)
		(layer "In11.Cu")
		(net 593)
	)
	(segment
		(start 187.315 126.255)
		(end 187.315 127.145)
		(width 0.09)
		(layer "In11.Cu")
		(net 593)
	)
	(segment
		(start 181.050211 126.6705)
		(end 180.672951 126.6705)
		(width 0.09)
		(layer "In11.Cu")
		(net 593)
	)
	(segment
		(start 186.170367 125.13674)
		(end 186.170366 125.136738)
		(width 0.09)
		(layer "In11.Cu")
		(net 593)
	)
	(segment
		(start 193.603499 127.195501)
		(end 193.689446 127.195501)
		(width 0.09)
		(layer "In11.Cu")
		(net 593)
	)
	(arc
		(start 185.714282 126.299931)
		(mid 185.668883 126.190329)
		(end 185.714282 126.080729)
		(width 0.09)
		(layer "In11.Cu")
		(net 593)
	)
	(arc
		(start 188.315 127.145)
		(mid 188.269602 127.254602)
		(end 188.16 127.3)
		(width 0.09)
		(layer "In11.Cu")
		(net 593)
	)
	(arc
		(start 187.005 126.255)
		(mid 186.903952 126.011048)
		(end 186.66 125.91)
		(width 0.09)
		(layer "In11.Cu")
		(net 593)
	)
	(arc
		(start 187.315 127.145)
		(mid 187.269602 127.254602)
		(end 187.16 127.3)
		(width 0.09)
		(layer "In11.Cu")
		(net 593)
	)
	(arc
		(start 188.005 126.255)
		(mid 187.903952 126.011048)
		(end 187.66 125.91)
		(width 0.09)
		(layer "In11.Cu")
		(net 593)
	)
	(arc
		(start 185.226378 125.592825)
		(mid 185.116776 125.638222)
		(end 185.007174 125.592823)
		(width 0.09)
		(layer "In11.Cu")
		(net 593)
	)
	(arc
		(start 188.16 127.3)
		(mid 188.050398 127.254602)
		(end 188.005 127.145)
		(width 0.09)
		(layer "In11.Cu")
		(net 593)
	)
	(arc
		(start 186.315 126.45)
		(mid 186.269602 126.559602)
		(end 186.16 126.605)
		(width 0.09)
		(layer "In11.Cu")
		(net 593)
	)
	(arc
		(start 187.16 127.3)
		(mid 187.050398 127.254602)
		(end 187.005 127.145)
		(width 0.09)
		(layer "In11.Cu")
		(net 593)
	)
	(arc
		(start 187.66 125.91)
		(mid 187.416048 126.011048)
		(end 187.315 126.255)
		(width 0.09)
		(layer "In11.Cu")
		(net 593)
	)
	(arc
		(start 186.66 125.91)
		(mid 186.416048 126.011048)
		(end 186.315 126.255)
		(width 0.09)
		(layer "In11.Cu")
		(net 593)
	)
	(arc
		(start 188.66 126.605)
		(mid 188.416048 126.706048)
		(end 188.315 126.95)
		(width 0.09)
		(layer "In11.Cu")
		(net 593)
	)
	(arc
		(start 186.170366 125.136738)
		(mid 185.926414 125.035691)
		(end 185.682461 125.136739)
		(width 0.09)
		(layer "In11.Cu")
		(net 593)
	)
	(arc
		(start 186.170366 125.624645)
		(mid 186.271414 125.380692)
		(end 186.170367 125.13674)
		(width 0.09)
		(layer "In11.Cu")
		(net 593)
	)
	(segment
		(start 183.604 135.766)
		(end 184.0035 136.0905)
		(width 0.174)
		(layer "F.Cu")
		(net 594)
	)
	(via
		(at 184.0035 136.0905)
		(size 0.35)
		(drill 0.15)
		(layers "F.Cu" "B.Cu")
		(remove_unused_layers yes)
		(keep_end_layers yes)
		(zone_layer_connections)
		(net 594)
	)
	(via
		(at 193.299 129.901)
		(size 0.35)
		(drill 0.15)
		(layers "F.Cu" "B.Cu")
		(remove_unused_layers yes)
		(keep_end_layers yes)
		(zone_layer_connections)
		(net 594)
	)
	(segment
		(start 192.08 133.67)
		(end 192.08 134.13)
		(width 0.09)
		(layer "In4.Cu")
		(net 594)
	)
	(segment
		(start 192.08 134.13)
		(end 191.87 134.34)
		(width 0.09)
		(layer "In4.Cu")
		(net 594)
	)
	(segment
		(start 194.5 131.55962)
		(end 194.23362 131.826)
		(width 0.09)
		(layer "In4.Cu")
		(net 594)
	)
	(segment
		(start 191.02 134.19)
		(end 191.02 134.164544)
		(width 0.09)
		(layer "In4.Cu")
		(net 594)
	)
	(segment
		(start 183.6 135.3)
		(end 183.6 135.687)
		(width 0.09)
		(layer "In4.Cu")
		(net 594)
	)
	(segment
		(start 187.23 136.94)
		(end 183.89 136.94)
		(width 0.09)
		(layer "In4.Cu")
		(net 594)
	)
	(segment
		(start 191.62 134.19)
		(end 191.62 134.164544)
		(width 0.09)
		(layer "In4.Cu")
		(net 594)
	)
	(segment
		(start 194.23362 129.576)
		(end 194.5 129.84238)
		(width 0.09)
		(layer "In4.Cu")
		(net 594)
	)
	(segment
		(start 193.774 132.676)
		(end 192.95 133.5)
		(width 0.09)
		(layer "In4.Cu")
		(net 594)
	)
	(segment
		(start 183.89 136.94)
		(end 183.3665 136.4165)
		(width 0.09)
		(layer "In4.Cu")
		(net 594)
	)
	(segment
		(start 194.5 129.84238)
		(end 194.5 131.55962)
		(width 0.09)
		(layer "In4.Cu")
		(net 594)
	)
	(segment
		(start 194.074 131.826)
		(end 193.774 132.126)
		(width 0.09)
		(layer "In4.Cu")
		(net 594)
	)
	(segment
		(start 193.774 132.126)
		(end 193.774 132.676)
		(width 0.09)
		(layer "In4.Cu")
		(net 594)
	)
	(segment
		(start 183.06988 136.4165)
		(end 182.8 136.14662)
		(width 0.09)
		(layer "In4.Cu")
		(net 594)
	)
	(segment
		(start 183.3665 136.4165)
		(end 183.06988 136.4165)
		(width 0.09)
		(layer "In4.Cu")
		(net 594)
	)
	(segment
		(start 193.624 129.576)
		(end 194.23362 129.576)
		(width 0.09)
		(layer "In4.Cu")
		(net 594)
	)
	(segment
		(start 189.41 135.46)
		(end 188.71 135.46)
		(width 0.09)
		(layer "In4.Cu")
		(net 594)
	)
	(segment
		(start 189.65 134.46)
		(end 189.65 135.22)
		(width 0.09)
		(layer "In4.Cu")
		(net 594)
	)
	(segment
		(start 188.71 135.46)
		(end 187.23 136.94)
		(width 0.09)
		(layer "In4.Cu")
		(net 594)
	)
	(segment
		(start 194.23362 131.826)
		(end 194.074 131.826)
		(width 0.09)
		(layer "In4.Cu")
		(net 594)
	)
	(segment
		(start 182.8 135.3)
		(end 182.9835 135.1165)
		(width 0.09)
		(layer "In4.Cu")
		(net 594)
	)
	(segment
		(start 189.77 134.34)
		(end 189.65 134.46)
		(width 0.09)
		(layer "In4.Cu")
		(net 594)
	)
	(segment
		(start 191.87 134.34)
		(end 191.77 134.34)
		(width 0.09)
		(layer "In4.Cu")
		(net 594)
	)
	(segment
		(start 189.97 134.34)
		(end 189.77 134.34)
		(width 0.09)
		(layer "In4.Cu")
		(net 594)
	)
	(segment
		(start 193.299 129.901)
		(end 193.624 129.576)
		(width 0.09)
		(layer "In4.Cu")
		(net 594)
	)
	(segment
		(start 192.95 133.5)
		(end 192.25 133.5)
		(width 0.09)
		(layer "In4.Cu")
		(net 594)
	)
	(segment
		(start 182.8 136.14662)
		(end 182.8 135.3)
		(width 0.09)
		(layer "In4.Cu")
		(net 594)
	)
	(segment
		(start 190.42 134.19)
		(end 190.42 134.164526)
		(width 0.09)
		(layer "In4.Cu")
		(net 594)
	)
	(segment
		(start 183.4165 135.1165)
		(end 183.6 135.3)
		(width 0.09)
		(layer "In4.Cu")
		(net 594)
	)
	(segment
		(start 192.25 133.5)
		(end 192.08 133.67)
		(width 0.09)
		(layer "In4.Cu")
		(net 594)
	)
	(segment
		(start 191.32 134.164544)
		(end 191.32 134.19)
		(width 0.09)
		(layer "In4.Cu")
		(net 594)
	)
	(segment
		(start 190.12 134.164526)
		(end 190.12 134.19)
		(width 0.09)
		(layer "In4.Cu")
		(net 594)
	)
	(segment
		(start 183.6 135.687)
		(end 184.0035 136.0905)
		(width 0.09)
		(layer "In4.Cu")
		(net 594)
	)
	(segment
		(start 189.65 135.22)
		(end 189.41 135.46)
		(width 0.09)
		(layer "In4.Cu")
		(net 594)
	)
	(segment
		(start 190.72 134.164544)
		(end 190.72 134.19)
		(width 0.09)
		(layer "In4.Cu")
		(net 594)
	)
	(segment
		(start 182.9835 135.1165)
		(end 183.4165 135.1165)
		(width 0.09)
		(layer "In4.Cu")
		(net 594)
	)
	(arc
		(start 190.27 134.014526)
		(mid 190.163934 134.05846)
		(end 190.12 134.164526)
		(width 0.09)
		(layer "In4.Cu")
		(net 594)
	)
	(arc
		(start 191.62 134.164544)
		(mid 191.576066 134.058478)
		(end 191.47 134.014544)
		(width 0.09)
		(layer "In4.Cu")
		(net 594)
	)
	(arc
		(start 190.87 134.014544)
		(mid 190.763934 134.058478)
		(end 190.72 134.164544)
		(width 0.09)
		(layer "In4.Cu")
		(net 594)
	)
	(arc
		(start 191.17 134.34)
		(mid 191.063934 134.296066)
		(end 191.02 134.19)
		(width 0.09)
		(layer "In4.Cu")
		(net 594)
	)
	(arc
		(start 191.47 134.014544)
		(mid 191.363934 134.058478)
		(end 191.32 134.164544)
		(width 0.09)
		(layer "In4.Cu")
		(net 594)
	)
	(arc
		(start 191.32 134.19)
		(mid 191.276066 134.296066)
		(end 191.17 134.34)
		(width 0.09)
		(layer "In4.Cu")
		(net 594)
	)
	(arc
		(start 190.72 134.19)
		(mid 190.676066 134.296066)
		(end 190.57 134.34)
		(width 0.09)
		(layer "In4.Cu")
		(net 594)
	)
	(arc
		(start 191.02 134.164544)
		(mid 190.976066 134.058478)
		(end 190.87 134.014544)
		(width 0.09)
		(layer "In4.Cu")
		(net 594)
	)
	(arc
		(start 190.12 134.19)
		(mid 190.076066 134.296066)
		(end 189.97 134.34)
		(width 0.09)
		(layer "In4.Cu")
		(net 594)
	)
	(arc
		(start 190.42 134.164526)
		(mid 190.376066 134.05846)
		(end 190.27 134.014526)
		(width 0.09)
		(layer "In4.Cu")
		(net 594)
	)
	(arc
		(start 190.57 134.34)
		(mid 190.463934 134.296066)
		(end 190.42 134.19)
		(width 0.09)
		(layer "In4.Cu")
		(net 594)
	)
	(arc
		(start 191.77 134.34)
		(mid 191.663934 134.296066)
		(end 191.62 134.19)
		(width 0.09)
		(layer "In4.Cu")
		(net 594)
	)
	(segment
		(start 182.805 134.466)
		(end 182.4055 134.7905)
		(width 0.174)
		(layer "F.Cu")
		(net 595)
	)
	(via
		(at 182.4055 134.7905)
		(size 0.35)
		(drill 0.15)
		(layers "F.Cu" "B.Cu")
		(remove_unused_layers yes)
		(keep_end_layers yes)
		(zone_layer_connections)
		(net 595)
	)
	(via
		(at 193.299 130.701)
		(size 0.35)
		(drill 0.15)
		(layers "F.Cu" "B.Cu")
		(remove_unused_layers yes)
		(keep_end_layers yes)
		(zone_layer_connections)
		(net 595)
	)
	(segment
		(start 187.16 132.38)
		(end 187.16 133.698695)
		(width 0.09)
		(layer "In4.Cu")
		(net 595)
	)
	(segment
		(start 183.869706 133.55)
		(end 185.019706 133.55)
		(width 0.09)
		(layer "In4.Cu")
		(net 595)
	)
	(segment
		(start 185.539706 132.2)
		(end 185.78 132.2)
		(width 0.09)
		(layer "In4.Cu")
		(net 595)
	)
	(segment
		(start 188.44 132.319706)
		(end 188.44 132.809706)
		(width 0.09)
		(layer "In4.Cu")
		(net 595)
	)
	(segment
		(start 191.832549 132.62)
		(end 192.02 132.432549)
		(width 0.09)
		(layer "In4.Cu")
		(net 595)
	)
	(segment
		(start 188.790294 133.16)
		(end 190.139706 133.16)
		(width 0.09)
		(layer "In4.Cu")
		(net 595)
	)
	(segment
		(start 193.019 131.114166)
		(end 193.019 130.981)
		(width 0.09)
		(layer "In4.Cu")
		(net 595)
	)
	(segment
		(start 185.4 133.169706)
		(end 185.4 132.339706)
		(width 0.09)
		(layer "In4.Cu")
		(net 595)
	)
	(segment
		(start 182.61 134.586)
		(end 182.833706 134.586)
		(width 0.09)
		(layer "In4.Cu")
		(net 595)
	)
	(segment
		(start 186.8 133.698671)
		(end 186.8 132.38)
		(width 0.09)
		(layer "In4.Cu")
		(net 595)
	)
	(segment
		(start 185.96 132.38)
		(end 185.96 133.698671)
		(width 0.09)
		(layer "In4.Cu")
		(net 595)
	)
	(segment
		(start 185.019706 133.55)
		(end 185.4 133.169706)
		(width 0.09)
		(layer "In4.Cu")
		(net 595)
	)
	(segment
		(start 193.019 130.981)
		(end 193.299 130.701)
		(width 0.09)
		(layer "In4.Cu")
		(net 595)
	)
	(segment
		(start 192.263166 131.87)
		(end 192.632549 131.87)
		(width 0.09)
		(layer "In4.Cu")
		(net 595)
	)
	(segment
		(start 192.632549 131.87)
		(end 192.82 131.682549)
		(width 0.09)
		(layer "In4.Cu")
		(net 595)
	)
	(segment
		(start 182.833706 134.586)
		(end 183.869706 133.55)
		(width 0.09)
		(layer "In4.Cu")
		(net 595)
	)
	(segment
		(start 190.499706 132.8)
		(end 191.25 132.8)
		(width 0.09)
		(layer "In4.Cu")
		(net 595)
	)
	(segment
		(start 192.82 131.682549)
		(end 192.82 131.313166)
		(width 0.09)
		(layer "In4.Cu")
		(net 595)
	)
	(segment
		(start 185.4 132.339706)
		(end 185.539706 132.2)
		(width 0.09)
		(layer "In4.Cu")
		(net 595)
	)
	(segment
		(start 190.139706 133.16)
		(end 190.499706 132.8)
		(width 0.09)
		(layer "In4.Cu")
		(net 595)
	)
	(segment
		(start 191.25 132.8)
		(end 191.43 132.62)
		(width 0.09)
		(layer "In4.Cu")
		(net 595)
	)
	(segment
		(start 192.82 131.313166)
		(end 193.019 131.114166)
		(width 0.09)
		(layer "In4.Cu")
		(net 595)
	)
	(segment
		(start 188 133.698695)
		(end 188 132.38)
		(width 0.09)
		(layer "In4.Cu")
		(net 595)
	)
	(segment
		(start 188.18 132.2)
		(end 188.320294 132.2)
		(width 0.09)
		(layer "In4.Cu")
		(net 595)
	)
	(segment
		(start 188.44 132.809706)
		(end 188.790294 133.16)
		(width 0.09)
		(layer "In4.Cu")
		(net 595)
	)
	(segment
		(start 192.02 132.432549)
		(end 192.02 132.113166)
		(width 0.09)
		(layer "In4.Cu")
		(net 595)
	)
	(segment
		(start 191.43 132.62)
		(end 191.832549 132.62)
		(width 0.09)
		(layer "In4.Cu")
		(net 595)
	)
	(segment
		(start 188.320294 132.2)
		(end 188.44 132.319706)
		(width 0.09)
		(layer "In4.Cu")
		(net 595)
	)
	(segment
		(start 192.02 132.113166)
		(end 192.263166 131.87)
		(width 0.09)
		(layer "In4.Cu")
		(net 595)
	)
	(segment
		(start 182.4055 134.7905)
		(end 182.61 134.586)
		(width 0.09)
		(layer "In4.Cu")
		(net 595)
	)
	(arc
		(start 186.8 132.38)
		(mid 186.852721 132.252721)
		(end 186.98 132.2)
		(width 0.09)
		(layer "In4.Cu")
		(net 595)
	)
	(arc
		(start 187.58 134.118695)
		(mid 187.876985 133.99568)
		(end 188 133.698695)
		(width 0.09)
		(layer "In4.Cu")
		(net 595)
	)
	(arc
		(start 188 132.38)
		(mid 188.052721 132.252721)
		(end 188.18 132.2)
		(width 0.09)
		(layer "In4.Cu")
		(net 595)
	)
	(arc
		(start 185.96 133.698671)
		(mid 186.083015 133.995656)
		(end 186.38 134.118671)
		(width 0.09)
		(layer "In4.Cu")
		(net 595)
	)
	(arc
		(start 185.78 132.2)
		(mid 185.907279 132.252721)
		(end 185.96 132.38)
		(width 0.09)
		(layer "In4.Cu")
		(net 595)
	)
	(arc
		(start 186.98 132.2)
		(mid 187.107279 132.252721)
		(end 187.16 132.38)
		(width 0.09)
		(layer "In4.Cu")
		(net 595)
	)
	(arc
		(start 186.38 134.118671)
		(mid 186.676985 133.995656)
		(end 186.8 133.698671)
		(width 0.09)
		(layer "In4.Cu")
		(net 595)
	)
	(arc
		(start 187.16 133.698695)
		(mid 187.283015 133.99568)
		(end 187.58 134.118695)
		(width 0.09)
		(layer "In4.Cu")
		(net 595)
	)
	(segment
		(start 183.604 133.167)
		(end 184.0035 132.8425)
		(width 0.174)
		(layer "F.Cu")
		(net 596)
	)
	(via
		(at 184.0035 132.8425)
		(size 0.35)
		(drill 0.15)
		(layers "F.Cu" "B.Cu")
		(remove_unused_layers yes)
		(keep_end_layers yes)
		(zone_layer_connections)
		(net 596)
	)
	(via
		(at 193.299 131.501)
		(size 0.35)
		(drill 0.15)
		(layers "F.Cu" "B.Cu")
		(remove_unused_layers yes)
		(keep_end_layers yes)
		(zone_layer_connections)
		(net 596)
	)
	(segment
		(start 185.235 131.64)
		(end 185.0135 131.8615)
		(width 0.09)
		(layer "In4.Cu")
		(net 596)
	)
	(segment
		(start 182.66 132.51)
		(end 182.14 132.51)
		(width 0.09)
		(layer "In4.Cu")
		(net 596)
	)
	(segment
		(start 188.91 132.47)
		(end 188.91 131.99)
		(width 0.09)
		(layer "In4.Cu")
		(net 596)
	)
	(segment
		(start 182.928579 131.95)
		(end 182.83 131.95)
		(width 0.09)
		(layer "In4.Cu")
		(net 596)
	)
	(segment
		(start 188.91 131.99)
		(end 188.56 131.64)
		(width 0.09)
		(layer "In4.Cu")
		(net 596)
	)
	(segment
		(start 182.14 132.79)
		(end 182.66 132.79)
		(width 0.09)
		(layer "In4.Cu")
		(net 596)
	)
	(segment
		(start 182.91 133.65)
		(end 183.7175 132.8425)
		(width 0.09)
		(layer "In4.Cu")
		(net 596)
	)
	(segment
		(start 191.225 131.475)
		(end 191.225 131.68462)
		(width 0.09)
		(layer "In4.Cu")
		(net 596)
	)
	(segment
		(start 182.043224 133.573224)
		(end 182.046777 133.576777)
		(width 0.09)
		(layer "In4.Cu")
		(net 596)
	)
	(segment
		(start 193.624 131.176)
		(end 193.624 130.56638)
		(width 0.09)
		(layer "In4.Cu")
		(net 596)
	)
	(segment
		(start 192.025 130.83562)
		(end 191.66062 131.2)
		(width 0.09)
		(layer "In4.Cu")
		(net 596)
	)
	(segment
		(start 182.38 131.7)
		(end 182.38 131.8)
		(width 0.09)
		(layer "In4.Cu")
		(net 596)
	)
	(segment
		(start 182.68 131.8)
		(end 182.68 131.7)
		(width 0.09)
		(layer "In4.Cu")
		(net 596)
	)
	(segment
		(start 182.23 131.95)
		(end 182.14 131.95)
		(width 0.09)
		(layer "In4.Cu")
		(net 596)
	)
	(segment
		(start 185.0135 131.8615)
		(end 183.099921 131.8615)
		(width 0.09)
		(layer "In4.Cu")
		(net 596)
	)
	(segment
		(start 189.7 132.12)
		(end 189.7 132.44)
		(width 0.09)
		(layer "In4.Cu")
		(net 596)
	)
	(segment
		(start 189.7 132.44)
		(end 189.52 132.62)
		(width 0.09)
		(layer "In4.Cu")
		(net 596)
	)
	(segment
		(start 188.56 131.64)
		(end 185.235 131.64)
		(width 0.09)
		(layer "In4.Cu")
		(net 596)
	)
	(segment
		(start 193.624 130.56638)
		(end 193.41762 130.36)
		(width 0.09)
		(layer "In4.Cu")
		(net 596)
	)
	(segment
		(start 189.52 132.62)
		(end 189.06 132.62)
		(width 0.09)
		(layer "In4.Cu")
		(net 596)
	)
	(segment
		(start 191.225 131.68462)
		(end 191.00462 131.905)
		(width 0.09)
		(layer "In4.Cu")
		(net 596)
	)
	(segment
		(start 182.14 132.23)
		(end 182.66 132.23)
		(width 0.09)
		(layer "In4.Cu")
		(net 596)
	)
	(segment
		(start 181.97 133.353553)
		(end 181.97 133.396447)
		(width 0.09)
		(layer "In4.Cu")
		(net 596)
	)
	(segment
		(start 193.299 131.501)
		(end 193.624 131.176)
		(width 0.09)
		(layer "In4.Cu")
		(net 596)
	)
	(segment
		(start 191.5 131.2)
		(end 191.225 131.475)
		(width 0.09)
		(layer "In4.Cu")
		(net 596)
	)
	(segment
		(start 183.7175 132.8425)
		(end 184.0035 132.8425)
		(width 0.09)
		(layer "In4.Cu")
		(net 596)
	)
	(segment
		(start 192.38038 130.36)
		(end 192.025 130.71538)
		(width 0.09)
		(layer "In4.Cu")
		(net 596)
	)
	(segment
		(start 192.025 130.71538)
		(end 192.025 130.83562)
		(width 0.09)
		(layer "In4.Cu")
		(net 596)
	)
	(segment
		(start 193.41762 130.36)
		(end 192.38038 130.36)
		(width 0.09)
		(layer "In4.Cu")
		(net 596)
	)
	(segment
		(start 183.02921 131.89079)
		(end 182.999289 131.920711)
		(width 0.09)
		(layer "In4.Cu")
		(net 596)
	)
	(segment
		(start 182.076776 133.143224)
		(end 182.043223 133.176777)
		(width 0.09)
		(layer "In4.Cu")
		(net 596)
	)
	(segment
		(start 189.06 132.62)
		(end 188.91 132.47)
		(width 0.09)
		(layer "In4.Cu")
		(net 596)
	)
	(segment
		(start 182.223553 133.65)
		(end 182.91 133.65)
		(width 0.09)
		(layer "In4.Cu")
		(net 596)
	)
	(segment
		(start 182.66 133.07)
		(end 182.253553 133.07)
		(width 0.09)
		(layer "In4.Cu")
		(net 596)
	)
	(segment
		(start 191.00462 131.905)
		(end 189.915 131.905)
		(width 0.09)
		(layer "In4.Cu")
		(net 596)
	)
	(segment
		(start 191.66062 131.2)
		(end 191.5 131.2)
		(width 0.09)
		(layer "In4.Cu")
		(net 596)
	)
	(segment
		(start 189.915 131.905)
		(end 189.7 132.12)
		(width 0.09)
		(layer "In4.Cu")
		(net 596)
	)
	(arc
		(start 182.253553 133.07)
		(mid 182.157882 133.08903)
		(end 182.076776 133.143224)
		(width 0.09)
		(layer "In4.Cu")
		(net 596)
	)
	(arc
		(start 182.046777 133.576777)
		(mid 182.127882 133.63097)
		(end 182.223553 133.65)
		(width 0.09)
		(layer "In4.Cu")
		(net 596)
	)
	(arc
		(start 183.099921 131.8615)
		(mid 183.061652 131.869112)
		(end 183.02921 131.89079)
		(width 0.09)
		(layer "In4.Cu")
		(net 596)
	)
	(arc
		(start 182.66 132.23)
		(mid 182.758995 132.271005)
		(end 182.8 132.37)
		(width 0.09)
		(layer "In4.Cu")
		(net 596)
	)
	(arc
		(start 182.8 132.37)
		(mid 182.758995 132.468995)
		(end 182.66 132.51)
		(width 0.09)
		(layer "In4.Cu")
		(net 596)
	)
	(arc
		(start 182.8 132.93)
		(mid 182.758995 133.028995)
		(end 182.66 133.07)
		(width 0.09)
		(layer "In4.Cu")
		(net 596)
	)
	(arc
		(start 182.66 132.79)
		(mid 182.758995 132.831005)
		(end 182.8 132.93)
		(width 0.09)
		(layer "In4.Cu")
		(net 596)
	)
	(arc
		(start 182.53 131.55)
		(mid 182.423934 131.593934)
		(end 182.38 131.7)
		(width 0.09)
		(layer "In4.Cu")
		(net 596)
	)
	(arc
		(start 182.14 132.51)
		(mid 182.041005 132.551005)
		(end 182 132.65)
		(width 0.09)
		(layer "In4.Cu")
		(net 596)
	)
	(arc
		(start 182 132.65)
		(mid 182.041005 132.748995)
		(end 182.14 132.79)
		(width 0.09)
		(layer "In4.Cu")
		(net 596)
	)
	(arc
		(start 182 132.09)
		(mid 182.041005 132.188995)
		(end 182.14 132.23)
		(width 0.09)
		(layer "In4.Cu")
		(net 596)
	)
	(arc
		(start 182.14 131.95)
		(mid 182.041005 131.991005)
		(end 182 132.09)
		(width 0.09)
		(layer "In4.Cu")
		(net 596)
	)
	(arc
		(start 182.999289 131.920711)
		(mid 182.966847 131.942388)
		(end 182.928579 131.95)
		(width 0.09)
		(layer "In4.Cu")
		(net 596)
	)
	(arc
		(start 182.043223 133.176777)
		(mid 181.98903 133.257883)
		(end 181.97 133.353553)
		(width 0.09)
		(layer "In4.Cu")
		(net 596)
	)
	(arc
		(start 181.97 133.396447)
		(mid 181.989031 133.492118)
		(end 182.043224 133.573224)
		(width 0.09)
		(layer "In4.Cu")
		(net 596)
	)
	(arc
		(start 182.83 131.95)
		(mid 182.723934 131.906066)
		(end 182.68 131.8)
		(width 0.09)
		(layer "In4.Cu")
		(net 596)
	)
	(arc
		(start 182.68 131.7)
		(mid 182.636066 131.593934)
		(end 182.53 131.55)
		(width 0.09)
		(layer "In4.Cu")
		(net 596)
	)
	(arc
		(start 182.38 131.8)
		(mid 182.336066 131.906066)
		(end 182.23 131.95)
		(width 0.09)
		(layer "In4.Cu")
		(net 596)
	)
	(segment
		(start 183.1295 127.6405)
		(end 183.15 127.6405)
		(width 0.174)
		(layer "F.Cu")
		(net 597)
	)
	(segment
		(start 183.1305 131.5415)
		(end 183.131 131.5415)
		(width 0.174)
		(layer "F.Cu")
		(net 597)
	)
	(segment
		(start 182.805 131.867)
		(end 183.1305 131.5415)
		(width 0.174)
		(layer "F.Cu")
		(net 597)
	)
	(segment
		(start 182.805 127.316)
		(end 183.1295 127.6405)
		(width 0.174)
		(layer "F.Cu")
		(net 597)
	)
	(via
		(at 183.15 127.6405)
		(size 0.35)
		(drill 0.15)
		(layers "F.Cu" "B.Cu")
		(remove_unused_layers yes)
		(keep_end_layers yes)
		(zone_layer_connections)
		(net 597)
	)
	(via
		(at 183.131 131.5415)
		(size 0.35)
		(drill 0.15)
		(layers "F.Cu" "B.Cu")
		(remove_unused_layers yes)
		(keep_end_layers yes)
		(zone_layer_connections)
		(net 597)
	)
	(via
		(at 192.499 128.3)
		(size 0.35)
		(drill 0.15)
		(layers "F.Cu" "B.Cu")
		(remove_unused_layers yes)
		(keep_end_layers yes)
		(zone_layer_connections)
		(net 597)
	)
	(segment
		(start 182.96 129.77)
		(end 182.76 129.77)
		(width 0.09)
		(layer "In9.Cu")
		(net 597)
	)
	(segment
		(start 183.15 127.6405)
		(end 182.8695 127.6405)
		(width 0.09)
		(layer "In9.Cu")
		(net 597)
	)
	(segment
		(start 182.8695 127.6405)
		(end 182.61 127.9)
		(width 0.09)
		(layer "In9.Cu")
		(net 597)
	)
	(segment
		(start 182.61 131.29)
		(end 182.8615 131.5415)
		(width 0.09)
		(layer "In9.Cu")
		(net 597)
	)
	(segment
		(start 182.8615 131.5415)
		(end 183.131 131.5415)
		(width 0.09)
		(layer "In9.Cu")
		(net 597)
	)
	(segment
		(start 182.61 127.9)
		(end 182.61 129.32)
		(width 0.09)
		(layer "In9.Cu")
		(net 597)
	)
	(segment
		(start 182.61 129.92)
		(end 182.61 131.29)
		(width 0.09)
		(layer "In9.Cu")
		(net 597)
	)
	(segment
		(start 182.76 129.47)
		(end 182.96 129.47)
		(width 0.09)
		(layer "In9.Cu")
		(net 597)
	)
	(arc
		(start 182.96 129.47)
		(mid 183.066066 129.513934)
		(end 183.11 129.62)
		(width 0.09)
		(layer "In9.Cu")
		(net 597)
	)
	(arc
		(start 183.11 129.62)
		(mid 183.066066 129.726066)
		(end 182.96 129.77)
		(width 0.09)
		(layer "In9.Cu")
		(net 597)
	)
	(arc
		(start 182.76 129.77)
		(mid 182.653934 129.813934)
		(end 182.61 129.92)
		(width 0.09)
		(layer "In9.Cu")
		(net 597)
	)
	(arc
		(start 182.61 129.32)
		(mid 182.653934 129.426066)
		(end 182.76 129.47)
		(width 0.09)
		(layer "In9.Cu")
		(net 597)
	)
	(segment
		(start 182.24 127.98)
		(end 182.1 127.84)
		(width 0.09)
		(layer "In11.Cu")
		(net 597)
	)
	(segment
		(start 186.18 129.61)
		(end 186.18 130.525332)
		(width 0.09)
		(layer "In11.Cu")
		(net 597)
	)
	(segment
		(start 185.68 129.28)
		(end 185.87 129.47)
		(width 0.09)
		(layer "In11.Cu")
		(net 597)
	)
	(segment
		(start 183.15 127.6405)
		(end 182.7795 127.6405)
		(width 0.09)
		(layer "In11.Cu")
		(net 597)
	)
	(segment
		(start 184.937049 127.3215)
		(end 185.68 128.064451)
		(width 0.09)
		(layer "In11.Cu")
		(net 597)
	)
	(segment
		(start 184.681951 127.3215)
		(end 184.937049 127.3215)
		(width 0.09)
		(layer "In11.Cu")
		(net 597)
	)
	(segment
		(start 182.44 127.98)
		(end 182.24 127.98)
		(width 0.09)
		(layer "In11.Cu")
		(net 597)
	)
	(segment
		(start 190.52 129.27)
		(end 190.52 128.865)
		(width 0.09)
		(layer "In11.Cu")
		(net 597)
	)
	(segment
		(start 185.68 128.064451)
		(end 185.68 129.28)
		(width 0.09)
		(layer "In11.Cu")
		(net 597)
	)
	(segment
		(start 187.3 129.61)
		(end 187.3 130.675336)
		(width 0.09)
		(layer "In11.Cu")
		(net 597)
	)
	(segment
		(start 188.14 130.675346)
		(end 188.14 129.61)
		(width 0.09)
		(layer "In11.Cu")
		(net 597)
	)
	(segment
		(start 192.099 128.7)
		(end 192.499 128.3)
		(width 0.09)
		(layer "In11.Cu")
		(net 597)
	)
	(segment
		(start 187.58 130.675336)
		(end 187.58 129.61)
		(width 0.09)
		(layer "In11.Cu")
		(net 597)
	)
	(segment
		(start 186.46 130.525332)
		(end 186.46 129.61)
		(width 0.09)
		(layer "In11.Cu")
		(net 597)
	)
	(segment
		(start 183.1035 126.6665)
		(end 184.026951 126.6665)
		(width 0.09)
		(layer "In11.Cu")
		(net 597)
	)
	(segment
		(start 190.685 128.7)
		(end 192.099 128.7)
		(width 0.09)
		(layer "In11.Cu")
		(net 597)
	)
	(segment
		(start 190.32 129.47)
		(end 190.52 129.27)
		(width 0.09)
		(layer "In11.Cu")
		(net 597)
	)
	(segment
		(start 188.42 129.61)
		(end 188.42 130.675349)
		(width 0.09)
		(layer "In11.Cu")
		(net 597)
	)
	(segment
		(start 182.1 127.67)
		(end 183.1035 126.6665)
		(width 0.09)
		(layer "In11.Cu")
		(net 597)
	)
	(segment
		(start 185.87 129.47)
		(end 186.04 129.47)
		(width 0.09)
		(layer "In11.Cu")
		(net 597)
	)
	(segment
		(start 184.026951 126.6665)
		(end 184.681951 127.3215)
		(width 0.09)
		(layer "In11.Cu")
		(net 597)
	)
	(segment
		(start 182.1 127.84)
		(end 182.1 127.67)
		(width 0.09)
		(layer "In11.Cu")
		(net 597)
	)
	(segment
		(start 187.86 129.61)
		(end 187.86 130.675346)
		(width 0.09)
		(layer "In11.Cu")
		(net 597)
	)
	(segment
		(start 187.02 130.675336)
		(end 187.02 129.61)
		(width 0.09)
		(layer "In11.Cu")
		(net 597)
	)
	(segment
		(start 186.74 129.61)
		(end 186.74 130.675336)
		(width 0.09)
		(layer "In11.Cu")
		(net 597)
	)
	(segment
		(start 182.7795 127.6405)
		(end 182.44 127.98)
		(width 0.09)
		(layer "In11.Cu")
		(net 597)
	)
	(segment
		(start 188.84 129.47)
		(end 190.32 129.47)
		(width 0.09)
		(layer "In11.Cu")
		(net 597)
	)
	(segment
		(start 190.52 128.865)
		(end 190.685 128.7)
		(width 0.09)
		(layer "In11.Cu")
		(net 597)
	)
	(segment
		(start 188.7 130.675349)
		(end 188.7 129.61)
		(width 0.09)
		(layer "In11.Cu")
		(net 597)
	)
	(arc
		(start 186.74 130.675336)
		(mid 186.781005 130.774331)
		(end 186.88 130.815336)
		(width 0.09)
		(layer "In11.Cu")
		(net 597)
	)
	(arc
		(start 187.86 130.675346)
		(mid 187.901005 130.774341)
		(end 188 130.815346)
		(width 0.09)
		(layer "In11.Cu")
		(net 597)
	)
	(arc
		(start 186.6 129.47)
		(mid 186.698995 129.511005)
		(end 186.74 129.61)
		(width 0.09)
		(layer "In11.Cu")
		(net 597)
	)
	(arc
		(start 186.46 129.61)
		(mid 186.501005 129.511005)
		(end 186.6 129.47)
		(width 0.09)
		(layer "In11.Cu")
		(net 597)
	)
	(arc
		(start 187.3 130.675336)
		(mid 187.341005 130.774331)
		(end 187.44 130.815336)
		(width 0.09)
		(layer "In11.Cu")
		(net 597)
	)
	(arc
		(start 188.56 130.815349)
		(mid 188.658995 130.774344)
		(end 188.7 130.675349)
		(width 0.09)
		(layer "In11.Cu")
		(net 597)
	)
	(arc
		(start 186.32 130.665332)
		(mid 186.418995 130.624327)
		(end 186.46 130.525332)
		(width 0.09)
		(layer "In11.Cu")
		(net 597)
	)
	(arc
		(start 188.28 129.47)
		(mid 188.378995 129.511005)
		(end 188.42 129.61)
		(width 0.09)
		(layer "In11.Cu")
		(net 597)
	)
	(arc
		(start 188.7 129.61)
		(mid 188.741005 129.511005)
		(end 188.84 129.47)
		(width 0.09)
		(layer "In11.Cu")
		(net 597)
	)
	(arc
		(start 187.44 130.815336)
		(mid 187.538995 130.774331)
		(end 187.58 130.675336)
		(width 0.09)
		(layer "In11.Cu")
		(net 597)
	)
	(arc
		(start 186.88 130.815336)
		(mid 186.978995 130.774331)
		(end 187.02 130.675336)
		(width 0.09)
		(layer "In11.Cu")
		(net 597)
	)
	(arc
		(start 188.42 130.675349)
		(mid 188.461005 130.774344)
		(end 188.56 130.815349)
		(width 0.09)
		(layer "In11.Cu")
		(net 597)
	)
	(arc
		(start 188.14 129.61)
		(mid 188.181005 129.511005)
		(end 188.28 129.47)
		(width 0.09)
		(layer "In11.Cu")
		(net 597)
	)
	(arc
		(start 187.16 129.47)
		(mid 187.258995 129.511005)
		(end 187.3 129.61)
		(width 0.09)
		(layer "In11.Cu")
		(net 597)
	)
	(arc
		(start 187.58 129.61)
		(mid 187.621005 129.511005)
		(end 187.72 129.47)
		(width 0.09)
		(layer "In11.Cu")
		(net 597)
	)
	(arc
		(start 187.02 129.61)
		(mid 187.061005 129.511005)
		(end 187.16 129.47)
		(width 0.09)
		(layer "In11.Cu")
		(net 597)
	)
	(arc
		(start 186.18 130.525332)
		(mid 186.221005 130.624327)
		(end 186.32 130.665332)
		(width 0.09)
		(layer "In11.Cu")
		(net 597)
	)
	(arc
		(start 187.72 129.47)
		(mid 187.818995 129.511005)
		(end 187.86 129.61)
		(width 0.09)
		(layer "In11.Cu")
		(net 597)
	)
	(arc
		(start 188 130.815346)
		(mid 188.098995 130.774341)
		(end 188.14 130.675346)
		(width 0.09)
		(layer "In11.Cu")
		(net 597)
	)
	(arc
		(start 186.04 129.47)
		(mid 186.138995 129.511005)
		(end 186.18 129.61)
		(width 0.09)
		(layer "In11.Cu")
		(net 597)
	)
	(segment
		(start 182.004 131.867)
		(end 181.6045 131.5425)
		(width 0.174)
		(layer "F.Cu")
		(net 598)
	)
	(segment
		(start 182.004 127.316)
		(end 181.6045 127.6405)
		(width 0.174)
		(layer "F.Cu")
		(net 598)
	)
	(via
		(at 181.6045 127.6405)
		(size 0.35)
		(drill 0.15)
		(layers "F.Cu" "B.Cu")
		(remove_unused_layers yes)
		(keep_end_layers yes)
		(zone_layer_connections)
		(net 598)
	)
	(via
		(at 181.6045 131.5425)
		(size 0.35)
		(drill 0.15)
		(layers "F.Cu" "B.Cu")
		(remove_unused_layers yes)
		(keep_end_layers yes)
		(zone_layer_connections)
		(net 598)
	)
	(via
		(at 192.499 129.1)
		(size 0.35)
		(drill 0.15)
		(layers "F.Cu" "B.Cu")
		(remove_unused_layers yes)
		(keep_end_layers yes)
		(zone_layer_connections)
		(net 598)
	)
	(segment
		(start 182.09 129.48)
		(end 182 129.48)
		(width 0.09)
		(layer "In9.Cu")
		(net 598)
	)
	(segment
		(start 182.237444 129.890492)
		(end 182.237444 131.292556)
		(width 0.09)
		(layer "In9.Cu")
		(net 598)
	)
	(segment
		(start 182 129.78)
		(end 182.09 129.78)
		(width 0.09)
		(layer "In9.Cu")
		(net 598)
	)
	(segment
		(start 182.237444 131.292556)
		(end 181.9875 131.5425)
		(width 0.09)
		(layer "In9.Cu")
		(net 598)
	)
	(segment
		(start 182.237444 127.877444)
		(end 182.237444 129.369508)
		(width 0.09)
		(layer "In9.Cu")
		(net 598)
	)
	(segment
		(start 181.6045 127.6405)
		(end 182.0005 127.6405)
		(width 0.09)
		(layer "In9.Cu")
		(net 598)
	)
	(segment
		(start 181.9875 131.5425)
		(end 181.6045 131.5425)
		(width 0.09)
		(layer "In9.Cu")
		(net 598)
	)
	(segment
		(start 182.0005 127.6405)
		(end 182.237444 127.877444)
		(width 0.09)
		(layer "In9.Cu")
		(net 598)
	)
	(arc
		(start 182 129.48)
		(mid 181.893934 129.523934)
		(end 181.85 129.63)
		(width 0.09)
		(layer "In9.Cu")
		(net 598)
	)
	(arc
		(start 182.09 129.78)
		(mid 182.181314 129.810997)
		(end 182.237444 129.890492)
		(width 0.09)
		(layer "In9.Cu")
		(net 598)
	)
	(arc
		(start 182.237444 129.369508)
		(mid 182.181314 129.449003)
		(end 182.09 129.48)
		(width 0.09)
		(layer "In9.Cu")
		(net 598)
	)
	(arc
		(start 181.85 129.63)
		(mid 181.893934 129.736066)
		(end 182 129.78)
		(width 0.09)
		(layer "In9.Cu")
		(net 598)
	)
	(segment
		(start 188.89 128.977142)
		(end 188.89 128.04)
		(width 0.09)
		(layer "In11.Cu")
		(net 598)
	)
	(segment
		(start 187.99 128.04)
		(end 187.99 128.977142)
		(width 0.09)
		(layer "In11.Cu")
		(net 598)
	)
	(segment
		(start 188.29 128.977142)
		(end 188.29 128.04)
		(width 0.09)
		(layer "In11.Cu")
		(net 598)
	)
	(segment
		(start 185.5 126.89)
		(end 185.5 127.44)
		(width 0.09)
		(layer "In11.Cu")
		(net 598)
	)
	(segment
		(start 187.39 128.04)
		(end 187.39 128.977142)
		(width 0.09)
		(layer "In11.Cu")
		(net 598)
	)
	(segment
		(start 182.77 126.2)
		(end 182.9545 126.0155)
		(width 0.09)
		(layer "In11.Cu")
		(net 598)
	)
	(segment
		(start 188.59 128.04)
		(end 188.59 128.977142)
		(width 0.09)
		(layer "In11.Cu")
		(net 598)
	)
	(segment
		(start 181.6045 127.6405)
		(end 182.77 126.475)
		(width 0.09)
		(layer "In11.Cu")
		(net 598)
	)
	(segment
		(start 192.09 127.71)
		(end 192.09 127.53)
		(width 0.09)
		(layer "In11.Cu")
		(net 598)
	)
	(segment
		(start 184.6405 126.6605)
		(end 185.2705 126.6605)
		(width 0.09)
		(layer "In11.Cu")
		(net 598)
	)
	(segment
		(start 184.1955 126.0155)
		(end 184.42 126.24)
		(width 0.09)
		(layer "In11.Cu")
		(net 598)
	)
	(segment
		(start 184.42 126.24)
		(end 184.42 126.44)
		(width 0.09)
		(layer "In11.Cu")
		(net 598)
	)
	(segment
		(start 187.69 128.977142)
		(end 187.69 128.04)
		(width 0.09)
		(layer "In11.Cu")
		(net 598)
	)
	(segment
		(start 182.77 126.475)
		(end 182.77 126.2)
		(width 0.09)
		(layer "In11.Cu")
		(net 598)
	)
	(segment
		(start 189.04 127.89)
		(end 191.91 127.89)
		(width 0.09)
		(layer "In11.Cu")
		(net 598)
	)
	(segment
		(start 184.42 126.44)
		(end 184.6405 126.6605)
		(width 0.09)
		(layer "In11.Cu")
		(net 598)
	)
	(segment
		(start 192.65 127.34)
		(end 192.89 127.58)
		(width 0.09)
		(layer "In11.Cu")
		(net 598)
	)
	(segment
		(start 186.79 128.04)
		(end 186.79 128.977142)
		(width 0.09)
		(layer "In11.Cu")
		(net 598)
	)
	(segment
		(start 192.09 127.53)
		(end 192.28 127.34)
		(width 0.09)
		(layer "In11.Cu")
		(net 598)
	)
	(segment
		(start 192.89 127.58)
		(end 192.89 128.709)
		(width 0.09)
		(layer "In11.Cu")
		(net 598)
	)
	(segment
		(start 185.5 127.44)
		(end 185.95 127.89)
		(width 0.09)
		(layer "In11.Cu")
		(net 598)
	)
	(segment
		(start 191.91 127.89)
		(end 192.09 127.71)
		(width 0.09)
		(layer "In11.Cu")
		(net 598)
	)
	(segment
		(start 186.19 128.04)
		(end 186.19 128.977142)
		(width 0.09)
		(layer "In11.Cu")
		(net 598)
	)
	(segment
		(start 187.09 128.977142)
		(end 187.09 128.04)
		(width 0.09)
		(layer "In11.Cu")
		(net 598)
	)
	(segment
		(start 185.95 127.89)
		(end 186.04 127.89)
		(width 0.09)
		(layer "In11.Cu")
		(net 598)
	)
	(segment
		(start 186.49 128.977142)
		(end 186.49 128.04)
		(width 0.09)
		(layer "In11.Cu")
		(net 598)
	)
	(segment
		(start 192.89 128.709)
		(end 192.499 129.1)
		(width 0.09)
		(layer "In11.Cu")
		(net 598)
	)
	(segment
		(start 185.2705 126.6605)
		(end 185.5 126.89)
		(width 0.09)
		(layer "In11.Cu")
		(net 598)
	)
	(segment
		(start 182.9545 126.0155)
		(end 184.1955 126.0155)
		(width 0.09)
		(layer "In11.Cu")
		(net 598)
	)
	(segment
		(start 192.28 127.34)
		(end 192.65 127.34)
		(width 0.09)
		(layer "In11.Cu")
		(net 598)
	)
	(arc
		(start 187.54 129.127142)
		(mid 187.646066 129.083208)
		(end 187.69 128.977142)
		(width 0.09)
		(layer "In11.Cu")
		(net 598)
	)
	(arc
		(start 187.24 127.89)
		(mid 187.346066 127.933934)
		(end 187.39 128.04)
		(width 0.09)
		(layer "In11.Cu")
		(net 598)
	)
	(arc
		(start 188.74 129.127142)
		(mid 188.846066 129.083208)
		(end 188.89 128.977142)
		(width 0.09)
		(layer "In11.Cu")
		(net 598)
	)
	(arc
		(start 186.19 128.977142)
		(mid 186.233934 129.083208)
		(end 186.34 129.127142)
		(width 0.09)
		(layer "In11.Cu")
		(net 598)
	)
	(arc
		(start 186.79 128.977142)
		(mid 186.833934 129.083208)
		(end 186.94 129.127142)
		(width 0.09)
		(layer "In11.Cu")
		(net 598)
	)
	(arc
		(start 188.44 127.89)
		(mid 188.546066 127.933934)
		(end 188.59 128.04)
		(width 0.09)
		(layer "In11.Cu")
		(net 598)
	)
	(arc
		(start 187.39 128.977142)
		(mid 187.433934 129.083208)
		(end 187.54 129.127142)
		(width 0.09)
		(layer "In11.Cu")
		(net 598)
	)
	(arc
		(start 186.94 129.127142)
		(mid 187.046066 129.083208)
		(end 187.09 128.977142)
		(width 0.09)
		(layer "In11.Cu")
		(net 598)
	)
	(arc
		(start 186.49 128.04)
		(mid 186.533934 127.933934)
		(end 186.64 127.89)
		(width 0.09)
		(layer "In11.Cu")
		(net 598)
	)
	(arc
		(start 187.99 128.977142)
		(mid 188.033934 129.083208)
		(end 188.14 129.127142)
		(width 0.09)
		(layer "In11.Cu")
		(net 598)
	)
	(arc
		(start 187.09 128.04)
		(mid 187.133934 127.933934)
		(end 187.24 127.89)
		(width 0.09)
		(layer "In11.Cu")
		(net 598)
	)
	(arc
		(start 187.84 127.89)
		(mid 187.946066 127.933934)
		(end 187.99 128.04)
		(width 0.09)
		(layer "In11.Cu")
		(net 598)
	)
	(arc
		(start 188.14 129.127142)
		(mid 188.246066 129.083208)
		(end 188.29 128.977142)
		(width 0.09)
		(layer "In11.Cu")
		(net 598)
	)
	(arc
		(start 188.29 128.04)
		(mid 188.333934 127.933934)
		(end 188.44 127.89)
		(width 0.09)
		(layer "In11.Cu")
		(net 598)
	)
	(arc
		(start 187.69 128.04)
		(mid 187.733934 127.933934)
		(end 187.84 127.89)
		(width 0.09)
		(layer "In11.Cu")
		(net 598)
	)
	(arc
		(start 186.34 129.127142)
		(mid 186.446066 129.083208)
		(end 186.49 128.977142)
		(width 0.09)
		(layer "In11.Cu")
		(net 598)
	)
	(arc
		(start 188.89 128.04)
		(mid 188.933934 127.933934)
		(end 189.04 127.89)
		(width 0.09)
		(layer "In11.Cu")
		(net 598)
	)
	(arc
		(start 186.64 127.89)
		(mid 186.746066 127.933934)
		(end 186.79 128.04)
		(width 0.09)
		(layer "In11.Cu")
		(net 598)
	)
	(arc
		(start 188.59 128.977142)
		(mid 188.633934 129.083208)
		(end 188.74 129.127142)
		(width 0.09)
		(layer "In11.Cu")
		(net 598)
	)
	(arc
		(start 186.04 127.89)
		(mid 186.146066 127.933934)
		(end 186.19 128.04)
		(width 0.09)
		(layer "In11.Cu")
		(net 598)
	)
	(segment
		(start 182.805 133.817)
		(end 182.4055 134.1415)
		(width 0.174)
		(layer "F.Cu")
		(net 599)
	)
	(via
		(at 192.499 130.701)
		(size 0.35)
		(drill 0.15)
		(layers "F.Cu" "B.Cu")
		(remove_unused_layers yes)
		(keep_end_layers yes)
		(zone_layer_connections)
		(net 599)
	)
	(via
		(at 182.4055 134.1415)
		(size 0.35)
		(drill 0.15)
		(layers "F.Cu" "B.Cu")
		(remove_unused_layers yes)
		(keep_end_layers yes)
		(zone_layer_connections)
		(net 599)
	)
	(segment
		(start 192.16 131.37)
		(end 192.36 131.17)
		(width 0.09)
		(layer "In4.Cu")
		(net 599)
	)
	(segment
		(start 188.889706 132.92)
		(end 190.040294 132.92)
		(width 0.09)
		(layer "In4.Cu")
		(net 599)
	)
	(segment
		(start 192.87 130.56)
		(end 192.64 130.56)
		(width 0.09)
		(layer "In4.Cu")
		(net 599)
	)
	(segment
		(start 192.779 131.014754)
		(end 192.779 130.881)
		(width 0.09)
		(layer "In4.Cu")
		(net 599)
	)
	(segment
		(start 182.4055 134.1415)
		(end 182.61 134.346)
		(width 0.09)
		(layer "In4.Cu")
		(net 599)
	)
	(segment
		(start 192.92 130.74)
		(end 192.92 130.61)
		(width 0.09)
		(layer "In4.Cu")
		(net 599)
	)
	(segment
		(start 182.734334 134.34596)
		(end 183.770294 133.31)
		(width 0.09)
		(layer "In4.Cu")
		(net 599)
	)
	(segment
		(start 183.770294 133.31)
		(end 184.920294 133.31)
		(width 0.09)
		(layer "In4.Cu")
		(net 599)
	)
	(segment
		(start 192.36 131.17)
		(end 192.623754 131.17)
		(width 0.09)
		(layer "In4.Cu")
		(net 599)
	)
	(segment
		(start 187.76 133.698695)
		(end 187.76 132.38)
		(width 0.09)
		(layer "In4.Cu")
		(net 599)
	)
	(segment
		(start 185.440294 131.96)
		(end 185.78 131.96)
		(width 0.09)
		(layer "In4.Cu")
		(net 599)
	)
	(segment
		(start 192.92 130.61)
		(end 192.87 130.56)
		(width 0.09)
		(layer "In4.Cu")
		(net 599)
	)
	(segment
		(start 188.419706 131.96)
		(end 188.68 132.220294)
		(width 0.09)
		(layer "In4.Cu")
		(net 599)
	)
	(segment
		(start 191.833754 131.96)
		(end 192.16 131.633754)
		(width 0.09)
		(layer "In4.Cu")
		(net 599)
	)
	(segment
		(start 182.734334 134.346)
		(end 182.734334 134.34596)
		(width 0.09)
		(layer "In4.Cu")
		(net 599)
	)
	(segment
		(start 186.2 132.38)
		(end 186.2 133.698671)
		(width 0.09)
		(layer "In4.Cu")
		(net 599)
	)
	(segment
		(start 192.16 131.633754)
		(end 192.16 131.37)
		(width 0.09)
		(layer "In4.Cu")
		(net 599)
	)
	(segment
		(start 191.34 132.16)
		(end 191.54 131.96)
		(width 0.09)
		(layer "In4.Cu")
		(net 599)
	)
	(segment
		(start 190.040294 132.92)
		(end 190.400274 132.56002)
		(width 0.09)
		(layer "In4.Cu")
		(net 599)
	)
	(segment
		(start 185.16 133.070294)
		(end 185.16 132.240294)
		(width 0.09)
		(layer "In4.Cu")
		(net 599)
	)
	(segment
		(start 190.400274 132.56002)
		(end 191.14998 132.56002)
		(width 0.09)
		(layer "In4.Cu")
		(net 599)
	)
	(segment
		(start 191.14998 132.56002)
		(end 191.34 132.37)
		(width 0.09)
		(layer "In4.Cu")
		(net 599)
	)
	(segment
		(start 192.623754 131.17)
		(end 192.779 131.014754)
		(width 0.09)
		(layer "In4.Cu")
		(net 599)
	)
	(segment
		(start 192.64 130.56)
		(end 192.499 130.701)
		(width 0.09)
		(layer "In4.Cu")
		(net 599)
	)
	(segment
		(start 191.54 131.96)
		(end 191.833754 131.96)
		(width 0.09)
		(layer "In4.Cu")
		(net 599)
	)
	(segment
		(start 192.779 130.881)
		(end 192.92 130.74)
		(width 0.09)
		(layer "In4.Cu")
		(net 599)
	)
	(segment
		(start 185.16 132.240294)
		(end 185.440294 131.96)
		(width 0.09)
		(layer "In4.Cu")
		(net 599)
	)
	(segment
		(start 186.56 133.698671)
		(end 186.56 132.38)
		(width 0.09)
		(layer "In4.Cu")
		(net 599)
	)
	(segment
		(start 188.18 131.96)
		(end 188.419706 131.96)
		(width 0.09)
		(layer "In4.Cu")
		(net 599)
	)
	(segment
		(start 184.920294 133.31)
		(end 185.16 133.070294)
		(width 0.09)
		(layer "In4.Cu")
		(net 599)
	)
	(segment
		(start 187.4 132.38)
		(end 187.4 133.698695)
		(width 0.09)
		(layer "In4.Cu")
		(net 599)
	)
	(segment
		(start 191.34 132.37)
		(end 191.34 132.16)
		(width 0.09)
		(layer "In4.Cu")
		(net 599)
	)
	(segment
		(start 182.61 134.346)
		(end 182.734334 134.346)
		(width 0.09)
		(layer "In4.Cu")
		(net 599)
	)
	(segment
		(start 188.68 132.220294)
		(end 188.68 132.710294)
		(width 0.09)
		(layer "In4.Cu")
		(net 599)
	)
	(segment
		(start 188.68 132.710294)
		(end 188.889706 132.92)
		(width 0.09)
		(layer "In4.Cu")
		(net 599)
	)
	(arc
		(start 186.56 132.38)
		(mid 186.683015 132.083015)
		(end 186.98 131.96)
		(width 0.09)
		(layer "In4.Cu")
		(net 599)
	)
	(arc
		(start 186.98 131.96)
		(mid 187.276985 132.083015)
		(end 187.4 132.38)
		(width 0.09)
		(layer "In4.Cu")
		(net 599)
	)
	(arc
		(start 187.58 133.878695)
		(mid 187.707279 133.825974)
		(end 187.76 133.698695)
		(width 0.09)
		(layer "In4.Cu")
		(net 599)
	)
	(arc
		(start 185.78 131.96)
		(mid 186.076985 132.083015)
		(end 186.2 132.38)
		(width 0.09)
		(layer "In4.Cu")
		(net 599)
	)
	(arc
		(start 187.4 133.698695)
		(mid 187.452721 133.825974)
		(end 187.58 133.878695)
		(width 0.09)
		(layer "In4.Cu")
		(net 599)
	)
	(arc
		(start 187.76 132.38)
		(mid 187.883015 132.083015)
		(end 188.18 131.96)
		(width 0.09)
		(layer "In4.Cu")
		(net 599)
	)
	(arc
		(start 186.2 133.698671)
		(mid 186.252721 133.82595)
		(end 186.38 133.878671)
		(width 0.09)
		(layer "In4.Cu")
		(net 599)
	)
	(arc
		(start 186.38 133.878671)
		(mid 186.507279 133.82595)
		(end 186.56 133.698671)
		(width 0.09)
		(layer "In4.Cu")
		(net 599)
	)
	(segment
		(start 178.004 133.817)
		(end 178.4035 134.1415)
		(width 0.174)
		(layer "F.Cu")
		(net 600)
	)
	(via
		(at 178.4035 134.1415)
		(size 0.35)
		(drill 0.15)
		(layers "F.Cu" "B.Cu")
		(remove_unused_layers yes)
		(keep_end_layers yes)
		(zone_layer_connections)
		(net 600)
	)
	(via
		(at 192.5 131.55)
		(size 0.35)
		(drill 0.15)
		(layers "F.Cu" "B.Cu")
		(remove_unused_layers yes)
		(keep_end_layers yes)
		(zone_layer_connections)
		(net 600)
	)
	(segment
		(start 179.54 134.3305)
		(end 179.54 134.0605)
		(width 0.09)
		(layer "In2.Cu")
		(net 600)
	)
	(segment
		(start 178.7325 134.4705)
		(end 179.4 134.4705)
		(width 0.09)
		(layer "In2.Cu")
		(net 600)
	)
	(segment
		(start 183.35 134.3305)
		(end 183.35 134.2105)
		(width 0.09)
		(layer "In2.Cu")
		(net 600)
	)
	(segment
		(start 190.5 131.4625)
		(end 190.7325 131.23)
		(width 0.09)
		(layer "In2.Cu")
		(net 600)
	)
	(segment
		(start 192.18 131.87)
		(end 192.5 131.55)
		(width 0.09)
		(layer "In2.Cu")
		(net 600)
	)
	(segment
		(start 191.032549 131.23)
		(end 191.35 131.547451)
		(width 0.09)
		(layer "In2.Cu")
		(net 600)
	)
	(segment
		(start 179.82 134.0605)
		(end 179.82 134.3305)
		(width 0.09)
		(layer "In2.Cu")
		(net 600)
	)
	(segment
		(start 183.07 134.2105)
		(end 183.07 134.3305)
		(width 0.09)
		(layer "In2.Cu")
		(net 600)
	)
	(segment
		(start 190.7325 131.23)
		(end 191.032549 131.23)
		(width 0.09)
		(layer "In2.Cu")
		(net 600)
	)
	(segment
		(start 178.4035 134.1415)
		(end 178.7325 134.4705)
		(width 0.09)
		(layer "In2.Cu")
		(net 600)
	)
	(segment
		(start 190.5 132.5)
		(end 190.5 131.4625)
		(width 0.09)
		(layer "In2.Cu")
		(net 600)
	)
	(segment
		(start 191.567451 131.87)
		(end 192.18 131.87)
		(width 0.09)
		(layer "In2.Cu")
		(net 600)
	)
	(segment
		(start 185.55 134.75)
		(end 188.8 134.75)
		(width 0.09)
		(layer "In2.Cu")
		(net 600)
	)
	(segment
		(start 180.52 134.4705)
		(end 182.65 134.4705)
		(width 0.09)
		(layer "In2.Cu")
		(net 600)
	)
	(segment
		(start 190.15 132.85)
		(end 190.5 132.5)
		(width 0.09)
		(layer "In2.Cu")
		(net 600)
	)
	(segment
		(start 185.2705 134.4705)
		(end 185.55 134.75)
		(width 0.09)
		(layer "In2.Cu")
		(net 600)
	)
	(segment
		(start 183.63 134.2105)
		(end 183.63 134.3305)
		(width 0.09)
		(layer "In2.Cu")
		(net 600)
	)
	(segment
		(start 188.8 134.75)
		(end 190.15 133.4)
		(width 0.09)
		(layer "In2.Cu")
		(net 600)
	)
	(segment
		(start 180.38 134.0605)
		(end 180.38 134.3305)
		(width 0.09)
		(layer "In2.Cu")
		(net 600)
	)
	(segment
		(start 191.35 131.652549)
		(end 191.567451 131.87)
		(width 0.09)
		(layer "In2.Cu")
		(net 600)
	)
	(segment
		(start 180.1 134.3305)
		(end 180.1 134.0605)
		(width 0.09)
		(layer "In2.Cu")
		(net 600)
	)
	(segment
		(start 182.79 134.3305)
		(end 182.79 134.2105)
		(width 0.09)
		(layer "In2.Cu")
		(net 600)
	)
	(segment
		(start 183.77 134.4705)
		(end 185.2705 134.4705)
		(width 0.09)
		(layer "In2.Cu")
		(net 600)
	)
	(segment
		(start 191.35 131.547451)
		(end 191.35 131.652549)
		(width 0.09)
		(layer "In2.Cu")
		(net 600)
	)
	(segment
		(start 190.15 133.4)
		(end 190.15 132.85)
		(width 0.09)
		(layer "In2.Cu")
		(net 600)
	)
	(arc
		(start 182.79 134.2105)
		(mid 182.831005 134.111505)
		(end 182.93 134.0705)
		(width 0.09)
		(layer "In2.Cu")
		(net 600)
	)
	(arc
		(start 183.21 134.4705)
		(mid 183.308995 134.429495)
		(end 183.35 134.3305)
		(width 0.09)
		(layer "In2.Cu")
		(net 600)
	)
	(arc
		(start 183.63 134.3305)
		(mid 183.671005 134.429495)
		(end 183.77 134.4705)
		(width 0.09)
		(layer "In2.Cu")
		(net 600)
	)
	(arc
		(start 179.82 134.3305)
		(mid 179.861005 134.429495)
		(end 179.96 134.4705)
		(width 0.09)
		(layer "In2.Cu")
		(net 600)
	)
	(arc
		(start 179.4 134.4705)
		(mid 179.498995 134.429495)
		(end 179.54 134.3305)
		(width 0.09)
		(layer "In2.Cu")
		(net 600)
	)
	(arc
		(start 179.54 134.0605)
		(mid 179.581005 133.961505)
		(end 179.68 133.9205)
		(width 0.09)
		(layer "In2.Cu")
		(net 600)
	)
	(arc
		(start 183.35 134.2105)
		(mid 183.391005 134.111505)
		(end 183.49 134.0705)
		(width 0.09)
		(layer "In2.Cu")
		(net 600)
	)
	(arc
		(start 180.24 133.9205)
		(mid 180.338995 133.961505)
		(end 180.38 134.0605)
		(width 0.09)
		(layer "In2.Cu")
		(net 600)
	)
	(arc
		(start 182.65 134.4705)
		(mid 182.748995 134.429495)
		(end 182.79 134.3305)
		(width 0.09)
		(layer "In2.Cu")
		(net 600)
	)
	(arc
		(start 179.68 133.9205)
		(mid 179.778995 133.961505)
		(end 179.82 134.0605)
		(width 0.09)
		(layer "In2.Cu")
		(net 600)
	)
	(arc
		(start 183.49 134.0705)
		(mid 183.588995 134.111505)
		(end 183.63 134.2105)
		(width 0.09)
		(layer "In2.Cu")
		(net 600)
	)
	(arc
		(start 182.93 134.0705)
		(mid 183.028995 134.111505)
		(end 183.07 134.2105)
		(width 0.09)
		(layer "In2.Cu")
		(net 600)
	)
	(arc
		(start 180.1 134.0605)
		(mid 180.141005 133.961505)
		(end 180.24 133.9205)
		(width 0.09)
		(layer "In2.Cu")
		(net 600)
	)
	(arc
		(start 180.38 134.3305)
		(mid 180.421005 134.429495)
		(end 180.52 134.4705)
		(width 0.09)
		(layer "In2.Cu")
		(net 600)
	)
	(arc
		(start 179.96 134.4705)
		(mid 180.058995 134.429495)
		(end 180.1 134.3305)
		(width 0.09)
		(layer "In2.Cu")
		(net 600)
	)
	(arc
		(start 183.07 134.3305)
		(mid 183.111005 134.429495)
		(end 183.21 134.4705)
		(width 0.09)
		(layer "In2.Cu")
		(net 600)
	)
	(segment
		(start 178.004 133.167)
		(end 178.4035 132.8425)
		(width 0.174)
		(layer "F.Cu")
		(net 601)
	)
	(via
		(at 192.499 132.3)
		(size 0.35)
		(drill 0.15)
		(layers "F.Cu" "B.Cu")
		(remove_unused_layers yes)
		(keep_end_layers yes)
		(zone_layer_connections)
		(net 601)
	)
	(via
		(at 178.4035 132.8425)
		(size 0.35)
		(drill 0.15)
		(layers "F.Cu" "B.Cu")
		(remove_unused_layers yes)
		(keep_end_layers yes)
		(zone_layer_connections)
		(net 601)
	)
	(segment
		(start 185.35 131.55)
		(end 188.1 131.55)
		(width 0.09)
		(layer "In2.Cu")
		(net 601)
	)
	(segment
		(start 185.0325 131.8675)
		(end 185.35 131.55)
		(width 0.09)
		(layer "In2.Cu")
		(net 601)
	)
	(segment
		(start 192.9 131.488)
		(end 192.9 133.2)
		(width 0.09)
		(layer "In2.Cu")
		(net 601)
	)
	(segment
		(start 178.8 132.446)
		(end 178.8 132.05)
		(width 0.09)
		(layer "In2.Cu")
		(net 601)
	)
	(segment
		(start 178.9825 131.8675)
		(end 185.0325 131.8675)
		(width 0.09)
		(layer "In2.Cu")
		(net 601)
	)
	(segment
		(start 178.8 132.05)
		(end 178.9825 131.8675)
		(width 0.09)
		(layer "In2.Cu")
		(net 601)
	)
	(segment
		(start 192.15 133.275)
		(end 192.15 132.649)
		(width 0.09)
		(layer "In2.Cu")
		(net 601)
	)
	(segment
		(start 192.325 133.45)
		(end 192.15 133.275)
		(width 0.09)
		(layer "In2.Cu")
		(net 601)
	)
	(segment
		(start 192.65 133.45)
		(end 192.325 133.45)
		(width 0.09)
		(layer "In2.Cu")
		(net 601)
	)
	(segment
		(start 188.1 131.55)
		(end 188.624 131.026)
		(width 0.09)
		(layer "In2.Cu")
		(net 601)
	)
	(segment
		(start 178.4035 132.8425)
		(end 178.8 132.446)
		(width 0.09)
		(layer "In2.Cu")
		(net 601)
	)
	(segment
		(start 188.624 131.026)
		(end 192.438 131.026)
		(width 0.09)
		(layer "In2.Cu")
		(net 601)
	)
	(segment
		(start 192.9 133.2)
		(end 192.65 133.45)
		(width 0.09)
		(layer "In2.Cu")
		(net 601)
	)
	(segment
		(start 192.15 132.649)
		(end 192.499 132.3)
		(width 0.09)
		(layer "In2.Cu")
		(net 601)
	)
	(segment
		(start 192.438 131.026)
		(end 192.9 131.488)
		(width 0.09)
		(layer "In2.Cu")
		(net 601)
	)
	(segment
		(start 182.805 125.367)
		(end 183.2045 125.0425)
		(width 0.174)
		(layer "F.Cu")
		(net 602)
	)
	(via
		(at 183.2045 125.0425)
		(size 0.35)
		(drill 0.15)
		(layers "F.Cu" "B.Cu")
		(remove_unused_layers yes)
		(keep_end_layers yes)
		(zone_layer_connections)
		(net 602)
	)
	(via
		(at 191.7 128.3)
		(size 0.35)
		(drill 0.15)
		(layers "F.Cu" "B.Cu")
		(remove_unused_layers yes)
		(keep_end_layers yes)
		(zone_layer_connections)
		(net 602)
	)
	(segment
		(start 188.782226 125.452225)
		(end 188.782226 125.452226)
		(width 0.09)
		(layer "In4.Cu")
		(net 602)
	)
	(segment
		(start 187.605015 124.970029)
		(end 187.574985 124.970029)
		(width 0.09)
		(layer "In4.Cu")
		(net 602)
	)
	(segment
		(start 188.974452 125.344451)
		(end 188.89 125.344451)
		(width 0.09)
		(layer "In4.Cu")
		(net 602)
	)
	(segment
		(start 191.032549 127.18)
		(end 190.71168 127.18)
		(width 0.09)
		(layer "In4.Cu")
		(net 602)
	)
	(segment
		(start 190.232549 126.381)
		(end 189.91268 126.381)
		(width 0.09)
		(layer "In4.Cu")
		(net 602)
	)
	(segment
		(start 190.42 126.88832)
		(end 190.42 126.568451)
		(width 0.09)
		(layer "In4.Cu")
		(net 602)
	)
	(segment
		(start 185.607391 124.974781)
		(end 185.572609 124.974781)
		(width 0.09)
		(layer "In4.Cu")
		(net 602)
	)
	(segment
		(start 182.712248 125.56)
		(end 185.107391 125.56)
		(width 0.09)
		(layer "In4.Cu")
		(net 602)
	)
	(segment
		(start 185.22 125.32739)
		(end 185.22 125.447391)
		(width 0.09)
		(layer "In4.Cu")
		(net 602)
	)
	(segment
		(start 185.96 126.076419)
		(end 185.96 125.32739)
		(width 0.09)
		(layer "In4.Cu")
		(net 602)
	)
	(segment
		(start 191.7 128.3)
		(end 191.42 128.02)
		(width 0.09)
		(layer "In4.Cu")
		(net 602)
	)
	(segment
		(start 186.605015 124.970029)
		(end 186.574985 124.970029)
		(width 0.09)
		(layer "In4.Cu")
		(net 602)
	)
	(segment
		(start 189.082226 125.452226)
		(end 189.082226 125.452225)
		(width 0.09)
		(layer "In4.Cu")
		(net 602)
	)
	(segment
		(start 187.96 126.126433)
		(end 187.96 125.325014)
		(width 0.09)
		(layer "In4.Cu")
		(net 602)
	)
	(segment
		(start 182.457623 125.305375)
		(end 182.457623 125.036343)
		(width 0.09)
		(layer "In4.Cu")
		(net 602)
	)
	(segment
		(start 191.42 128.02)
		(end 191.42 127.88832)
		(width 0.09)
		(layer "In4.Cu")
		(net 602)
	)
	(segment
		(start 182.9995 124.8375)
		(end 183.2045 125.0425)
		(width 0.09)
		(layer "In4.Cu")
		(net 602)
	)
	(segment
		(start 188.22 125.93)
		(end 188.22 126.126433)
		(width 0.09)
		(layer "In4.Cu")
		(net 602)
	)
	(segment
		(start 189.410549 125.56)
		(end 189.19 125.56)
		(width 0.09)
		(layer "In4.Cu")
		(net 602)
	)
	(segment
		(start 187.22 125.325014)
		(end 187.22 126.076419)
		(width 0.09)
		(layer "In4.Cu")
		(net 602)
	)
	(segment
		(start 186.22 125.325014)
		(end 186.22 126.076419)
		(width 0.09)
		(layer "In4.Cu")
		(net 602)
	)
	(segment
		(start 182.712248 125.56)
		(end 182.457623 125.305375)
		(width 0.09)
		(layer "In4.Cu")
		(net 602)
	)
	(segment
		(start 188.674452 125.56)
		(end 188.59 125.56)
		(width 0.09)
		(layer "In4.Cu")
		(net 602)
	)
	(segment
		(start 182.656466 124.8375)
		(end 182.9995 124.8375)
		(width 0.09)
		(layer "In4.Cu")
		(net 602)
	)
	(segment
		(start 191.192115 127.660435)
		(end 191.22 127.632549)
		(width 0.09)
		(layer "In4.Cu")
		(net 602)
	)
	(segment
		(start 191.42 127.88832)
		(end 191.192115 127.660435)
		(width 0.09)
		(layer "In4.Cu")
		(net 602)
	)
	(segment
		(start 191.22 127.367451)
		(end 191.032549 127.18)
		(width 0.09)
		(layer "In4.Cu")
		(net 602)
	)
	(segment
		(start 191.22 127.632549)
		(end 191.22 127.367451)
		(width 0.09)
		(layer "In4.Cu")
		(net 602)
	)
	(segment
		(start 189.619 126.08732)
		(end 189.619 125.768451)
		(width 0.09)
		(layer "In4.Cu")
		(net 602)
	)
	(segment
		(start 186.96 126.076419)
		(end 186.96 125.325014)
		(width 0.09)
		(layer "In4.Cu")
		(net 602)
	)
	(segment
		(start 190.71168 127.18)
		(end 190.42 126.88832)
		(width 0.09)
		(layer "In4.Cu")
		(net 602)
	)
	(segment
		(start 182.457623 125.036343)
		(end 182.656466 124.8375)
		(width 0.09)
		(layer "In4.Cu")
		(net 602)
	)
	(segment
		(start 190.42 126.568451)
		(end 190.232549 126.381)
		(width 0.09)
		(layer "In4.Cu")
		(net 602)
	)
	(segment
		(start 189.619 125.768451)
		(end 189.410549 125.56)
		(width 0.09)
		(layer "In4.Cu")
		(net 602)
	)
	(segment
		(start 189.91268 126.381)
		(end 189.619 126.08732)
		(width 0.09)
		(layer "In4.Cu")
		(net 602)
	)
	(arc
		(start 188.22 126.126433)
		(mid 188.181924 126.218357)
		(end 188.09 126.256433)
		(width 0.09)
		(layer "In4.Cu")
		(net 602)
	)
	(arc
		(start 188.89 125.344451)
		(mid 188.813792 125.376017)
		(end 188.782226 125.452225)
		(width 0.09)
		(layer "In4.Cu")
		(net 602)
	)
	(arc
		(start 186.09 126.206419)
		(mid 185.998076 126.168343)
		(end 185.96 126.076419)
		(width 0.09)
		(layer "In4.Cu")
		(net 602)
	)
	(arc
		(start 186.574985 124.970029)
		(mid 186.323973 125.074002)
		(end 186.22 125.325014)
		(width 0.09)
		(layer "In4.Cu")
		(net 602)
	)
	(arc
		(start 189.19 125.56)
		(mid 189.113792 125.528434)
		(end 189.082226 125.452226)
		(width 0.09)
		(layer "In4.Cu")
		(net 602)
	)
	(arc
		(start 186.96 125.325014)
		(mid 186.856027 125.074002)
		(end 186.605015 124.970029)
		(width 0.09)
		(layer "In4.Cu")
		(net 602)
	)
	(arc
		(start 188.782226 125.452226)
		(mid 188.75066 125.528434)
		(end 188.674452 125.56)
		(width 0.09)
		(layer "In4.Cu")
		(net 602)
	)
	(arc
		(start 186.22 126.076419)
		(mid 186.181924 126.168343)
		(end 186.09 126.206419)
		(width 0.09)
		(layer "In4.Cu")
		(net 602)
	)
	(arc
		(start 187.09 126.206419)
		(mid 186.998076 126.168343)
		(end 186.96 126.076419)
		(width 0.09)
		(layer "In4.Cu")
		(net 602)
	)
	(arc
		(start 185.96 125.32739)
		(mid 185.856723 125.078058)
		(end 185.607391 124.974781)
		(width 0.09)
		(layer "In4.Cu")
		(net 602)
	)
	(arc
		(start 187.574985 124.970029)
		(mid 187.323973 125.074002)
		(end 187.22 125.325014)
		(width 0.09)
		(layer "In4.Cu")
		(net 602)
	)
	(arc
		(start 187.96 125.325014)
		(mid 187.856027 125.074002)
		(end 187.605015 124.970029)
		(width 0.09)
		(layer "In4.Cu")
		(net 602)
	)
	(arc
		(start 185.572609 124.974781)
		(mid 185.323277 125.078058)
		(end 185.22 125.32739)
		(width 0.09)
		(layer "In4.Cu")
		(net 602)
	)
	(arc
		(start 187.22 126.076419)
		(mid 187.181924 126.168343)
		(end 187.09 126.206419)
		(width 0.09)
		(layer "In4.Cu")
		(net 602)
	)
	(arc
		(start 188.09 126.256433)
		(mid 187.998076 126.218357)
		(end 187.96 126.126433)
		(width 0.09)
		(layer "In4.Cu")
		(net 602)
	)
	(arc
		(start 188.59 125.56)
		(mid 188.32837 125.66837)
		(end 188.22 125.93)
		(width 0.09)
		(layer "In4.Cu")
		(net 602)
	)
	(arc
		(start 185.22 125.447391)
		(mid 185.187018 125.527018)
		(end 185.107391 125.56)
		(width 0.09)
		(layer "In4.Cu")
		(net 602)
	)
	(arc
		(start 189.082226 125.452225)
		(mid 189.05066 125.376017)
		(end 188.974452 125.344451)
		(width 0.09)
		(layer "In4.Cu")
		(net 602)
	)
	(segment
		(start 183.604 124.066)
		(end 184.0035 123.7415)
		(width 0.174)
		(layer "F.Cu")
		(net 603)
	)
	(via
		(at 184.0035 123.7415)
		(size 0.35)
		(drill 0.15)
		(layers "F.Cu" "B.Cu")
		(remove_unused_layers yes)
		(keep_end_layers yes)
		(zone_layer_connections)
		(net 603)
	)
	(via
		(at 191.7 129.1)
		(size 0.35)
		(drill 0.15)
		(layers "F.Cu" "B.Cu")
		(remove_unused_layers yes)
		(keep_end_layers yes)
		(zone_layer_connections)
		(net 603)
	)
	(segment
		(start 192.819 127.499)
		(end 192.819 128.432549)
		(width 0.09)
		(layer "In4.Cu")
		(net 603)
	)
	(segment
		(start 187.2 123.71)
		(end 187.2 123.56)
		(width 0.09)
		(layer "In4.Cu")
		(net 603)
	)
	(segment
		(start 192.106506 126.434265)
		(end 192.106506 126.434264)
		(width 0.09)
		(layer "In4.Cu")
		(net 603)
	)
	(segment
		(start 184.926049 124.0725)
		(end 185.138549 123.86)
		(width 0.09)
		(layer "In4.Cu")
		(net 603)
	)
	(segment
		(start 185.138549 123.86)
		(end 185.25 123.86)
		(width 0.09)
		(layer "In4.Cu")
		(net 603)
	)
	(segment
		(start 186.6 123.71)
		(end 186.6 123.56)
		(width 0.09)
		(layer "In4.Cu")
		(net 603)
	)
	(segment
		(start 191.542132 126.01)
		(end 191.789215 125.762918)
		(width 0.09)
		(layer "In4.Cu")
		(net 603)
	)
	(segment
		(start 188.85 123.86)
		(end 189.311549 123.86)
		(width 0.09)
		(layer "In4.Cu")
		(net 603)
	)
	(segment
		(start 192.001347 125.97505)
		(end 191.754263 126.222131)
		(width 0.09)
		(layer "In4.Cu")
		(net 603)
	)
	(segment
		(start 189.311549 123.86)
		(end 189.619 124.167451)
		(width 0.09)
		(layer "In4.Cu")
		(net 603)
	)
	(segment
		(start 191.542133 126.009999)
		(end 191.542132 126.01)
		(width 0.09)
		(layer "In4.Cu")
		(net 603)
	)
	(segment
		(start 187.8 123.71)
		(end 187.8 123.56)
		(width 0.09)
		(layer "In4.Cu")
		(net 603)
	)
	(segment
		(start 192.18 128.62)
		(end 191.7 129.1)
		(width 0.09)
		(layer "In4.Cu")
		(net 603)
	)
	(segment
		(start 184.3345 124.0725)
		(end 184.926049 124.0725)
		(width 0.09)
		(layer "In4.Cu")
		(net 603)
	)
	(segment
		(start 192.142516 126.822516)
		(end 192.819 127.499)
		(width 0.09)
		(layer "In4.Cu")
		(net 603)
	)
	(segment
		(start 188.1 123.56)
		(end 188.1 123.71)
		(width 0.09)
		(layer "In4.Cu")
		(net 603)
	)
	(segment
		(start 191.754263 126.434263)
		(end 191.754264 126.434264)
		(width 0.09)
		(layer "In4.Cu")
		(net 603)
	)
	(segment
		(start 185.7 123.56)
		(end 185.7 123.71)
		(width 0.09)
		(layer "In4.Cu")
		(net 603)
	)
	(segment
		(start 192.001346 125.975051)
		(end 192.001347 125.97505)
		(width 0.09)
		(layer "In4.Cu")
		(net 603)
	)
	(segment
		(start 190.871549 124.62)
		(end 191.28 125.028451)
		(width 0.09)
		(layer "In4.Cu")
		(net 603)
	)
	(segment
		(start 192.631549 128.62)
		(end 192.18 128.62)
		(width 0.09)
		(layer "In4.Cu")
		(net 603)
	)
	(segment
		(start 186.3 123.56)
		(end 186.3 123.71)
		(width 0.09)
		(layer "In4.Cu")
		(net 603)
	)
	(segment
		(start 189.806451 124.62)
		(end 190.871549 124.62)
		(width 0.09)
		(layer "In4.Cu")
		(net 603)
	)
	(segment
		(start 188.7 123.56)
		(end 188.7 123.71)
		(width 0.09)
		(layer "In4.Cu")
		(net 603)
	)
	(segment
		(start 189.619 124.432549)
		(end 189.806451 124.62)
		(width 0.09)
		(layer "In4.Cu")
		(net 603)
	)
	(segment
		(start 192.819 128.432549)
		(end 192.631549 128.62)
		(width 0.09)
		(layer "In4.Cu")
		(net 603)
	)
	(segment
		(start 186.9 123.56)
		(end 186.9 123.71)
		(width 0.09)
		(layer "In4.Cu")
		(net 603)
	)
	(segment
		(start 192.106506 126.434264)
		(end 192.142516 126.470274)
		(width 0.09)
		(layer "In4.Cu")
		(net 603)
	)
	(segment
		(start 191.28 125.028451)
		(end 191.28 125.96)
		(width 0.09)
		(layer "In4.Cu")
		(net 603)
	)
	(segment
		(start 188.4 123.71)
		(end 188.4 123.56)
		(width 0.09)
		(layer "In4.Cu")
		(net 603)
	)
	(segment
		(start 184.0035 123.7415)
		(end 184.3345 124.0725)
		(width 0.09)
		(layer "In4.Cu")
		(net 603)
	)
	(segment
		(start 191.28 125.96)
		(end 191.33 126.01)
		(width 0.09)
		(layer "In4.Cu")
		(net 603)
	)
	(segment
		(start 186 123.71)
		(end 186 123.56)
		(width 0.09)
		(layer "In4.Cu")
		(net 603)
	)
	(segment
		(start 187.5 123.56)
		(end 187.5 123.71)
		(width 0.09)
		(layer "In4.Cu")
		(net 603)
	)
	(segment
		(start 191.930385 126.434263)
		(end 191.930386 126.434265)
		(width 0.09)
		(layer "In4.Cu")
		(net 603)
	)
	(segment
		(start 189.619 124.167451)
		(end 189.619 124.432549)
		(width 0.09)
		(layer "In4.Cu")
		(net 603)
	)
	(segment
		(start 185.4 123.71)
		(end 185.4 123.56)
		(width 0.09)
		(layer "In4.Cu")
		(net 603)
	)
	(arc
		(start 186.6 123.56)
		(mid 186.643934 123.453934)
		(end 186.75 123.41)
		(width 0.09)
		(layer "In4.Cu")
		(net 603)
	)
	(arc
		(start 191.930386 126.434265)
		(mid 192.018446 126.397789)
		(end 192.106506 126.434265)
		(width 0.09)
		(layer "In4.Cu")
		(net 603)
	)
	(arc
		(start 187.65 123.86)
		(mid 187.756066 123.816066)
		(end 187.8 123.71)
		(width 0.09)
		(layer "In4.Cu")
		(net 603)
	)
	(arc
		(start 188.4 123.56)
		(mid 188.443934 123.453934)
		(end 188.55 123.41)
		(width 0.09)
		(layer "In4.Cu")
		(net 603)
	)
	(arc
		(start 188.55 123.41)
		(mid 188.656066 123.453934)
		(end 188.7 123.56)
		(width 0.09)
		(layer "In4.Cu")
		(net 603)
	)
	(arc
		(start 192.142516 126.470274)
		(mid 192.178993 126.558336)
		(end 192.142516 126.646396)
		(width 0.09)
		(layer "In4.Cu")
		(net 603)
	)
	(arc
		(start 185.25 123.86)
		(mid 185.356066 123.816066)
		(end 185.4 123.71)
		(width 0.09)
		(layer "In4.Cu")
		(net 603)
	)
	(arc
		(start 185.7 123.71)
		(mid 185.743934 123.816066)
		(end 185.85 123.86)
		(width 0.09)
		(layer "In4.Cu")
		(net 603)
	)
	(arc
		(start 191.789215 125.762918)
		(mid 191.895281 125.718984)
		(end 192.001347 125.762918)
		(width 0.09)
		(layer "In4.Cu")
		(net 603)
	)
	(arc
		(start 186.75 123.41)
		(mid 186.856066 123.453934)
		(end 186.9 123.56)
		(width 0.09)
		(layer "In4.Cu")
		(net 603)
	)
	(arc
		(start 185.85 123.86)
		(mid 185.956066 123.816066)
		(end 186 123.71)
		(width 0.09)
		(layer "In4.Cu")
		(net 603)
	)
	(arc
		(start 192.001347 125.762918)
		(mid 192.04528 125.868984)
		(end 192.001346 125.975051)
		(width 0.09)
		(layer "In4.Cu")
		(net 603)
	)
	(arc
		(start 187.95 123.41)
		(mid 188.056066 123.453934)
		(end 188.1 123.56)
		(width 0.09)
		(layer "In4.Cu")
		(net 603)
	)
	(arc
		(start 187.5 123.71)
		(mid 187.543934 123.816066)
		(end 187.65 123.86)
		(width 0.09)
		(layer "In4.Cu")
		(net 603)
	)
	(arc
		(start 186.9 123.71)
		(mid 186.943934 123.816066)
		(end 187.05 123.86)
		(width 0.09)
		(layer "In4.Cu")
		(net 603)
	)
	(arc
		(start 185.55 123.41)
		(mid 185.656066 123.453934)
		(end 185.7 123.56)
		(width 0.09)
		(layer "In4.Cu")
		(net 603)
	)
	(arc
		(start 185.4 123.56)
		(mid 185.443934 123.453934)
		(end 185.55 123.41)
		(width 0.09)
		(layer "In4.Cu")
		(net 603)
	)
	(arc
		(start 186 123.56)
		(mid 186.043934 123.453934)
		(end 186.15 123.41)
		(width 0.09)
		(layer "In4.Cu")
		(net 603)
	)
	(arc
		(start 186.45 123.86)
		(mid 186.556066 123.816066)
		(end 186.6 123.71)
		(width 0.09)
		(layer "In4.Cu")
		(net 603)
	)
	(arc
		(start 187.05 123.86)
		(mid 187.156066 123.816066)
		(end 187.2 123.71)
		(width 0.09)
		(layer "In4.Cu")
		(net 603)
	)
	(arc
		(start 191.754263 126.222131)
		(mid 191.710329 126.328197)
		(end 191.754263 126.434263)
		(width 0.09)
		(layer "In4.Cu")
		(net 603)
	)
	(arc
		(start 188.7 123.71)
		(mid 188.743934 123.816066)
		(end 188.85 123.86)
		(width 0.09)
		(layer "In4.Cu")
		(net 603)
	)
	(arc
		(start 191.33 126.01)
		(mid 191.436068 126.053935)
		(end 191.542133 126.009999)
		(width 0.09)
		(layer "In4.Cu")
		(net 603)
	)
	(arc
		(start 191.754264 126.434264)
		(mid 191.842325 126.470739)
		(end 191.930385 126.434263)
		(width 0.09)
		(layer "In4.Cu")
		(net 603)
	)
	(arc
		(start 192.142516 126.646396)
		(mid 192.10604 126.734456)
		(end 192.142516 126.822516)
		(width 0.09)
		(layer "In4.Cu")
		(net 603)
	)
	(arc
		(start 188.1 123.71)
		(mid 188.143934 123.816066)
		(end 188.25 123.86)
		(width 0.09)
		(layer "In4.Cu")
		(net 603)
	)
	(arc
		(start 188.25 123.86)
		(mid 188.356066 123.816066)
		(end 188.4 123.71)
		(width 0.09)
		(layer "In4.Cu")
		(net 603)
	)
	(arc
		(start 187.8 123.56)
		(mid 187.843934 123.453934)
		(end 187.95 123.41)
		(width 0.09)
		(layer "In4.Cu")
		(net 603)
	)
	(arc
		(start 186.3 123.71)
		(mid 186.343934 123.816066)
		(end 186.45 123.86)
		(width 0.09)
		(layer "In4.Cu")
		(net 603)
	)
	(arc
		(start 186.15 123.41)
		(mid 186.256066 123.453934)
		(end 186.3 123.56)
		(width 0.09)
		(layer "In4.Cu")
		(net 603)
	)
	(arc
		(start 187.2 123.56)
		(mid 187.243934 123.453934)
		(end 187.35 123.41)
		(width 0.09)
		(layer "In4.Cu")
		(net 603)
	)
	(arc
		(start 187.35 123.41)
		(mid 187.456066 123.453934)
		(end 187.5 123.56)
		(width 0.09)
		(layer "In4.Cu")
		(net 603)
	)
	(segment
		(start 183.604 123.416)
		(end 184.0035 123.0915)
		(width 0.174)
		(layer "F.Cu")
		(net 604)
	)
	(via
		(at 184.0035 123.0915)
		(size 0.35)
		(drill 0.15)
		(layers "F.Cu" "B.Cu")
		(remove_unused_layers yes)
		(keep_end_layers yes)
		(zone_layer_connections)
		(net 604)
	)
	(via
		(at 191.7 129.85)
		(size 0.35)
		(drill 0.15)
		(layers "F.Cu" "B.Cu")
		(remove_unused_layers yes)
		(keep_end_layers yes)
		(zone_layer_connections)
		(net 604)
	)
	(segment
		(start 190.994263 123.644263)
		(end 193.73 126.38)
		(width 0.09)
		(layer "In4.Cu")
		(net 604)
	)
	(segment
		(start 190.711422 123.714973)
		(end 190.782131 123.644263)
		(width 0.09)
		(layer "In4.Cu")
		(net 604)
	)
	(segment
		(start 184.0035 123.0915)
		(end 188.99 123.0915)
		(width 0.09)
		(layer "In4.Cu")
		(net 604)
	)
	(segment
		(start 190.04 123.3915)
		(end 190.04 123.2415)
		(width 0.09)
		(layer "In4.Cu")
		(net 604)
	)
	(segment
		(start 193.73 126.38)
		(end 193.73 128.59)
		(width 0.09)
		(layer "In4.Cu")
		(net 604)
	)
	(segment
		(start 189.44 123.3915)
		(end 189.44 123.2415)
		(width 0.09)
		(layer "In4.Cu")
		(net 604)
	)
	(segment
		(start 189.74 123.2415)
		(end 189.74 123.3915)
		(width 0.09)
		(layer "In4.Cu")
		(net 604)
	)
	(segment
		(start 190.19 123.0915)
		(end 190.4415 123.0915)
		(width 0.09)
		(layer "In4.Cu")
		(net 604)
	)
	(segment
		(start 192.1 129.45)
		(end 191.7 129.85)
		(width 0.09)
		(layer "In4.Cu")
		(net 604)
	)
	(segment
		(start 193.73 128.59)
		(end 192.87 129.45)
		(width 0.09)
		(layer "In4.Cu")
		(net 604)
	)
	(segment
		(start 192.87 129.45)
		(end 192.1 129.45)
		(width 0.09)
		(layer "In4.Cu")
		(net 604)
	)
	(segment
		(start 190.4415 123.0915)
		(end 190.57 123.22)
		(width 0.09)
		(layer "In4.Cu")
		(net 604)
	)
	(segment
		(start 190.569999 123.432133)
		(end 190.499289 123.502842)
		(width 0.09)
		(layer "In4.Cu")
		(net 604)
	)
	(segment
		(start 189.14 123.2415)
		(end 189.14 123.3915)
		(width 0.09)
		(layer "In4.Cu")
		(net 604)
	)
	(arc
		(start 190.499289 123.502842)
		(mid 190.455355 123.608908)
		(end 190.499289 123.714974)
		(width 0.09)
		(layer "In4.Cu")
		(net 604)
	)
	(arc
		(start 189.29 123.5415)
		(mid 189.396066 123.497566)
		(end 189.44 123.3915)
		(width 0.09)
		(layer "In4.Cu")
		(net 604)
	)
	(arc
		(start 189.59 123.0915)
		(mid 189.696066 123.135434)
		(end 189.74 123.2415)
		(width 0.09)
		(layer "In4.Cu")
		(net 604)
	)
	(arc
		(start 190.04 123.2415)
		(mid 190.083934 123.135434)
		(end 190.19 123.0915)
		(width 0.09)
		(layer "In4.Cu")
		(net 604)
	)
	(arc
		(start 190.782131 123.644263)
		(mid 190.888197 123.600329)
		(end 190.994263 123.644263)
		(width 0.09)
		(layer "In4.Cu")
		(net 604)
	)
	(arc
		(start 190.499289 123.714974)
		(mid 190.605356 123.758908)
		(end 190.711422 123.714973)
		(width 0.09)
		(layer "In4.Cu")
		(net 604)
	)
	(arc
		(start 188.99 123.0915)
		(mid 189.096066 123.135434)
		(end 189.14 123.2415)
		(width 0.09)
		(layer "In4.Cu")
		(net 604)
	)
	(arc
		(start 189.44 123.2415)
		(mid 189.483934 123.135434)
		(end 189.59 123.0915)
		(width 0.09)
		(layer "In4.Cu")
		(net 604)
	)
	(arc
		(start 190.57 123.22)
		(mid 190.613934 123.326067)
		(end 190.569999 123.432133)
		(width 0.09)
		(layer "In4.Cu")
		(net 604)
	)
	(arc
		(start 189.14 123.3915)
		(mid 189.183934 123.497566)
		(end 189.29 123.5415)
		(width 0.09)
		(layer "In4.Cu")
		(net 604)
	)
	(arc
		(start 189.89 123.5415)
		(mid 189.996066 123.497566)
		(end 190.04 123.3915)
		(width 0.09)
		(layer "In4.Cu")
		(net 604)
	)
	(arc
		(start 189.74 123.3915)
		(mid 189.783934 123.497566)
		(end 189.89 123.5415)
		(width 0.09)
		(layer "In4.Cu")
		(net 604)
	)
	(segment
		(start 176.404 135.117)
		(end 176.0045 135.4415)
		(width 0.174)
		(layer "F.Cu")
		(net 605)
	)
	(via
		(at 176.0045 135.4415)
		(size 0.35)
		(drill 0.15)
		(layers "F.Cu" "B.Cu")
		(remove_unused_layers yes)
		(keep_end_layers yes)
		(zone_layer_connections)
		(net 605)
	)
	(via
		(at 191.7 130.701)
		(size 0.35)
		(drill 0.15)
		(layers "F.Cu" "B.Cu")
		(remove_unused_layers yes)
		(keep_end_layers yes)
		(zone_layer_connections)
		(net 605)
	)
	(segment
		(start 175.6915 135.4415)
		(end 176.0045 135.4415)
		(width 0.09)
		(layer "In2.Cu")
		(net 605)
	)
	(segment
		(start 188.7665 129.9165)
		(end 177.0835 129.9165)
		(width 0.09)
		(layer "In2.Cu")
		(net 605)
	)
	(segment
		(start 190.676 130.176)
		(end 189.026 130.176)
		(width 0.09)
		(layer "In2.Cu")
		(net 605)
	)
	(segment
		(start 191.7 130.701)
		(end 191.375 130.376)
		(width 0.09)
		(layer "In2.Cu")
		(net 605)
	)
	(segment
		(start 191.375 130.376)
		(end 190.876 130.376)
		(width 0.09)
		(layer "In2.Cu")
		(net 605)
	)
	(segment
		(start 175.6 134.18)
		(end 175.425 134.355)
		(width 0.09)
		(layer "In2.Cu")
		(net 605)
	)
	(segment
		(start 175.83638 130.6)
		(end 175.6 130.83638)
		(width 0.09)
		(layer "In2.Cu")
		(net 605)
	)
	(segment
		(start 175.425 134.355)
		(end 175.425 135.175)
		(width 0.09)
		(layer "In2.Cu")
		(net 605)
	)
	(segment
		(start 189.026 130.176)
		(end 188.7665 129.9165)
		(width 0.09)
		(layer "In2.Cu")
		(net 605)
	)
	(segment
		(start 177.0835 129.9165)
		(end 176.4 130.6)
		(width 0.09)
		(layer "In2.Cu")
		(net 605)
	)
	(segment
		(start 190.876 130.376)
		(end 190.676 130.176)
		(width 0.09)
		(layer "In2.Cu")
		(net 605)
	)
	(segment
		(start 175.425 135.175)
		(end 175.6915 135.4415)
		(width 0.09)
		(layer "In2.Cu")
		(net 605)
	)
	(segment
		(start 176.4 130.6)
		(end 175.83638 130.6)
		(width 0.09)
		(layer "In2.Cu")
		(net 605)
	)
	(segment
		(start 175.6 130.83638)
		(end 175.6 134.18)
		(width 0.09)
		(layer "In2.Cu")
		(net 605)
	)
	(segment
		(start 178.004 135.766)
		(end 178.4035 136.0905)
		(width 0.174)
		(layer "F.Cu")
		(net 606)
	)
	(via
		(at 178.4035 136.0905)
		(size 0.35)
		(drill 0.15)
		(layers "F.Cu" "B.Cu")
		(remove_unused_layers yes)
		(keep_end_layers yes)
		(zone_layer_connections)
		(net 606)
	)
	(via
		(at 191.7 132.3)
		(size 0.35)
		(drill 0.15)
		(layers "F.Cu" "B.Cu")
		(remove_unused_layers yes)
		(keep_end_layers yes)
		(zone_layer_connections)
		(net 606)
	)
	(segment
		(start 184.365 137.035)
		(end 184.365 136.861251)
		(width 0.09)
		(layer "In2.Cu")
		(net 606)
	)
	(segment
		(start 187.4 135.9)
		(end 186.1 137.2)
		(width 0.09)
		(layer "In2.Cu")
		(net 606)
	)
	(segment
		(start 191.7 134.078554)
		(end 189.878554 135.9)
		(width 0.09)
		(layer "In2.Cu")
		(net 606)
	)
	(segment
		(start 177.95 137.2)
		(end 183.87 137.2)
		(width 0.09)
		(layer "In2.Cu")
		(net 606)
	)
	(segment
		(start 191.7 132.3)
		(end 191.7 134.078554)
		(width 0.09)
		(layer "In2.Cu")
		(net 606)
	)
	(segment
		(start 184.035 136.861251)
		(end 184.035 137.035)
		(width 0.09)
		(layer "In2.Cu")
		(net 606)
	)
	(segment
		(start 177.55 136.4)
		(end 177.8595 136.0905)
		(width 0.09)
		(layer "In2.Cu")
		(net 606)
	)
	(segment
		(start 185.025 137.035)
		(end 185.025 136.761251)
		(width 0.09)
		(layer "In2.Cu")
		(net 606)
	)
	(segment
		(start 189.878554 135.9)
		(end 187.4 135.9)
		(width 0.09)
		(layer "In2.Cu")
		(net 606)
	)
	(segment
		(start 184.695 136.761251)
		(end 184.695 137.035)
		(width 0.09)
		(layer "In2.Cu")
		(net 606)
	)
	(segment
		(start 186.1 137.2)
		(end 185.85 137.2)
		(width 0.09)
		(layer "In2.Cu")
		(net 606)
	)
	(segment
		(start 185.685 137.035)
		(end 185.685 136.761251)
		(width 0.09)
		(layer "In2.Cu")
		(net 606)
	)
	(segment
		(start 177.95 137.2)
		(end 177.55 136.8)
		(width 0.09)
		(layer "In2.Cu")
		(net 606)
	)
	(segment
		(start 185.355 136.761251)
		(end 185.355 137.035)
		(width 0.09)
		(layer "In2.Cu")
		(net 606)
	)
	(segment
		(start 177.55 136.8)
		(end 177.55 136.4)
		(width 0.09)
		(layer "In2.Cu")
		(net 606)
	)
	(segment
		(start 177.8595 136.0905)
		(end 178.4035 136.0905)
		(width 0.09)
		(layer "In2.Cu")
		(net 606)
	)
	(arc
		(start 185.52 136.596251)
		(mid 185.403327 136.644578)
		(end 185.355 136.761251)
		(width 0.09)
		(layer "In2.Cu")
		(net 606)
	)
	(arc
		(start 184.2 136.696251)
		(mid 184.083327 136.744578)
		(end 184.035 136.861251)
		(width 0.09)
		(layer "In2.Cu")
		(net 606)
	)
	(arc
		(start 185.19 137.2)
		(mid 185.073327 137.151673)
		(end 185.025 137.035)
		(width 0.09)
		(layer "In2.Cu")
		(net 606)
	)
	(arc
		(start 184.86 136.596251)
		(mid 184.743327 136.644578)
		(end 184.695 136.761251)
		(width 0.09)
		(layer "In2.Cu")
		(net 606)
	)
	(arc
		(start 184.365 136.861251)
		(mid 184.316673 136.744578)
		(end 184.2 136.696251)
		(width 0.09)
		(layer "In2.Cu")
		(net 606)
	)
	(arc
		(start 185.85 137.2)
		(mid 185.733327 137.151673)
		(end 185.685 137.035)
		(width 0.09)
		(layer "In2.Cu")
		(net 606)
	)
	(arc
		(start 184.035 137.035)
		(mid 183.986673 137.151673)
		(end 183.87 137.2)
		(width 0.09)
		(layer "In2.Cu")
		(net 606)
	)
	(arc
		(start 184.53 137.2)
		(mid 184.413327 137.151673)
		(end 184.365 137.035)
		(width 0.09)
		(layer "In2.Cu")
		(net 606)
	)
	(arc
		(start 185.025 136.761251)
		(mid 184.976673 136.644578)
		(end 184.86 136.596251)
		(width 0.09)
		(layer "In2.Cu")
		(net 606)
	)
	(arc
		(start 185.355 137.035)
		(mid 185.306673 137.151673)
		(end 185.19 137.2)
		(width 0.09)
		(layer "In2.Cu")
		(net 606)
	)
	(arc
		(start 185.685 136.761251)
		(mid 185.636673 136.644578)
		(end 185.52 136.596251)
		(width 0.09)
		(layer "In2.Cu")
		(net 606)
	)
	(arc
		(start 184.695 137.035)
		(mid 184.646673 137.151673)
		(end 184.53 137.2)
		(width 0.09)
		(layer "In2.Cu")
		(net 606)
	)
	(segment
		(start 176.404 125.367)
		(end 176.006 124.969)
		(width 0.174)
		(layer "F.Cu")
		(net 607)
	)
	(segment
		(start 176.006 124.969)
		(end 175.931 124.969)
		(width 0.174)
		(layer "F.Cu")
		(net 607)
	)
	(via
		(at 190.9 124.3)
		(size 0.35)
		(drill 0.15)
		(layers "F.Cu" "B.Cu")
		(remove_unused_layers yes)
		(keep_end_layers yes)
		(zone_layer_connections)
		(net 607)
	)
	(via
		(at 175.931 124.969)
		(size 0.35)
		(drill 0.15)
		(layers "F.Cu" "B.Cu")
		(remove_unused_layers yes)
		(keep_end_layers yes)
		(zone_layer_connections)
		(net 607)
	)
	(segment
		(start 188.972142 123.12283)
		(end 188.972143 123.122831)
		(width 0.09)
		(layer "In2.Cu")
		(net 607)
	)
	(segment
		(start 187.075 121.05)
		(end 188.045294 121.05)
		(width 0.09)
		(layer "In2.Cu")
		(net 607)
	)
	(segment
		(start 189.21963 123.122831)
		(end 189.545133 122.797327)
		(width 0.09)
		(layer "In2.Cu")
		(net 607)
	)
	(segment
		(start 189.297647 122.54984)
		(end 188.972143 122.875343)
		(width 0.09)
		(layer "In2.Cu")
		(net 607)
	)
	(segment
		(start 189.21963 123.12283)
		(end 189.21963 123.122831)
		(width 0.09)
		(layer "In2.Cu")
		(net 607)
	)
	(segment
		(start 189.79262 122.797326)
		(end 190.9 123.904706)
		(width 0.09)
		(layer "In2.Cu")
		(net 607)
	)
	(segment
		(start 189.297646 122.54984)
		(end 189.297647 122.54984)
		(width 0.09)
		(layer "In2.Cu")
		(net 607)
	)
	(segment
		(start 185.95 121.375)
		(end 185.95 121.275)
		(width 0.09)
		(layer "In2.Cu")
		(net 607)
	)
	(segment
		(start 177.2 121.05)
		(end 185.275 121.05)
		(width 0.09)
		(layer "In2.Cu")
		(net 607)
	)
	(segment
		(start 186.85 121.375)
		(end 186.85 121.275)
		(width 0.09)
		(layer "In2.Cu")
		(net 607)
	)
	(segment
		(start 175.931 124.969)
		(end 175.5295 124.5675)
		(width 0.09)
		(layer "In2.Cu")
		(net 607)
	)
	(segment
		(start 186.4 121.275)
		(end 186.4 121.375)
		(width 0.09)
		(layer "In2.Cu")
		(net 607)
	)
	(segment
		(start 175.5295 124.5675)
		(end 175.5295 122.7205)
		(width 0.09)
		(layer "In2.Cu")
		(net 607)
	)
	(segment
		(start 188.045294 121.05)
		(end 189.297647 122.302353)
		(width 0.09)
		(layer "In2.Cu")
		(net 607)
	)
	(segment
		(start 190.9 123.904706)
		(end 190.9 124.3)
		(width 0.09)
		(layer "In2.Cu")
		(net 607)
	)
	(segment
		(start 185.5 121.275)
		(end 185.5 121.375)
		(width 0.09)
		(layer "In2.Cu")
		(net 607)
	)
	(segment
		(start 175.5295 122.7205)
		(end 177.2 121.05)
		(width 0.09)
		(layer "In2.Cu")
		(net 607)
	)
	(arc
		(start 185.95 121.275)
		(mid 186.015901 121.115901)
		(end 186.175 121.05)
		(width 0.09)
		(layer "In2.Cu")
		(net 607)
	)
	(arc
		(start 186.175 121.05)
		(mid 186.334099 121.115901)
		(end 186.4 121.275)
		(width 0.09)
		(layer "In2.Cu")
		(net 607)
	)
	(arc
		(start 189.545133 122.797327)
		(mid 189.668876 122.74607)
		(end 189.79262 122.797326)
		(width 0.09)
		(layer "In2.Cu")
		(net 607)
	)
	(arc
		(start 188.972143 122.875343)
		(mid 188.920886 122.999086)
		(end 188.972142 123.12283)
		(width 0.09)
		(layer "In2.Cu")
		(net 607)
	)
	(arc
		(start 185.5 121.375)
		(mid 185.565901 121.534099)
		(end 185.725 121.6)
		(width 0.09)
		(layer "In2.Cu")
		(net 607)
	)
	(arc
		(start 186.625 121.6)
		(mid 186.784099 121.534099)
		(end 186.85 121.375)
		(width 0.09)
		(layer "In2.Cu")
		(net 607)
	)
	(arc
		(start 185.275 121.05)
		(mid 185.434099 121.115901)
		(end 185.5 121.275)
		(width 0.09)
		(layer "In2.Cu")
		(net 607)
	)
	(arc
		(start 186.85 121.275)
		(mid 186.915901 121.115901)
		(end 187.075 121.05)
		(width 0.09)
		(layer "In2.Cu")
		(net 607)
	)
	(arc
		(start 188.972143 123.122831)
		(mid 189.095887 123.174087)
		(end 189.21963 123.12283)
		(width 0.09)
		(layer "In2.Cu")
		(net 607)
	)
	(arc
		(start 189.297647 122.302353)
		(mid 189.348903 122.426097)
		(end 189.297646 122.54984)
		(width 0.09)
		(layer "In2.Cu")
		(net 607)
	)
	(arc
		(start 186.4 121.375)
		(mid 186.465901 121.534099)
		(end 186.625 121.6)
		(width 0.09)
		(layer "In2.Cu")
		(net 607)
	)
	(arc
		(start 185.725 121.6)
		(mid 185.884099 121.534099)
		(end 185.95 121.375)
		(width 0.09)
		(layer "In2.Cu")
		(net 607)
	)
	(segment
		(start 176.404 123.416)
		(end 176.0045 123.0915)
		(width 0.174)
		(layer "F.Cu")
		(net 608)
	)
	(via
		(at 190.9 125.901)
		(size 0.35)
		(drill 0.15)
		(layers "F.Cu" "B.Cu")
		(remove_unused_layers yes)
		(keep_end_layers yes)
		(zone_layer_connections)
		(net 608)
	)
	(via
		(at 176.0045 123.0915)
		(size 0.35)
		(drill 0.15)
		(layers "F.Cu" "B.Cu")
		(remove_unused_layers yes)
		(keep_end_layers yes)
		(zone_layer_connections)
		(net 608)
	)
	(segment
		(start 188.624981 122.24751)
		(end 188.677298 122.195191)
		(width 0.09)
		(layer "In2.Cu")
		(net 608)
	)
	(segment
		(start 187.434988 122.302451)
		(end 187.364278 122.231741)
		(width 0.09)
		(layer "In2.Cu")
		(net 608)
	)
	(segment
		(start 187.716724 121.631802)
		(end 187.611763 121.736763)
		(width 0.09)
		(layer "In2.Cu")
		(net 608)
	)
	(segment
		(start 176.0045 123.0915)
		(end 176.0045 122.78088)
		(width 0.09)
		(layer "In2.Cu")
		(net 608)
	)
	(segment
		(start 187.116791 122.23174)
		(end 187.11679 122.23174)
		(width 0.09)
		(layer "In2.Cu")
		(net 608)
	)
	(segment
		(start 190.5 124.025)
		(end 190.5 124.4)
		(width 0.09)
		(layer "In2.Cu")
		(net 608)
	)
	(segment
		(start 187.611763 121.984251)
		(end 187.682474 122.054962)
		(width 0.09)
		(layer "In2.Cu")
		(net 608)
	)
	(segment
		(start 187.115684 122.515684)
		(end 187.25 122.65)
		(width 0.09)
		(layer "In2.Cu")
		(net 608)
	)
	(segment
		(start 186.832843 121.949999)
		(end 187.433883 121.34896)
		(width 0.09)
		(layer "In2.Cu")
		(net 608)
	)
	(segment
		(start 188.323744 122.424286)
		(end 188.323745 122.424285)
		(width 0.09)
		(layer "In2.Cu")
		(net 608)
	)
	(segment
		(start 188.929594 122.19038)
		(end 188.929594 122.190381)
		(width 0.09)
		(layer "In2.Cu")
		(net 608)
	)
	(segment
		(start 185.325 121.825)
		(end 186.425 121.825)
		(width 0.09)
		(layer "In2.Cu")
		(net 608)
	)
	(segment
		(start 191.3 125.501)
		(end 190.9 125.901)
		(width 0.09)
		(layer "In2.Cu")
		(net 608)
	)
	(segment
		(start 188.775 123.45)
		(end 189.925 123.45)
		(width 0.09)
		(layer "In2.Cu")
		(net 608)
	)
	(segment
		(start 188.677298 122.195191)
		(end 188.682106 122.19038)
		(width 0.09)
		(layer "In2.Cu")
		(net 608)
	)
	(segment
		(start 187.716726 121.348959)
		(end 187.716725 121.348959)
		(width 0.09)
		(layer "In2.Cu")
		(net 608)
	)
	(segment
		(start 191.05 124.75)
		(end 191.3 125)
		(width 0.09)
		(layer "In2.Cu")
		(net 608)
	)
	(segment
		(start 190.5 124.4)
		(end 190.85 124.75)
		(width 0.09)
		(layer "In2.Cu")
		(net 608)
	)
	(segment
		(start 186.425 121.825)
		(end 186.55 121.95)
		(width 0.09)
		(layer "In2.Cu")
		(net 608)
	)
	(segment
		(start 188.222488 122.650001)
		(end 188.323744 122.548744)
		(width 0.09)
		(layer "In2.Cu")
		(net 608)
	)
	(segment
		(start 188.929593 122.437868)
		(end 188.929593 122.437867)
		(width 0.09)
		(layer "In2.Cu")
		(net 608)
	)
	(segment
		(start 188.222487 122.649999)
		(end 188.222488 122.650001)
		(width 0.09)
		(layer "In2.Cu")
		(net 608)
	)
	(segment
		(start 177.38538 121.4)
		(end 184.9 121.4)
		(width 0.09)
		(layer "In2.Cu")
		(net 608)
	)
	(segment
		(start 176.0045 122.78088)
		(end 177.38538 121.4)
		(width 0.09)
		(layer "In2.Cu")
		(net 608)
	)
	(segment
		(start 188.929593 122.437867)
		(end 188.469974 122.897487)
		(width 0.09)
		(layer "In2.Cu")
		(net 608)
	)
	(segment
		(start 188.469974 123.144975)
		(end 188.469973 123.144973)
		(width 0.09)
		(layer "In2.Cu")
		(net 608)
	)
	(segment
		(start 188.323744 122.299826)
		(end 188.376063 122.247508)
		(width 0.09)
		(layer "In2.Cu")
		(net 608)
	)
	(segment
		(start 184.9 121.4)
		(end 185.325 121.825)
		(width 0.09)
		(layer "In2.Cu")
		(net 608)
	)
	(segment
		(start 187.115684 122.515685)
		(end 187.115684 122.515684)
		(width 0.09)
		(layer "In2.Cu")
		(net 608)
	)
	(segment
		(start 188.500523 122.247508)
		(end 188.500522 122.247509)
		(width 0.09)
		(layer "In2.Cu")
		(net 608)
	)
	(segment
		(start 187.11679 122.23174)
		(end 187.116788 122.231738)
		(width 0.09)
		(layer "In2.Cu")
		(net 608)
	)
	(segment
		(start 187.25 122.65)
		(end 187.975 122.65)
		(width 0.09)
		(layer "In2.Cu")
		(net 608)
	)
	(segment
		(start 191.3 125)
		(end 191.3 125.501)
		(width 0.09)
		(layer "In2.Cu")
		(net 608)
	)
	(segment
		(start 189.925 123.45)
		(end 190.5 124.025)
		(width 0.09)
		(layer "In2.Cu")
		(net 608)
	)
	(segment
		(start 187.43499 122.30245)
		(end 187.434988 122.302451)
		(width 0.09)
		(layer "In2.Cu")
		(net 608)
	)
	(segment
		(start 187.116788 122.231738)
		(end 187.115685 122.232842)
		(width 0.09)
		(layer "In2.Cu")
		(net 608)
	)
	(segment
		(start 190.85 124.75)
		(end 191.05 124.75)
		(width 0.09)
		(layer "In2.Cu")
		(net 608)
	)
	(segment
		(start 188.469973 123.144973)
		(end 188.775 123.45)
		(width 0.09)
		(layer "In2.Cu")
		(net 608)
	)
	(arc
		(start 187.364278 122.231741)
		(mid 187.240535 122.180484)
		(end 187.116791 122.23174)
		(width 0.09)
		(layer "In2.Cu")
		(net 608)
	)
	(arc
		(start 187.115685 122.232842)
		(mid 187.057106 122.374263)
		(end 187.115684 122.515685)
		(width 0.09)
		(layer "In2.Cu")
		(net 608)
	)
	(arc
		(start 188.323745 122.424285)
		(mid 188.297967 122.362055)
		(end 188.323744 122.299826)
		(width 0.09)
		(layer "In2.Cu")
		(net 608)
	)
	(arc
		(start 187.433883 121.34896)
		(mid 187.575304 121.290381)
		(end 187.716726 121.348959)
		(width 0.09)
		(layer "In2.Cu")
		(net 608)
	)
	(arc
		(start 188.376063 122.247508)
		(mid 188.438292 122.221732)
		(end 188.500523 122.247508)
		(width 0.09)
		(layer "In2.Cu")
		(net 608)
	)
	(arc
		(start 188.929594 122.190381)
		(mid 188.98085 122.314125)
		(end 188.929593 122.437868)
		(width 0.09)
		(layer "In2.Cu")
		(net 608)
	)
	(arc
		(start 187.716725 121.348959)
		(mid 187.775303 121.490381)
		(end 187.716724 121.631802)
		(width 0.09)
		(layer "In2.Cu")
		(net 608)
	)
	(arc
		(start 188.682106 122.19038)
		(mid 188.80585 122.139124)
		(end 188.929594 122.19038)
		(width 0.09)
		(layer "In2.Cu")
		(net 608)
	)
	(arc
		(start 187.682476 122.30245)
		(mid 187.558732 122.353707)
		(end 187.43499 122.30245)
		(width 0.09)
		(layer "In2.Cu")
		(net 608)
	)
	(arc
		(start 187.611763 121.736763)
		(mid 187.560507 121.860507)
		(end 187.611763 121.984251)
		(width 0.09)
		(layer "In2.Cu")
		(net 608)
	)
	(arc
		(start 187.975 122.65)
		(mid 188.098744 122.701256)
		(end 188.222487 122.649999)
		(width 0.09)
		(layer "In2.Cu")
		(net 608)
	)
	(arc
		(start 187.682474 122.054962)
		(mid 187.73373 122.178706)
		(end 187.682476 122.30245)
		(width 0.09)
		(layer "In2.Cu")
		(net 608)
	)
	(arc
		(start 188.469974 122.897487)
		(mid 188.418718 123.021231)
		(end 188.469974 123.144975)
		(width 0.09)
		(layer "In2.Cu")
		(net 608)
	)
	(arc
		(start 188.323744 122.548744)
		(mid 188.349519 122.486514)
		(end 188.323744 122.424286)
		(width 0.09)
		(layer "In2.Cu")
		(net 608)
	)
	(arc
		(start 186.55 121.95)
		(mid 186.691422 122.008578)
		(end 186.832843 121.949999)
		(width 0.09)
		(layer "In2.Cu")
		(net 608)
	)
	(arc
		(start 188.500522 122.247509)
		(mid 188.562751 122.273286)
		(end 188.624981 122.24751)
		(width 0.09)
		(layer "In2.Cu")
		(net 608)
	)
	(segment
		(start 176.404 124.066)
		(end 176.0045 123.7415)
		(width 0.174)
		(layer "F.Cu")
		(net 609)
	)
	(via
		(at 190.9 126.701)
		(size 0.35)
		(drill 0.15)
		(layers "F.Cu" "B.Cu")
		(remove_unused_layers yes)
		(keep_end_layers yes)
		(zone_layer_connections)
		(net 609)
	)
	(via
		(at 176.0045 123.7415)
		(size 0.35)
		(drill 0.15)
		(layers "F.Cu" "B.Cu")
		(remove_unused_layers yes)
		(keep_end_layers yes)
		(zone_layer_connections)
		(net 609)
	)
	(segment
		(start 177.6 125.65)
		(end 177.8 125.85)
		(width 0.09)
		(layer "In2.Cu")
		(net 609)
	)
	(segment
		(start 176.5 125.65)
		(end 177.6 125.65)
		(width 0.09)
		(layer "In2.Cu")
		(net 609)
	)
	(segment
		(start 180.325 128.3)
		(end 180.6535 127.9715)
		(width 0.09)
		(layer "In2.Cu")
		(net 609)
	)
	(segment
		(start 185.0715 127.9715)
		(end 185.775 128.675)
		(width 0.09)
		(layer "In2.Cu")
		(net 609)
	)
	(segment
		(start 178.975 128.3)
		(end 179.325 128.3)
		(width 0.09)
		(layer "In2.Cu")
		(net 609)
	)
	(segment
		(start 178.825 128.15)
		(end 178.975 128.3)
		(width 0.09)
		(layer "In2.Cu")
		(net 609)
	)
	(segment
		(start 190.575 127.026)
		(end 190.9 126.701)
		(width 0.09)
		(layer "In2.Cu")
		(net 609)
	)
	(segment
		(start 177.8 125.85)
		(end 178.425 125.85)
		(width 0.09)
		(layer "In2.Cu")
		(net 609)
	)
	(segment
		(start 180 126.816202)
		(end 180 128.075)
		(width 0.09)
		(layer "In2.Cu")
		(net 609)
	)
	(segment
		(start 190.15962 127.9)
		(end 190.575 127.48462)
		(width 0.09)
		(layer "In2.Cu")
		(net 609)
	)
	(segment
		(start 178.425 125.85)
		(end 178.825 126.25)
		(width 0.09)
		(layer "In2.Cu")
		(net 609)
	)
	(segment
		(start 178.825 126.25)
		(end 178.825 128.15)
		(width 0.09)
		(layer "In2.Cu")
		(net 609)
	)
	(segment
		(start 188.175 128.675)
		(end 188.95 127.9)
		(width 0.09)
		(layer "In2.Cu")
		(net 609)
	)
	(segment
		(start 180.6535 127.9715)
		(end 185.0715 127.9715)
		(width 0.09)
		(layer "In2.Cu")
		(net 609)
	)
	(segment
		(start 190.575 127.48462)
		(end 190.575 127.026)
		(width 0.09)
		(layer "In2.Cu")
		(net 609)
	)
	(segment
		(start 176.256 123.993)
		(end 176.256 125.406)
		(width 0.09)
		(layer "In2.Cu")
		(net 609)
	)
	(segment
		(start 179.55 128.075)
		(end 179.55 126.816202)
		(width 0.09)
		(layer "In2.Cu")
		(net 609)
	)
	(segment
		(start 188.95 127.9)
		(end 190.15962 127.9)
		(width 0.09)
		(layer "In2.Cu")
		(net 609)
	)
	(segment
		(start 180.225 128.3)
		(end 180.325 128.3)
		(width 0.09)
		(layer "In2.Cu")
		(net 609)
	)
	(segment
		(start 176.256 125.406)
		(end 176.5 125.65)
		(width 0.09)
		(layer "In2.Cu")
		(net 609)
	)
	(segment
		(start 176.0045 123.7415)
		(end 176.256 123.993)
		(width 0.09)
		(layer "In2.Cu")
		(net 609)
	)
	(segment
		(start 185.775 128.675)
		(end 188.175 128.675)
		(width 0.09)
		(layer "In2.Cu")
		(net 609)
	)
	(arc
		(start 179.775 126.591202)
		(mid 179.934099 126.657103)
		(end 180 126.816202)
		(width 0.09)
		(layer "In2.Cu")
		(net 609)
	)
	(arc
		(start 179.325 128.3)
		(mid 179.484099 128.234099)
		(end 179.55 128.075)
		(width 0.09)
		(layer "In2.Cu")
		(net 609)
	)
	(arc
		(start 180 128.075)
		(mid 180.065901 128.234099)
		(end 180.225 128.3)
		(width 0.09)
		(layer "In2.Cu")
		(net 609)
	)
	(arc
		(start 179.55 126.816202)
		(mid 179.615901 126.657103)
		(end 179.775 126.591202)
		(width 0.09)
		(layer "In2.Cu")
		(net 609)
	)
	(segment
		(start 178.004 126.016)
		(end 178.4035 126.3405)
		(width 0.174)
		(layer "F.Cu")
		(net 610)
	)
	(via
		(at 190.9 127.5)
		(size 0.35)
		(drill 0.15)
		(layers "F.Cu" "B.Cu")
		(remove_unused_layers yes)
		(keep_end_layers yes)
		(zone_layer_connections)
		(net 610)
	)
	(via
		(at 178.4035 126.3405)
		(size 0.35)
		(drill 0.15)
		(layers "F.Cu" "B.Cu")
		(remove_unused_layers yes)
		(keep_end_layers yes)
		(zone_layer_connections)
		(net 610)
	)
	(segment
		(start 188.425 129.1)
		(end 188.825 128.7)
		(width 0.09)
		(layer "In2.Cu")
		(net 610)
	)
	(segment
		(start 180.025 129.1215)
		(end 180.025 128.7715)
		(width 0.09)
		(layer "In2.Cu")
		(net 610)
	)
	(segment
		(start 177.962367 126.468816)
		(end 177.962367 126.85374)
		(width 0.09)
		(layer "In2.Cu")
		(net 610)
	)
	(segment
		(start 185.05 128.6215)
		(end 185.5285 129.1)
		(width 0.09)
		(layer "In2.Cu")
		(net 610)
	)
	(segment
		(start 188.825 128.7)
		(end 190.15962 128.7)
		(width 0.09)
		(layer "In2.Cu")
		(net 610)
	)
	(segment
		(start 190.5 127.9)
		(end 190.9 127.5)
		(width 0.09)
		(layer "In2.Cu")
		(net 610)
	)
	(segment
		(start 182.225 129.1215)
		(end 182.225 128.7715)
		(width 0.09)
		(layer "In2.Cu")
		(net 610)
	)
	(segment
		(start 180.625 129.1215)
		(end 180.625 128.7715)
		(width 0.09)
		(layer "In2.Cu")
		(net 610)
	)
	(segment
		(start 185.5285 129.1)
		(end 188.425 129.1)
		(width 0.09)
		(layer "In2.Cu")
		(net 610)
	)
	(segment
		(start 178.4035 126.3405)
		(end 178.394 126.35)
		(width 0.09)
		(layer "In2.Cu")
		(net 610)
	)
	(segment
		(start 190.5 128.35962)
		(end 190.5 127.9)
		(width 0.09)
		(layer "In2.Cu")
		(net 610)
	)
	(segment
		(start 180.325 128.7715)
		(end 180.325 129.1215)
		(width 0.09)
		(layer "In2.Cu")
		(net 610)
	)
	(segment
		(start 178.394 126.35)
		(end 178.081183 126.35)
		(width 0.09)
		(layer "In2.Cu")
		(net 610)
	)
	(segment
		(start 181.225 129.1215)
		(end 181.225 128.7715)
		(width 0.09)
		(layer "In2.Cu")
		(net 610)
	)
	(segment
		(start 177.425 127.369)
		(end 177.775 127.369)
		(width 0.09)
		(layer "In2.Cu")
		(net 610)
	)
	(segment
		(start 179.725 128.7715)
		(end 179.725 129.1215)
		(width 0.09)
		(layer "In2.Cu")
		(net 610)
	)
	(segment
		(start 182.825 129.1215)
		(end 182.825 128.7715)
		(width 0.09)
		(layer "In2.Cu")
		(net 610)
	)
	(segment
		(start 179.125 128.7715)
		(end 179.125 129.1215)
		(width 0.09)
		(layer "In2.Cu")
		(net 610)
	)
	(segment
		(start 182.525 128.7715)
		(end 182.525 129.1215)
		(width 0.09)
		(layer "In2.Cu")
		(net 610)
	)
	(segment
		(start 177.775 126.969)
		(end 177.425 126.969)
		(width 0.09)
		(layer "In2.Cu")
		(net 610)
	)
	(segment
		(start 178.280951 128.6215)
		(end 178.975 128.6215)
		(width 0.09)
		(layer "In2.Cu")
		(net 610)
	)
	(segment
		(start 181.925 128.7715)
		(end 181.925 129.1215)
		(width 0.09)
		(layer "In2.Cu")
		(net 610)
	)
	(segment
		(start 177.975 127.569)
		(end 177.975 128.315549)
		(width 0.09)
		(layer "In2.Cu")
		(net 610)
	)
	(segment
		(start 178.081183 126.35)
		(end 177.962367 126.468816)
		(width 0.09)
		(layer "In2.Cu")
		(net 610)
	)
	(segment
		(start 182.975 128.6215)
		(end 185.05 128.6215)
		(width 0.09)
		(layer "In2.Cu")
		(net 610)
	)
	(segment
		(start 179.425 129.1215)
		(end 179.425 128.7715)
		(width 0.09)
		(layer "In2.Cu")
		(net 610)
	)
	(segment
		(start 190.15962 128.7)
		(end 190.5 128.35962)
		(width 0.09)
		(layer "In2.Cu")
		(net 610)
	)
	(segment
		(start 177.975 128.315549)
		(end 178.280951 128.6215)
		(width 0.09)
		(layer "In2.Cu")
		(net 610)
	)
	(segment
		(start 181.375 128.6215)
		(end 181.775 128.6215)
		(width 0.09)
		(layer "In2.Cu")
		(net 610)
	)
	(segment
		(start 180.925 128.7715)
		(end 180.925 129.1215)
		(width 0.09)
		(layer "In2.Cu")
		(net 610)
	)
	(arc
		(start 181.925 129.1215)
		(mid 181.968934 129.227566)
		(end 182.075 129.2715)
		(width 0.09)
		(layer "In2.Cu")
		(net 610)
	)
	(arc
		(start 179.875 129.2715)
		(mid 179.981066 129.227566)
		(end 180.025 129.1215)
		(width 0.09)
		(layer "In2.Cu")
		(net 610)
	)
	(arc
		(start 177.425 126.969)
		(mid 177.283579 127.027579)
		(end 177.225 127.169)
		(width 0.09)
		(layer "In2.Cu")
		(net 610)
	)
	(arc
		(start 179.125 129.1215)
		(mid 179.168934 129.227566)
		(end 179.275 129.2715)
		(width 0.09)
		(layer "In2.Cu")
		(net 610)
	)
	(arc
		(start 180.325 129.1215)
		(mid 180.368934 129.227566)
		(end 180.475 129.2715)
		(width 0.09)
		(layer "In2.Cu")
		(net 610)
	)
	(arc
		(start 177.962367 126.85374)
		(mid 177.884922 126.938648)
		(end 177.775 126.969)
		(width 0.09)
		(layer "In2.Cu")
		(net 610)
	)
	(arc
		(start 181.075 129.2715)
		(mid 181.181066 129.227566)
		(end 181.225 129.1215)
		(width 0.09)
		(layer "In2.Cu")
		(net 610)
	)
	(arc
		(start 177.775 127.369)
		(mid 177.916421 127.427579)
		(end 177.975 127.569)
		(width 0.09)
		(layer "In2.Cu")
		(net 610)
	)
	(arc
		(start 182.225 128.7715)
		(mid 182.268934 128.665434)
		(end 182.375 128.6215)
		(width 0.09)
		(layer "In2.Cu")
		(net 610)
	)
	(arc
		(start 182.525 129.1215)
		(mid 182.568934 129.227566)
		(end 182.675 129.2715)
		(width 0.09)
		(layer "In2.Cu")
		(net 610)
	)
	(arc
		(start 177.225 127.169)
		(mid 177.283579 127.310421)
		(end 177.425 127.369)
		(width 0.09)
		(layer "In2.Cu")
		(net 610)
	)
	(arc
		(start 179.425 128.7715)
		(mid 179.468934 128.665434)
		(end 179.575 128.6215)
		(width 0.09)
		(layer "In2.Cu")
		(net 610)
	)
	(arc
		(start 182.075 129.2715)
		(mid 182.181066 129.227566)
		(end 182.225 129.1215)
		(width 0.09)
		(layer "In2.Cu")
		(net 610)
	)
	(arc
		(start 180.475 129.2715)
		(mid 180.581066 129.227566)
		(end 180.625 129.1215)
		(width 0.09)
		(layer "In2.Cu")
		(net 610)
	)
	(arc
		(start 179.275 129.2715)
		(mid 179.381066 129.227566)
		(end 179.425 129.1215)
		(width 0.09)
		(layer "In2.Cu")
		(net 610)
	)
	(arc
		(start 178.975 128.6215)
		(mid 179.081066 128.665434)
		(end 179.125 128.7715)
		(width 0.09)
		(layer "In2.Cu")
		(net 610)
	)
	(arc
		(start 180.775 128.6215)
		(mid 180.881066 128.665434)
		(end 180.925 128.7715)
		(width 0.09)
		(layer "In2.Cu")
		(net 610)
	)
	(arc
		(start 180.625 128.7715)
		(mid 180.668934 128.665434)
		(end 180.775 128.6215)
		(width 0.09)
		(layer "In2.Cu")
		(net 610)
	)
	(arc
		(start 180.025 128.7715)
		(mid 180.068934 128.665434)
		(end 180.175 128.6215)
		(width 0.09)
		(layer "In2.Cu")
		(net 610)
	)
	(arc
		(start 182.675 129.2715)
		(mid 182.781066 129.227566)
		(end 182.825 129.1215)
		(width 0.09)
		(layer "In2.Cu")
		(net 610)
	)
	(arc
		(start 181.775 128.6215)
		(mid 181.881066 128.665434)
		(end 181.925 128.7715)
		(width 0.09)
		(layer "In2.Cu")
		(net 610)
	)
	(arc
		(start 179.725 129.1215)
		(mid 179.768934 129.227566)
		(end 179.875 129.2715)
		(width 0.09)
		(layer "In2.Cu")
		(net 610)
	)
	(arc
		(start 180.175 128.6215)
		(mid 180.281066 128.665434)
		(end 180.325 128.7715)
		(width 0.09)
		(layer "In2.Cu")
		(net 610)
	)
	(arc
		(start 182.375 128.6215)
		(mid 182.481066 128.665434)
		(end 182.525 128.7715)
		(width 0.09)
		(layer "In2.Cu")
		(net 610)
	)
	(arc
		(start 182.825 128.7715)
		(mid 182.868934 128.665434)
		(end 182.975 128.6215)
		(width 0.09)
		(layer "In2.Cu")
		(net 610)
	)
	(arc
		(start 181.225 128.7715)
		(mid 181.268934 128.665434)
		(end 181.375 128.6215)
		(width 0.09)
		(layer "In2.Cu")
		(net 610)
	)
	(arc
		(start 179.575 128.6215)
		(mid 179.681066 128.665434)
		(end 179.725 128.7715)
		(width 0.09)
		(layer "In2.Cu")
		(net 610)
	)
	(arc
		(start 180.925 129.1215)
		(mid 180.968934 129.227566)
		(end 181.075 129.2715)
		(width 0.09)
		(layer "In2.Cu")
		(net 610)
	)
	(segment
		(start 182.805 124.717)
		(end 183.2045 124.3925)
		(width 0.174)
		(layer "F.Cu")
		(net 611)
	)
	(via
		(at 190.9 128.3)
		(size 0.35)
		(drill 0.15)
		(layers "F.Cu" "B.Cu")
		(remove_unused_layers yes)
		(keep_end_layers yes)
		(zone_layer_connections)
		(net 611)
	)
	(via
		(at 183.2045 124.3925)
		(size 0.35)
		(drill 0.15)
		(layers "F.Cu" "B.Cu")
		(remove_unused_layers yes)
		(keep_end_layers yes)
		(zone_layer_connections)
		(net 611)
	)
	(segment
		(start 188.979 126.033549)
		(end 189.166451 126.221)
		(width 0.09)
		(layer "In4.Cu")
		(net 611)
	)
	(segment
		(start 190.213268 127.021)
		(end 190.58 127.387732)
		(width 0.09)
		(layer "In4.Cu")
		(net 611)
	)
	(segment
		(start 185.72 125.32739)
		(end 185.72 126.076419)
		(width 0.09)
		(layer "In4.Cu")
		(net 611)
	)
	(segment
		(start 188.9 125.801)
		(end 188.979 125.88)
		(width 0.09)
		(layer "In4.Cu")
		(net 611)
	)
	(segment
		(start 187.46 126.076419)
		(end 187.46 125.325014)
		(width 0.09)
		(layer "In4.Cu")
		(net 611)
	)
	(segment
		(start 190.58 127.387732)
		(end 190.58 127.632549)
		(width 0.09)
		(layer "In4.Cu")
		(net 611)
	)
	(segment
		(start 182.612836 125.8)
		(end 185.107391 125.8)
		(width 0.09)
		(layer "In4.Cu")
		(net 611)
	)
	(segment
		(start 187.574985 125.210029)
		(end 187.605015 125.210029)
		(width 0.09)
		(layer "In4.Cu")
		(net 611)
	)
	(segment
		(start 183.2045 124.3925)
		(end 182.9995 124.5975)
		(width 0.09)
		(layer "In4.Cu")
		(net 611)
	)
	(segment
		(start 190.767451 127.82)
		(end 191.012268 127.82)
		(width 0.09)
		(layer "In4.Cu")
		(net 611)
	)
	(segment
		(start 188.9 125.8)
		(end 188.9 125.801)
		(width 0.09)
		(layer "In4.Cu")
		(net 611)
	)
	(segment
		(start 182.217623 125.404787)
		(end 182.612836 125.8)
		(width 0.09)
		(layer "In4.Cu")
		(net 611)
	)
	(segment
		(start 182.217623 124.936931)
		(end 182.217623 125.404787)
		(width 0.09)
		(layer "In4.Cu")
		(net 611)
	)
	(segment
		(start 186.72 125.325014)
		(end 186.72 126.076419)
		(width 0.09)
		(layer "In4.Cu")
		(net 611)
	)
	(segment
		(start 182.9995 124.5975)
		(end 182.557054 124.5975)
		(width 0.09)
		(layer "In4.Cu")
		(net 611)
	)
	(segment
		(start 186.574985 125.210029)
		(end 186.605015 125.210029)
		(width 0.09)
		(layer "In4.Cu")
		(net 611)
	)
	(segment
		(start 187.72 125.325014)
		(end 187.72 126.126433)
		(width 0.09)
		(layer "In4.Cu")
		(net 611)
	)
	(segment
		(start 182.557054 124.5975)
		(end 182.217623 124.936931)
		(width 0.09)
		(layer "In4.Cu")
		(net 611)
	)
	(segment
		(start 189.967451 127.021)
		(end 190.213268 127.021)
		(width 0.09)
		(layer "In4.Cu")
		(net 611)
	)
	(segment
		(start 186.46 126.076419)
		(end 186.46 125.325014)
		(width 0.09)
		(layer "In4.Cu")
		(net 611)
	)
	(segment
		(start 188.46 126.126433)
		(end 188.46 125.93)
		(width 0.09)
		(layer "In4.Cu")
		(net 611)
	)
	(segment
		(start 190.975 128.3)
		(end 190.9 128.3)
		(width 0.09)
		(layer "In4.Cu")
		(net 611)
	)
	(segment
		(start 185.46 125.447391)
		(end 185.46 125.32739)
		(width 0.09)
		(layer "In4.Cu")
		(net 611)
	)
	(segment
		(start 189.166451 126.221)
		(end 189.413268 126.221)
		(width 0.09)
		(layer "In4.Cu")
		(net 611)
	)
	(segment
		(start 190.58 127.632549)
		(end 190.767451 127.82)
		(width 0.09)
		(layer "In4.Cu")
		(net 611)
	)
	(segment
		(start 188.979 125.88)
		(end 188.979 126.033549)
		(width 0.09)
		(layer "In4.Cu")
		(net 611)
	)
	(segment
		(start 189.78 126.587732)
		(end 189.78 126.833549)
		(width 0.09)
		(layer "In4.Cu")
		(net 611)
	)
	(segment
		(start 191.18 127.987732)
		(end 191.18 128.095)
		(width 0.09)
		(layer "In4.Cu")
		(net 611)
	)
	(segment
		(start 191.012268 127.82)
		(end 191.18 127.987732)
		(width 0.09)
		(layer "In4.Cu")
		(net 611)
	)
	(segment
		(start 189.413268 126.221)
		(end 189.78 126.587732)
		(width 0.09)
		(layer "In4.Cu")
		(net 611)
	)
	(segment
		(start 189.78 126.833549)
		(end 189.967451 127.021)
		(width 0.09)
		(layer "In4.Cu")
		(net 611)
	)
	(segment
		(start 185.572609 125.214781)
		(end 185.607391 125.214781)
		(width 0.09)
		(layer "In4.Cu")
		(net 611)
	)
	(segment
		(start 191.18 128.095)
		(end 190.975 128.3)
		(width 0.09)
		(layer "In4.Cu")
		(net 611)
	)
	(segment
		(start 188.59 125.8)
		(end 188.9 125.8)
		(width 0.09)
		(layer "In4.Cu")
		(net 611)
	)
	(arc
		(start 188.09 126.496433)
		(mid 188.35163 126.388063)
		(end 188.46 126.126433)
		(width 0.09)
		(layer "In4.Cu")
		(net 611)
	)
	(arc
		(start 185.72 126.076419)
		(mid 185.82837 126.338049)
		(end 186.09 126.446419)
		(width 0.09)
		(layer "In4.Cu")
		(net 611)
	)
	(arc
		(start 187.605015 125.210029)
		(mid 187.686322 125.243707)
		(end 187.72 125.325014)
		(width 0.09)
		(layer "In4.Cu")
		(net 611)
	)
	(arc
		(start 186.605015 125.210029)
		(mid 186.686322 125.243707)
		(end 186.72 125.325014)
		(width 0.09)
		(layer "In4.Cu")
		(net 611)
	)
	(arc
		(start 187.09 126.446419)
		(mid 187.35163 126.338049)
		(end 187.46 126.076419)
		(width 0.09)
		(layer "In4.Cu")
		(net 611)
	)
	(arc
		(start 185.107391 125.8)
		(mid 185.356723 125.696723)
		(end 185.46 125.447391)
		(width 0.09)
		(layer "In4.Cu")
		(net 611)
	)
	(arc
		(start 187.72 126.126433)
		(mid 187.82837 126.388063)
		(end 188.09 126.496433)
		(width 0.09)
		(layer "In4.Cu")
		(net 611)
	)
	(arc
		(start 187.46 125.325014)
		(mid 187.493678 125.243707)
		(end 187.574985 125.210029)
		(width 0.09)
		(layer "In4.Cu")
		(net 611)
	)
	(arc
		(start 185.46 125.32739)
		(mid 185.492982 125.247763)
		(end 185.572609 125.214781)
		(width 0.09)
		(layer "In4.Cu")
		(net 611)
	)
	(arc
		(start 186.09 126.446419)
		(mid 186.35163 126.338049)
		(end 186.46 126.076419)
		(width 0.09)
		(layer "In4.Cu")
		(net 611)
	)
	(arc
		(start 186.46 125.325014)
		(mid 186.493678 125.243707)
		(end 186.574985 125.210029)
		(width 0.09)
		(layer "In4.Cu")
		(net 611)
	)
	(arc
		(start 186.72 126.076419)
		(mid 186.82837 126.338049)
		(end 187.09 126.446419)
		(width 0.09)
		(layer "In4.Cu")
		(net 611)
	)
	(arc
		(start 188.46 125.93)
		(mid 188.498076 125.838076)
		(end 188.59 125.8)
		(width 0.09)
		(layer "In4.Cu")
		(net 611)
	)
	(arc
		(start 185.607391 125.214781)
		(mid 185.687018 125.247763)
		(end 185.72 125.32739)
		(width 0.09)
		(layer "In4.Cu")
		(net 611)
	)
	(segment
		(start 182.004 124.067)
		(end 181.6045 123.7425)
		(width 0.174)
		(layer "F.Cu")
		(net 612)
	)
	(via
		(at 181.6045 123.7425)
		(size 0.35)
		(drill 0.15)
		(layers "F.Cu" "B.Cu")
		(remove_unused_layers yes)
		(keep_end_layers yes)
		(zone_layer_connections)
		(net 612)
	)
	(via
		(at 190.9 129.901)
		(size 0.35)
		(drill 0.15)
		(layers "F.Cu" "B.Cu")
		(remove_unused_layers yes)
		(keep_end_layers yes)
		(zone_layer_connections)
		(net 612)
	)
	(segment
		(start 189.76 130.93)
		(end 189.61 131.08)
		(width 0.09)
		(layer "In4.Cu")
		(net 612)
	)
	(segment
		(start 190.471 130.33)
		(end 189.98 130.33)
		(width 0.09)
		(layer "In4.Cu")
		(net 612)
	)
	(segment
		(start 189.61 131.08)
		(end 185.445549 131.08)
		(width 0.09)
		(layer "In4.Cu")
		(net 612)
	)
	(segment
		(start 189.76 130.55)
		(end 189.76 130.93)
		(width 0.09)
		(layer "In4.Cu")
		(net 612)
	)
	(segment
		(start 190.9 129.901)
		(end 190.471 130.33)
		(width 0.09)
		(layer "In4.Cu")
		(net 612)
	)
	(segment
		(start 179.85 128.95)
		(end 179.85 124.88738)
		(width 0.09)
		(layer "In4.Cu")
		(net 612)
	)
	(segment
		(start 179.85 124.88738)
		(end 180.66988 124.0675)
		(width 0.09)
		(layer "In4.Cu")
		(net 612)
	)
	(segment
		(start 184.937049 130.5715)
		(end 181.4715 130.5715)
		(width 0.09)
		(layer "In4.Cu")
		(net 612)
	)
	(segment
		(start 180.66988 124.0675)
		(end 181.0325 124.0675)
		(width 0.09)
		(layer "In4.Cu")
		(net 612)
	)
	(segment
		(start 181.3575 123.7425)
		(end 181.6045 123.7425)
		(width 0.09)
		(layer "In4.Cu")
		(net 612)
	)
	(segment
		(start 181.0325 124.0675)
		(end 181.3575 123.7425)
		(width 0.09)
		(layer "In4.Cu")
		(net 612)
	)
	(segment
		(start 189.98 130.33)
		(end 189.76 130.55)
		(width 0.09)
		(layer "In4.Cu")
		(net 612)
	)
	(segment
		(start 181.4715 130.5715)
		(end 179.85 128.95)
		(width 0.09)
		(layer "In4.Cu")
		(net 612)
	)
	(segment
		(start 185.445549 131.08)
		(end 184.937049 130.5715)
		(width 0.09)
		(layer "In4.Cu")
		(net 612)
	)
	(segment
		(start 176.404 135.766)
		(end 176.0045 136.0905)
		(width 0.174)
		(layer "F.Cu")
		(net 613)
	)
	(via
		(at 176.0045 136.0905)
		(size 0.35)
		(drill 0.15)
		(layers "F.Cu" "B.Cu")
		(remove_unused_layers yes)
		(keep_end_layers yes)
		(zone_layer_connections)
		(net 613)
	)
	(via
		(at 190.9 130.701)
		(size 0.35)
		(drill 0.15)
		(layers "F.Cu" "B.Cu")
		(remove_unused_layers yes)
		(keep_end_layers yes)
		(zone_layer_connections)
		(net 613)
	)
	(segment
		(start 176.88 131.12281)
		(end 176.88 131.02)
		(width 0.09)
		(layer "In2.Cu")
		(net 613)
	)
	(segment
		(start 185.1335 130.5665)
		(end 185.324 130.376)
		(width 0.09)
		(layer "In2.Cu")
		(net 613)
	)
	(segment
		(start 190.575 130.376)
		(end 190.9 130.701)
		(width 0.09)
		(layer "In2.Cu")
		(net 613)
	)
	(segment
		(start 175.6795 134.5705)
		(end 176.3245 133.9255)
		(width 0.09)
		(layer "In2.Cu")
		(net 613)
	)
	(segment
		(start 176.0045 136.0905)
		(end 176.3295 135.7655)
		(width 0.09)
		(layer "In2.Cu")
		(net 613)
	)
	(segment
		(start 176.1 133.1215)
		(end 176.1 132.452549)
		(width 0.09)
		(layer "In2.Cu")
		(net 613)
	)
	(segment
		(start 176.27 131.73281)
		(end 176.88 131.12281)
		(width 0.09)
		(layer "In2.Cu")
		(net 613)
	)
	(segment
		(start 177.009 130.891)
		(end 177.33962 130.891)
		(width 0.09)
		(layer "In2.Cu")
		(net 613)
	)
	(segment
		(start 179.225 130.361935)
		(end 179.225 130.3915)
		(width 0.09)
		(layer "In2.Cu")
		(net 613)
	)
	(segment
		(start 180.275 130.3915)
		(end 180.275 130.361935)
		(width 0.09)
		(layer "In2.Cu")
		(net 613)
	)
	(segment
		(start 179.925 130.361935)
		(end 179.925 130.3915)
		(width 0.09)
		(layer "In2.Cu")
		(net 613)
	)
	(segment
		(start 176.13912 135.1165)
		(end 175.87088 135.1165)
		(width 0.09)
		(layer "In2.Cu")
		(net 613)
	)
	(segment
		(start 176.88 131.02)
		(end 177.009 130.891)
		(width 0.09)
		(layer "In2.Cu")
		(net 613)
	)
	(segment
		(start 175.6795 134.92512)
		(end 175.6795 134.5705)
		(width 0.09)
		(layer "In2.Cu")
		(net 613)
	)
	(segment
		(start 176.3295 135.7655)
		(end 176.3295 135.30688)
		(width 0.09)
		(layer "In2.Cu")
		(net 613)
	)
	(segment
		(start 175.87088 135.1165)
		(end 175.6795 134.92512)
		(width 0.09)
		(layer "In2.Cu")
		(net 613)
	)
	(segment
		(start 176.3245 133.346)
		(end 176.1 133.1215)
		(width 0.09)
		(layer "In2.Cu")
		(net 613)
	)
	(segment
		(start 176.27 132.282549)
		(end 176.27 131.73281)
		(width 0.09)
		(layer "In2.Cu")
		(net 613)
	)
	(segment
		(start 177.33962 130.891)
		(end 177.66412 130.5665)
		(width 0.09)
		(layer "In2.Cu")
		(net 613)
	)
	(segment
		(start 185.324 130.376)
		(end 190.575 130.376)
		(width 0.09)
		(layer "In2.Cu")
		(net 613)
	)
	(segment
		(start 177.66412 130.5665)
		(end 178.7 130.5665)
		(width 0.09)
		(layer "In2.Cu")
		(net 613)
	)
	(segment
		(start 180.625 130.361935)
		(end 180.625 130.3915)
		(width 0.09)
		(layer "In2.Cu")
		(net 613)
	)
	(segment
		(start 176.1 132.452549)
		(end 176.27 132.282549)
		(width 0.09)
		(layer "In2.Cu")
		(net 613)
	)
	(segment
		(start 179.575 130.3915)
		(end 179.575 130.361935)
		(width 0.09)
		(layer "In2.Cu")
		(net 613)
	)
	(segment
		(start 176.3245 133.9255)
		(end 176.3245 133.346)
		(width 0.09)
		(layer "In2.Cu")
		(net 613)
	)
	(segment
		(start 176.3295 135.30688)
		(end 176.13912 135.1165)
		(width 0.09)
		(layer "In2.Cu")
		(net 613)
	)
	(segment
		(start 178.875 130.3915)
		(end 178.875 130.361935)
		(width 0.09)
		(layer "In2.Cu")
		(net 613)
	)
	(segment
		(start 180.8 130.5665)
		(end 185.1335 130.5665)
		(width 0.09)
		(layer "In2.Cu")
		(net 613)
	)
	(arc
		(start 180.275 130.361935)
		(mid 180.326256 130.238191)
		(end 180.45 130.186935)
		(width 0.09)
		(layer "In2.Cu")
		(net 613)
	)
	(arc
		(start 178.7 130.5665)
		(mid 178.823744 130.515244)
		(end 178.875 130.3915)
		(width 0.09)
		(layer "In2.Cu")
		(net 613)
	)
	(arc
		(start 180.45 130.186935)
		(mid 180.573744 130.238191)
		(end 180.625 130.361935)
		(width 0.09)
		(layer "In2.Cu")
		(net 613)
	)
	(arc
		(start 179.575 130.361935)
		(mid 179.626256 130.238191)
		(end 179.75 130.186935)
		(width 0.09)
		(layer "In2.Cu")
		(net 613)
	)
	(arc
		(start 179.05 130.186935)
		(mid 179.173744 130.238191)
		(end 179.225 130.361935)
		(width 0.09)
		(layer "In2.Cu")
		(net 613)
	)
	(arc
		(start 179.75 130.186935)
		(mid 179.873744 130.238191)
		(end 179.925 130.361935)
		(width 0.09)
		(layer "In2.Cu")
		(net 613)
	)
	(arc
		(start 179.225 130.3915)
		(mid 179.276256 130.515244)
		(end 179.4 130.5665)
		(width 0.09)
		(layer "In2.Cu")
		(net 613)
	)
	(arc
		(start 178.875 130.361935)
		(mid 178.926256 130.238191)
		(end 179.05 130.186935)
		(width 0.09)
		(layer "In2.Cu")
		(net 613)
	)
	(arc
		(start 179.925 130.3915)
		(mid 179.976256 130.515244)
		(end 180.1 130.5665)
		(width 0.09)
		(layer "In2.Cu")
		(net 613)
	)
	(arc
		(start 179.4 130.5665)
		(mid 179.523744 130.515244)
		(end 179.575 130.3915)
		(width 0.09)
		(layer "In2.Cu")
		(net 613)
	)
	(arc
		(start 180.625 130.3915)
		(mid 180.676256 130.515244)
		(end 180.8 130.5665)
		(width 0.09)
		(layer "In2.Cu")
		(net 613)
	)
	(arc
		(start 180.1 130.5665)
		(mid 180.223744 130.515244)
		(end 180.275 130.3915)
		(width 0.09)
		(layer "In2.Cu")
		(net 613)
	)
	(segment
		(start 177.205 135.117)
		(end 176.8055 135.4415)
		(width 0.174)
		(layer "F.Cu")
		(net 614)
	)
	(via
		(at 190.9 131.55)
		(size 0.35)
		(drill 0.15)
		(layers "F.Cu" "B.Cu")
		(remove_unused_layers yes)
		(keep_end_layers yes)
		(zone_layer_connections)
		(net 614)
	)
	(via
		(at 176.8055 135.4415)
		(size 0.35)
		(drill 0.15)
		(layers "F.Cu" "B.Cu")
		(remove_unused_layers yes)
		(keep_end_layers yes)
		(zone_layer_connections)
		(net 614)
	)
	(segment
		(start 186.88 135.91)
		(end 186.88 135.69)
		(width 0.09)
		(layer "In2.Cu")
		(net 614)
	)
	(segment
		(start 186.12 135.91)
		(end 186.12 135.69)
		(width 0.09)
		(layer "In2.Cu")
		(net 614)
	)
	(segment
		(start 185.74 135.69)
		(end 185.74 135.91)
		(width 0.09)
		(layer "In2.Cu")
		(net 614)
	)
	(segment
		(start 177.64 134.79)
		(end 177.87 135.02)
		(width 0.09)
		(layer "In2.Cu")
		(net 614)
	)
	(segment
		(start 177.65 135.6)
		(end 177.8115 135.7615)
		(width 0.09)
		(layer "In2.Cu")
		(net 614)
	)
	(segment
		(start 178.75 136.2)
		(end 178.9605 136.4105)
		(width 0.09)
		(layer "In2.Cu")
		(net 614)
	)
	(segment
		(start 191.3 131.95)
		(end 190.9 131.55)
		(width 0.09)
		(layer "In2.Cu")
		(net 614)
	)
	(segment
		(start 178.75 135.9)
		(end 178.75 136.2)
		(width 0.09)
		(layer "In2.Cu")
		(net 614)
	)
	(segment
		(start 185.4 135.5)
		(end 185.55 135.5)
		(width 0.09)
		(layer "In2.Cu")
		(net 614)
	)
	(segment
		(start 177.46 134.79)
		(end 177.64 134.79)
		(width 0.09)
		(layer "In2.Cu")
		(net 614)
	)
	(segment
		(start 179.95 136.7605)
		(end 180.03 136.7605)
		(width 0.09)
		(layer "In2.Cu")
		(net 614)
	)
	(segment
		(start 186.5 135.69)
		(end 186.5 135.91)
		(width 0.09)
		(layer "In2.Cu")
		(net 614)
	)
	(segment
		(start 191.3 133.952549)
		(end 191.3 131.95)
		(width 0.09)
		(layer "In2.Cu")
		(net 614)
	)
	(segment
		(start 176.8085 135.4415)
		(end 177.46 134.79)
		(width 0.09)
		(layer "In2.Cu")
		(net 614)
	)
	(segment
		(start 177.87 135.18)
		(end 177.65 135.4)
		(width 0.09)
		(layer "In2.Cu")
		(net 614)
	)
	(segment
		(start 180.38 136.4105)
		(end 184.4895 136.4105)
		(width 0.09)
		(layer "In2.Cu")
		(net 614)
	)
	(segment
		(start 177.65 135.4)
		(end 177.65 135.6)
		(width 0.09)
		(layer "In2.Cu")
		(net 614)
	)
	(segment
		(start 178.9605 136.4105)
		(end 179.6 136.4105)
		(width 0.09)
		(layer "In2.Cu")
		(net 614)
	)
	(segment
		(start 189.752549 135.5)
		(end 191.3 133.952549)
		(width 0.09)
		(layer "In2.Cu")
		(net 614)
	)
	(segment
		(start 177.87 135.02)
		(end 177.87 135.18)
		(width 0.09)
		(layer "In2.Cu")
		(net 614)
	)
	(segment
		(start 184.4895 136.4105)
		(end 185.4 135.5)
		(width 0.09)
		(layer "In2.Cu")
		(net 614)
	)
	(segment
		(start 176.8055 135.4415)
		(end 176.8085 135.4415)
		(width 0.09)
		(layer "In2.Cu")
		(net 614)
	)
	(segment
		(start 187.07 135.5)
		(end 189.752549 135.5)
		(width 0.09)
		(layer "In2.Cu")
		(net 614)
	)
	(segment
		(start 177.8115 135.7615)
		(end 178.6115 135.7615)
		(width 0.09)
		(layer "In2.Cu")
		(net 614)
	)
	(segment
		(start 178.6115 135.7615)
		(end 178.75 135.9)
		(width 0.09)
		(layer "In2.Cu")
		(net 614)
	)
	(arc
		(start 180.205 136.5855)
		(mid 180.256256 136.461756)
		(end 180.38 136.4105)
		(width 0.09)
		(layer "In2.Cu")
		(net 614)
	)
	(arc
		(start 180.03 136.7605)
		(mid 180.153744 136.709244)
		(end 180.205 136.5855)
		(width 0.09)
		(layer "In2.Cu")
		(net 614)
	)
	(arc
		(start 186.31 135.5)
		(mid 186.44435 135.55565)
		(end 186.5 135.69)
		(width 0.09)
		(layer "In2.Cu")
		(net 614)
	)
	(arc
		(start 179.775 136.5855)
		(mid 179.826256 136.709244)
		(end 179.95 136.7605)
		(width 0.09)
		(layer "In2.Cu")
		(net 614)
	)
	(arc
		(start 186.69 136.1)
		(mid 186.82435 136.04435)
		(end 186.88 135.91)
		(width 0.09)
		(layer "In2.Cu")
		(net 614)
	)
	(arc
		(start 186.12 135.69)
		(mid 186.17565 135.55565)
		(end 186.31 135.5)
		(width 0.09)
		(layer "In2.Cu")
		(net 614)
	)
	(arc
		(start 185.74 135.91)
		(mid 185.79565 136.04435)
		(end 185.93 136.1)
		(width 0.09)
		(layer "In2.Cu")
		(net 614)
	)
	(arc
		(start 185.55 135.5)
		(mid 185.68435 135.55565)
		(end 185.74 135.69)
		(width 0.09)
		(layer "In2.Cu")
		(net 614)
	)
	(arc
		(start 186.88 135.69)
		(mid 186.93565 135.55565)
		(end 187.07 135.5)
		(width 0.09)
		(layer "In2.Cu")
		(net 614)
	)
	(arc
		(start 185.93 136.1)
		(mid 186.06435 136.04435)
		(end 186.12 135.91)
		(width 0.09)
		(layer "In2.Cu")
		(net 614)
	)
	(arc
		(start 186.5 135.91)
		(mid 186.55565 136.04435)
		(end 186.69 136.1)
		(width 0.09)
		(layer "In2.Cu")
		(net 614)
	)
	(arc
		(start 179.6 136.4105)
		(mid 179.723744 136.461756)
		(end 179.775 136.5855)
		(width 0.09)
		(layer "In2.Cu")
		(net 614)
	)
	(segment
		(start 178.004 135.117)
		(end 178.4035 135.4415)
		(width 0.174)
		(layer "F.Cu")
		(net 615)
	)
	(via
		(at 178.4035 135.4415)
		(size 0.35)
		(drill 0.15)
		(layers "F.Cu" "B.Cu")
		(remove_unused_layers yes)
		(keep_end_layers yes)
		(zone_layer_connections)
		(net 615)
	)
	(via
		(at 190.9 132.225)
		(size 0.35)
		(drill 0.15)
		(layers "F.Cu" "B.Cu")
		(remove_unused_layers yes)
		(keep_end_layers yes)
		(zone_layer_connections)
		(net 615)
	)
	(segment
		(start 188.9985 135.1215)
		(end 190.5 133.62)
		(width 0.09)
		(layer "In2.Cu")
		(net 615)
	)
	(segment
		(start 178.7235 135.1215)
		(end 179.45 135.1215)
		(width 0.09)
		(layer "In2.Cu")
		(net 615)
	)
	(segment
		(start 190.5 133.62)
		(end 190.5 133)
		(width 0.09)
		(layer "In2.Cu")
		(net 615)
	)
	(segment
		(start 180.15 135.2615)
		(end 180.15 136.0315)
		(width 0.09)
		(layer "In2.Cu")
		(net 615)
	)
	(segment
		(start 180.43 136.0315)
		(end 180.43 135.2615)
		(width 0.09)
		(layer "In2.Cu")
		(net 615)
	)
	(segment
		(start 182.97 135.1215)
		(end 188.9985 135.1215)
		(width 0.09)
		(layer "In2.Cu")
		(net 615)
	)
	(segment
		(start 179.59 135.2615)
		(end 179.59 136.0315)
		(width 0.09)
		(layer "In2.Cu")
		(net 615)
	)
	(segment
		(start 180.57 135.1215)
		(end 181.85 135.1215)
		(width 0.09)
		(layer "In2.Cu")
		(net 615)
	)
	(segment
		(start 182.55 135.2615)
		(end 182.55 135.9815)
		(width 0.09)
		(layer "In2.Cu")
		(net 615)
	)
	(segment
		(start 179.87 136.0315)
		(end 179.87 135.2615)
		(width 0.09)
		(layer "In2.Cu")
		(net 615)
	)
	(segment
		(start 182.83 135.9815)
		(end 182.83 135.2615)
		(width 0.09)
		(layer "In2.Cu")
		(net 615)
	)
	(segment
		(start 190.5 133)
		(end 190.9 132.6)
		(width 0.09)
		(layer "In2.Cu")
		(net 615)
	)
	(segment
		(start 181.99 135.2615)
		(end 181.99 135.9815)
		(width 0.09)
		(layer "In2.Cu")
		(net 615)
	)
	(segment
		(start 178.4035 135.4415)
		(end 178.7235 135.1215)
		(width 0.09)
		(layer "In2.Cu")
		(net 615)
	)
	(segment
		(start 190.9 132.6)
		(end 190.9 132.225)
		(width 0.09)
		(layer "In2.Cu")
		(net 615)
	)
	(segment
		(start 182.27 135.9815)
		(end 182.27 135.2615)
		(width 0.09)
		(layer "In2.Cu")
		(net 615)
	)
	(arc
		(start 179.73 136.1715)
		(mid 179.828995 136.130495)
		(end 179.87 136.0315)
		(width 0.09)
		(layer "In2.Cu")
		(net 615)
	)
	(arc
		(start 180.15 136.0315)
		(mid 180.191005 136.130495)
		(end 180.29 136.1715)
		(width 0.09)
		(layer "In2.Cu")
		(net 615)
	)
	(arc
		(start 179.87 135.2615)
		(mid 179.911005 135.162505)
		(end 180.01 135.1215)
		(width 0.09)
		(layer "In2.Cu")
		(net 615)
	)
	(arc
		(start 182.83 135.2615)
		(mid 182.871005 135.162505)
		(end 182.97 135.1215)
		(width 0.09)
		(layer "In2.Cu")
		(net 615)
	)
	(arc
		(start 180.43 135.2615)
		(mid 180.471005 135.162505)
		(end 180.57 135.1215)
		(width 0.09)
		(layer "In2.Cu")
		(net 615)
	)
	(arc
		(start 180.01 135.1215)
		(mid 180.108995 135.162505)
		(end 180.15 135.2615)
		(width 0.09)
		(layer "In2.Cu")
		(net 615)
	)
	(arc
		(start 182.13 136.1215)
		(mid 182.228995 136.080495)
		(end 182.27 135.9815)
		(width 0.09)
		(layer "In2.Cu")
		(net 615)
	)
	(arc
		(start 182.55 135.9815)
		(mid 182.591005 136.080495)
		(end 182.69 136.1215)
		(width 0.09)
		(layer "In2.Cu")
		(net 615)
	)
	(arc
		(start 179.45 135.1215)
		(mid 179.548995 135.162505)
		(end 179.59 135.2615)
		(width 0.09)
		(layer "In2.Cu")
		(net 615)
	)
	(arc
		(start 181.99 135.9815)
		(mid 182.031005 136.080495)
		(end 182.13 136.1215)
		(width 0.09)
		(layer "In2.Cu")
		(net 615)
	)
	(arc
		(start 182.41 135.1215)
		(mid 182.508995 135.162505)
		(end 182.55 135.2615)
		(width 0.09)
		(layer "In2.Cu")
		(net 615)
	)
	(arc
		(start 182.27 135.2615)
		(mid 182.311005 135.162505)
		(end 182.41 135.1215)
		(width 0.09)
		(layer "In2.Cu")
		(net 615)
	)
	(arc
		(start 180.29 136.1715)
		(mid 180.388995 136.130495)
		(end 180.43 136.0315)
		(width 0.09)
		(layer "In2.Cu")
		(net 615)
	)
	(arc
		(start 181.85 135.1215)
		(mid 181.948995 135.162505)
		(end 181.99 135.2615)
		(width 0.09)
		(layer "In2.Cu")
		(net 615)
	)
	(arc
		(start 182.69 136.1215)
		(mid 182.788995 136.080495)
		(end 182.83 135.9815)
		(width 0.09)
		(layer "In2.Cu")
		(net 615)
	)
	(arc
		(start 179.59 136.0315)
		(mid 179.631005 136.130495)
		(end 179.73 136.1715)
		(width 0.09)
		(layer "In2.Cu")
		(net 615)
	)
	(segment
		(start 219.05 124.93)
		(end 219.05 123.875)
		(width 0.09)
		(layer "F.Cu")
		(net 617)
	)
	(segment
		(start 218.4 125.58)
		(end 219.05 124.93)
		(width 0.09)
		(layer "F.Cu")
		(net 617)
	)
	(via
		(at 218.4 125.58)
		(size 0.35)
		(drill 0.15)
		(layers "F.Cu" "B.Cu")
		(remove_unused_layers yes)
		(keep_end_layers yes)
		(zone_layer_connections)
		(net 617)
	)
	(segment
		(start 218.79 124.82)
		(end 219.44 124.82)
		(width 0.15)
		(layer "B.Cu")
		(net 617)
	)
	(segment
		(start 218.279411 125.330589)
		(end 218.79 124.82)
		(width 0.15)
		(layer "B.Cu")
		(net 617)
	)
	(via
		(at 218.06 116.411)
		(size 0.35)
		(drill 0.15)
		(layers "F.Cu" "B.Cu")
		(remove_unused_layers yes)
		(keep_end_layers yes)
		(zone_layer_connections)
		(net 618)
	)
	(via
		(at 222.8 119.400001)
		(size 0.35)
		(drill 0.15)
		(layers "F.Cu" "B.Cu")
		(remove_unused_layers yes)
		(keep_end_layers yes)
		(zone_layer_connections)
		(net 618)
	)
	(segment
		(start 223.35 117)
		(end 223.35 118.1)
		(width 0.09)
		(layer "In9.Cu")
		(net 618)
	)
	(segment
		(start 223.35 118.1)
		(end 222.8 118.65)
		(width 0.09)
		(layer "In9.Cu")
		(net 618)
	)
	(segment
		(start 222.761 116.411)
		(end 223.35 117)
		(width 0.09)
		(layer "In9.Cu")
		(net 618)
	)
	(segment
		(start 218.06 116.411)
		(end 222.761 116.411)
		(width 0.09)
		(layer "In9.Cu")
		(net 618)
	)
	(segment
		(start 222.8 118.65)
		(end 222.8 119.400001)
		(width 0.09)
		(layer "In9.Cu")
		(net 618)
	)
	(via
		(at 193.324959 120.019596)
		(size 0.35)
		(drill 0.15)
		(layers "F.Cu" "B.Cu")
		(remove_unused_layers yes)
		(keep_end_layers yes)
		(zone_layer_connections)
		(net 619)
	)
	(segment
		(start 222.68 139.72)
		(end 223.6015 140.6415)
		(width 0.09)
		(layer "F.Cu")
		(net 620)
	)
	(segment
		(start 223.6015 140.6415)
		(end 223.6015 141.067)
		(width 0.09)
		(layer "F.Cu")
		(net 620)
	)
	(segment
		(start 224.269 139.719)
		(end 223.3 138.75)
		(width 0.09)
		(layer "F.Cu")
		(net 621)
	)
	(segment
		(start 224.269 140.622135)
		(end 224.269 139.719)
		(width 0.09)
		(layer "F.Cu")
		(net 621)
	)
	(segment
		(start 224.2015 140.689635)
		(end 224.269 140.622135)
		(width 0.09)
		(layer "F.Cu")
		(net 621)
	)
	(segment
		(start 224.2015 141.067)
		(end 224.2015 140.689635)
		(width 0.09)
		(layer "F.Cu")
		(net 621)
	)
	(segment
		(start 191.79 145.976778)
		(end 191.79 146.186778)
		(width 0.15)
		(layer "F.Cu")
		(net 622)
	)
	(segment
		(start 191.953222 146.35)
		(end 192.14 146.35)
		(width 0.15)
		(layer "F.Cu")
		(net 622)
	)
	(segment
		(start 191.79 146.186778)
		(end 191.953222 146.35)
		(width 0.15)
		(layer "F.Cu")
		(net 622)
	)
	(via
		(at 191.79 145.976778)
		(size 0.35)
		(drill 0.15)
		(layers "F.Cu" "B.Cu")
		(remove_unused_layers yes)
		(keep_end_layers yes)
		(zone_layer_connections)
		(net 622)
	)
	(segment
		(start 191.6 145.786778)
		(end 191.79 145.976778)
		(width 0.15)
		(layer "B.Cu")
		(net 622)
	)
	(segment
		(start 192.07 143.47)
		(end 191.6 143.94)
		(width 0.15)
		(layer "B.Cu")
		(net 622)
	)
	(segment
		(start 191.6 143.94)
		(end 191.6 145.786778)
		(width 0.15)
		(layer "B.Cu")
		(net 622)
	)
	(segment
		(start 192.68 143.47)
		(end 192.07 143.47)
		(width 0.15)
		(layer "B.Cu")
		(net 622)
	)
	(segment
		(start 192.75 143.4)
		(end 192.68 143.47)
		(width 0.15)
		(layer "B.Cu")
		(net 622)
	)
	(segment
		(start 192.75 143.15)
		(end 192.75 143.4)
		(width 0.15)
		(layer "B.Cu")
		(net 622)
	)
	(segment
		(start 193.95 119.9)
		(end 193.95 120.15)
		(width 0.11)
		(layer "F.Cu")
		(net 623)
	)
	(segment
		(start 193.5 119.45)
		(end 193.95 119.9)
		(width 0.11)
		(layer "F.Cu")
		(net 623)
	)
	(via
		(at 193.5 119.45)
		(size 0.35)
		(drill 0.15)
		(layers "F.Cu" "B.Cu")
		(remove_unused_layers yes)
		(keep_end_layers yes)
		(zone_layer_connections)
		(net 623)
	)
	(segment
		(start 193.5 119.45)
		(end 193.722 119.672)
		(width 0.11)
		(layer "B.Cu")
		(net 623)
	)
	(segment
		(start 193.722 119.672)
		(end 193.722 120.171)
		(width 0.11)
		(layer "B.Cu")
		(net 623)
	)
	(via
		(at 196.396957 121.875749)
		(size 0.35)
		(drill 0.15)
		(layers "F.Cu" "B.Cu")
		(remove_unused_layers yes)
		(keep_end_layers yes)
		(zone_layer_connections)
		(net 624)
	)
	(via
		(at 198.899 125.901)
		(size 0.35)
		(drill 0.15)
		(layers "F.Cu" "B.Cu")
		(remove_unused_layers yes)
		(keep_end_layers yes)
		(zone_layer_connections)
		(net 624)
	)
	(segment
		(start 198.034379 120.809379)
		(end 198.034379 121.63)
		(width 0.09)
		(layer "In4.Cu")
		(net 624)
	)
	(segment
		(start 198.034379 123.61)
		(end 198.034379 123.715621)
		(width 0.09)
		(layer "In4.Cu")
		(net 624)
	)
	(segment
		(start 196.396957 121.875749)
		(end 196.794251 121.875749)
		(width 0.09)
		(layer "In4.Cu")
		(net 624)
	)
	(segment
		(start 197.7 124.05)
		(end 197.7 124.338407)
		(width 0.09)
		(layer "In4.Cu")
		(net 624)
	)
	(segment
		(start 198.034379 123.715621)
		(end 197.7 124.05)
		(width 0.09)
		(layer "In4.Cu")
		(net 624)
	)
	(segment
		(start 198.955065 122.455)
		(end 196.963682 122.455)
		(width 0.09)
		(layer "In4.Cu")
		(net 624)
	)
	(segment
		(start 198.745 123.28)
		(end 198.745 123.371153)
		(width 0.09)
		(layer "In4.Cu")
		(net 624)
	)
	(segment
		(start 198.51 125)
		(end 198.51 125.27)
		(width 0.09)
		(layer "In4.Cu")
		(net 624)
	)
	(segment
		(start 198.899 125.659)
		(end 198.899 125.901)
		(width 0.09)
		(layer "In4.Cu")
		(net 624)
	)
	(segment
		(start 197.869379 121.795)
		(end 197.813662 121.795)
		(width 0.09)
		(layer "In4.Cu")
		(net 624)
	)
	(segment
		(start 198.955065 123.115)
		(end 198.91 123.115)
		(width 0.09)
		(layer "In4.Cu")
		(net 624)
	)
	(segment
		(start 196.785 120.425)
		(end 197.65 120.425)
		(width 0.09)
		(layer "In4.Cu")
		(net 624)
	)
	(segment
		(start 197.02 121.099884)
		(end 196.65 120.729884)
		(width 0.09)
		(layer "In4.Cu")
		(net 624)
	)
	(segment
		(start 196.963682 122.785)
		(end 198.955065 122.785)
		(width 0.09)
		(layer "In4.Cu")
		(net 624)
	)
	(segment
		(start 198.25 123.115)
		(end 197.513699 123.115)
		(width 0.09)
		(layer "In4.Cu")
		(net 624)
	)
	(segment
		(start 198.12 124.61)
		(end 198.51 125)
		(width 0.09)
		(layer "In4.Cu")
		(net 624)
	)
	(segment
		(start 196.794251 121.875749)
		(end 197.02 121.65)
		(width 0.09)
		(layer "In4.Cu")
		(net 624)
	)
	(segment
		(start 197.7 124.338407)
		(end 197.971593 124.61)
		(width 0.09)
		(layer "In4.Cu")
		(net 624)
	)
	(segment
		(start 196.65 120.56)
		(end 196.785 120.425)
		(width 0.09)
		(layer "In4.Cu")
		(net 624)
	)
	(segment
		(start 197.02 121.65)
		(end 197.02 121.099884)
		(width 0.09)
		(layer "In4.Cu")
		(net 624)
	)
	(segment
		(start 198.51 125.27)
		(end 198.899 125.659)
		(width 0.09)
		(layer "In4.Cu")
		(net 624)
	)
	(segment
		(start 197.65 120.425)
		(end 198.034379 120.809379)
		(width 0.09)
		(layer "In4.Cu")
		(net 624)
	)
	(segment
		(start 197.813662 122.125)
		(end 198.955065 122.125)
		(width 0.09)
		(layer "In4.Cu")
		(net 624)
	)
	(segment
		(start 198.415 123.371153)
		(end 198.415 123.28)
		(width 0.09)
		(layer "In4.Cu")
		(net 624)
	)
	(segment
		(start 197.971593 124.61)
		(end 198.12 124.61)
		(width 0.09)
		(layer "In4.Cu")
		(net 624)
	)
	(segment
		(start 196.65 120.729884)
		(end 196.65 120.56)
		(width 0.09)
		(layer "In4.Cu")
		(net 624)
	)
	(segment
		(start 197.513699 123.445)
		(end 197.869379 123.445)
		(width 0.09)
		(layer "In4.Cu")
		(net 624)
	)
	(arc
		(start 198.955065 122.785)
		(mid 199.071738 122.833327)
		(end 199.120065 122.95)
		(width 0.09)
		(layer "In4.Cu")
		(net 624)
	)
	(arc
		(start 196.963682 122.455)
		(mid 196.847009 122.503327)
		(end 196.798682 122.62)
		(width 0.09)
		(layer "In4.Cu")
		(net 624)
	)
	(arc
		(start 198.745 123.371153)
		(mid 198.696673 123.487826)
		(end 198.58 123.536153)
		(width 0.09)
		(layer "In4.Cu")
		(net 624)
	)
	(arc
		(start 198.955065 122.125)
		(mid 199.071738 122.173327)
		(end 199.120065 122.29)
		(width 0.09)
		(layer "In4.Cu")
		(net 624)
	)
	(arc
		(start 198.58 123.536153)
		(mid 198.463327 123.487826)
		(end 198.415 123.371153)
		(width 0.09)
		(layer "In4.Cu")
		(net 624)
	)
	(arc
		(start 197.813662 121.795)
		(mid 197.696989 121.843327)
		(end 197.648662 121.96)
		(width 0.09)
		(layer "In4.Cu")
		(net 624)
	)
	(arc
		(start 198.415 123.28)
		(mid 198.366673 123.163327)
		(end 198.25 123.115)
		(width 0.09)
		(layer "In4.Cu")
		(net 624)
	)
	(arc
		(start 197.648662 121.96)
		(mid 197.696989 122.076673)
		(end 197.813662 122.125)
		(width 0.09)
		(layer "In4.Cu")
		(net 624)
	)
	(arc
		(start 197.513699 123.115)
		(mid 197.397026 123.163327)
		(end 197.348699 123.28)
		(width 0.09)
		(layer "In4.Cu")
		(net 624)
	)
	(arc
		(start 199.120065 122.29)
		(mid 199.071738 122.406673)
		(end 198.955065 122.455)
		(width 0.09)
		(layer "In4.Cu")
		(net 624)
	)
	(arc
		(start 197.869379 123.445)
		(mid 197.986052 123.493327)
		(end 198.034379 123.61)
		(width 0.09)
		(layer "In4.Cu")
		(net 624)
	)
	(arc
		(start 198.034379 121.63)
		(mid 197.986052 121.746673)
		(end 197.869379 121.795)
		(width 0.09)
		(layer "In4.Cu")
		(net 624)
	)
	(arc
		(start 196.798682 122.62)
		(mid 196.847009 122.736673)
		(end 196.963682 122.785)
		(width 0.09)
		(layer "In4.Cu")
		(net 624)
	)
	(arc
		(start 197.348699 123.28)
		(mid 197.397026 123.396673)
		(end 197.513699 123.445)
		(width 0.09)
		(layer "In4.Cu")
		(net 624)
	)
	(arc
		(start 198.91 123.115)
		(mid 198.793327 123.163327)
		(end 198.745 123.28)
		(width 0.09)
		(layer "In4.Cu")
		(net 624)
	)
	(arc
		(start 199.120065 122.95)
		(mid 199.071738 123.066673)
		(end 198.955065 123.115)
		(width 0.09)
		(layer "In4.Cu")
		(net 624)
	)
	(via
		(at 196.573533 121.450247)
		(size 0.35)
		(drill 0.15)
		(layers "F.Cu" "B.Cu")
		(remove_unused_layers yes)
		(keep_end_layers yes)
		(zone_layer_connections)
		(net 625)
	)
	(via
		(at 198.899 127.5)
		(size 0.35)
		(drill 0.15)
		(layers "F.Cu" "B.Cu")
		(remove_unused_layers yes)
		(keep_end_layers yes)
		(zone_layer_connections)
		(net 625)
	)
	(segment
		(start 196.868662 123.356373)
		(end 196.868662 123.356372)
		(width 0.09)
		(layer "In4.Cu")
		(net 625)
	)
	(segment
		(start 198.575 127.225)
		(end 198.575 127.375)
		(width 0.09)
		(layer "In4.Cu")
		(net 625)
	)
	(segment
		(start 196.790879 124.600879)
		(end 196.97 124.78)
		(width 0.09)
		(layer "In4.Cu")
		(net 625)
	)
	(segment
		(start 196.085 123.205)
		(end 195.965 123.205)
		(width 0.09)
		(layer "In4.Cu")
		(net 625)
	)
	(segment
		(start 197.57811 125.38811)
		(end 197.68 125.49)
		(width 0.09)
		(layer "In4.Cu")
		(net 625)
	)
	(segment
		(start 195.965 122.875)
		(end 196.085 122.875)
		(width 0.09)
		(layer "In4.Cu")
		(net 625)
	)
	(segment
		(start 198.233442 125.49)
		(end 198.51 125.766558)
		(width 0.09)
		(layer "In4.Cu")
		(net 625)
	)
	(segment
		(start 196.324191 124.13419)
		(end 196.32419 124.13419)
		(width 0.09)
		(layer "In4.Cu")
		(net 625)
	)
	(segment
		(start 196.557535 124.134189)
		(end 196.557536 124.134191)
		(width 0.09)
		(layer "In4.Cu")
		(net 625)
	)
	(segment
		(start 198.575 127.375)
		(end 198.7 127.5)
		(width 0.09)
		(layer "In4.Cu")
		(net 625)
	)
	(segment
		(start 196.453505 122.545)
		(end 195.965 122.545)
		(width 0.09)
		(layer "In4.Cu")
		(net 625)
	)
	(segment
		(start 195.8 123.61)
		(end 195.8575 123.6675)
		(width 0.09)
		(layer "In4.Cu")
		(net 625)
	)
	(segment
		(start 198.71 126.3)
		(end 198.936407 126.3)
		(width 0.09)
		(layer "In4.Cu")
		(net 625)
	)
	(segment
		(start 197.274056 124.780001)
		(end 197.394263 124.659791)
		(width 0.09)
		(layer "In4.Cu")
		(net 625)
	)
	(segment
		(start 196.269753 121.450247)
		(end 195.8 121.92)
		(width 0.09)
		(layer "In4.Cu")
		(net 625)
	)
	(segment
		(start 197.698318 124.963846)
		(end 197.69832 124.963847)
		(width 0.09)
		(layer "In4.Cu")
		(net 625)
	)
	(segment
		(start 196.090846 123.667501)
		(end 196.635317 123.123027)
		(width 0.09)
		(layer "In4.Cu")
		(net 625)
	)
	(segment
		(start 198.936407 126.3)
		(end 199.37 126.733593)
		(width 0.09)
		(layer "In4.Cu")
		(net 625)
	)
	(segment
		(start 196.790881 124.60088)
		(end 196.790879 124.600879)
		(width 0.09)
		(layer "In4.Cu")
		(net 625)
	)
	(segment
		(start 196.868662 123.123028)
		(end 196.868663 123.123028)
		(width 0.09)
		(layer "In4.Cu")
		(net 625)
	)
	(segment
		(start 196.868662 123.356372)
		(end 196.32419 123.900845)
		(width 0.09)
		(layer "In4.Cu")
		(net 625)
	)
	(segment
		(start 196.557536 124.134191)
		(end 197.102007 123.589717)
		(width 0.09)
		(layer "In4.Cu")
		(net 625)
	)
	(segment
		(start 195.965 122.215)
		(end 196.453505 122.215)
		(width 0.09)
		(layer "In4.Cu")
		(net 625)
	)
	(segment
		(start 199.37 126.905)
		(end 199.25 127.025)
		(width 0.09)
		(layer "In4.Cu")
		(net 625)
	)
	(segment
		(start 197.335352 123.589718)
		(end 197.335353 123.589718)
		(width 0.09)
		(layer "In4.Cu")
		(net 625)
	)
	(segment
		(start 199.37 126.733593)
		(end 199.37 126.905)
		(width 0.09)
		(layer "In4.Cu")
		(net 625)
	)
	(segment
		(start 197.274055 124.779999)
		(end 197.274056 124.780001)
		(width 0.09)
		(layer "In4.Cu")
		(net 625)
	)
	(segment
		(start 198.775 127.025)
		(end 198.575 127.225)
		(width 0.09)
		(layer "In4.Cu")
		(net 625)
	)
	(segment
		(start 199.25 127.025)
		(end 198.775 127.025)
		(width 0.09)
		(layer "In4.Cu")
		(net 625)
	)
	(segment
		(start 198.51 125.766558)
		(end 198.51 126.1)
		(width 0.09)
		(layer "In4.Cu")
		(net 625)
	)
	(segment
		(start 197.335352 123.823062)
		(end 196.79088 124.367535)
		(width 0.09)
		(layer "In4.Cu")
		(net 625)
	)
	(segment
		(start 195.8 121.92)
		(end 195.8 122.05)
		(width 0.09)
		(layer "In4.Cu")
		(net 625)
	)
	(segment
		(start 198.7 127.5)
		(end 198.899 127.5)
		(width 0.09)
		(layer "In4.Cu")
		(net 625)
	)
	(segment
		(start 197.68 125.49)
		(end 198.233442 125.49)
		(width 0.09)
		(layer "In4.Cu")
		(net 625)
	)
	(segment
		(start 196.573533 121.450247)
		(end 196.269753 121.450247)
		(width 0.09)
		(layer "In4.Cu")
		(net 625)
	)
	(segment
		(start 198.51 126.1)
		(end 198.71 126.3)
		(width 0.09)
		(layer "In4.Cu")
		(net 625)
	)
	(segment
		(start 196.090845 123.667499)
		(end 196.090846 123.667501)
		(width 0.09)
		(layer "In4.Cu")
		(net 625)
	)
	(segment
		(start 195.8 123.37)
		(end 195.8 123.61)
		(width 0.09)
		(layer "In4.Cu")
		(net 625)
	)
	(segment
		(start 197.69832 124.963847)
		(end 197.57811 125.084054)
		(width 0.09)
		(layer "In4.Cu")
		(net 625)
	)
	(segment
		(start 197.335352 123.823063)
		(end 197.335352 123.823062)
		(width 0.09)
		(layer "In4.Cu")
		(net 625)
	)
	(arc
		(start 197.394263 124.659791)
		(mid 197.546291 124.596819)
		(end 197.698319 124.659791)
		(width 0.09)
		(layer "In4.Cu")
		(net 625)
	)
	(arc
		(start 196.635317 123.123027)
		(mid 196.75199 123.0747)
		(end 196.868662 123.123028)
		(width 0.09)
		(layer "In4.Cu")
		(net 625)
	)
	(arc
		(start 195.965 123.205)
		(mid 195.848327 123.253327)
		(end 195.8 123.37)
		(width 0.09)
		(layer "In4.Cu")
		(net 625)
	)
	(arc
		(start 196.25 123.04)
		(mid 196.201673 123.156673)
		(end 196.085 123.205)
		(width 0.09)
		(layer "In4.Cu")
		(net 625)
	)
	(arc
		(start 196.79088 124.367535)
		(mid 196.742553 124.484208)
		(end 196.790881 124.60088)
		(width 0.09)
		(layer "In4.Cu")
		(net 625)
	)
	(arc
		(start 195.8 122.71)
		(mid 195.848327 122.826673)
		(end 195.965 122.875)
		(width 0.09)
		(layer "In4.Cu")
		(net 625)
	)
	(arc
		(start 196.32419 123.900845)
		(mid 196.275863 124.017518)
		(end 196.324191 124.13419)
		(width 0.09)
		(layer "In4.Cu")
		(net 625)
	)
	(arc
		(start 196.97 124.78)
		(mid 197.122029 124.842972)
		(end 197.274055 124.779999)
		(width 0.09)
		(layer "In4.Cu")
		(net 625)
	)
	(arc
		(start 196.085 122.875)
		(mid 196.201673 122.923327)
		(end 196.25 123.04)
		(width 0.09)
		(layer "In4.Cu")
		(net 625)
	)
	(arc
		(start 196.618505 122.38)
		(mid 196.570178 122.496673)
		(end 196.453505 122.545)
		(width 0.09)
		(layer "In4.Cu")
		(net 625)
	)
	(arc
		(start 196.868663 123.123028)
		(mid 196.91699 123.239701)
		(end 196.868662 123.356373)
		(width 0.09)
		(layer "In4.Cu")
		(net 625)
	)
	(arc
		(start 195.8 122.05)
		(mid 195.848327 122.166673)
		(end 195.965 122.215)
		(width 0.09)
		(layer "In4.Cu")
		(net 625)
	)
	(arc
		(start 197.57811 125.084054)
		(mid 197.515138 125.236082)
		(end 197.57811 125.38811)
		(width 0.09)
		(layer "In4.Cu")
		(net 625)
	)
	(arc
		(start 196.32419 124.13419)
		(mid 196.440863 124.182517)
		(end 196.557535 124.134189)
		(width 0.09)
		(layer "In4.Cu")
		(net 625)
	)
	(arc
		(start 197.102007 123.589717)
		(mid 197.21868 123.54139)
		(end 197.335352 123.589718)
		(width 0.09)
		(layer "In4.Cu")
		(net 625)
	)
	(arc
		(start 197.698319 124.659791)
		(mid 197.761291 124.81182)
		(end 197.698318 124.963846)
		(width 0.09)
		(layer "In4.Cu")
		(net 625)
	)
	(arc
		(start 195.8575 123.6675)
		(mid 195.974173 123.715827)
		(end 196.090845 123.667499)
		(width 0.09)
		(layer "In4.Cu")
		(net 625)
	)
	(arc
		(start 195.965 122.545)
		(mid 195.848327 122.593327)
		(end 195.8 122.71)
		(width 0.09)
		(layer "In4.Cu")
		(net 625)
	)
	(arc
		(start 196.453505 122.215)
		(mid 196.570178 122.263327)
		(end 196.618505 122.38)
		(width 0.09)
		(layer "In4.Cu")
		(net 625)
	)
	(arc
		(start 197.335353 123.589718)
		(mid 197.38368 123.706391)
		(end 197.335352 123.823063)
		(width 0.09)
		(layer "In4.Cu")
		(net 625)
	)
	(segment
		(start 181.75 138.8015)
		(end 181.686 138.8015)
		(width 0.174)
		(layer "F.Cu")
		(net 632)
	)
	(segment
		(start 181.686 138.8015)
		(end 181.25 139.2375)
		(width 0.174)
		(layer "F.Cu")
		(net 632)
	)
	(segment
		(start 181.25 139.2375)
		(end 181.25 139.7875)
		(width 0.174)
		(layer "F.Cu")
		(net 632)
	)
	(via
		(at 181.441 139.094954)
		(size 0.35)
		(drill 0.15)
		(layers "F.Cu" "B.Cu")
		(remove_unused_layers yes)
		(keep_end_layers yes)
		(zone_layer_connections)
		(net 632)
	)
	(via
		(at 181.825 138.807061)
		(size 0.35)
		(drill 0.15)
		(layers "F.Cu" "B.Cu")
		(remove_unused_layers yes)
		(keep_end_layers yes)
		(zone_layer_connections)
		(net 632)
	)
	(segment
		(start 181.8 138.6)
		(end 181.8 137.8)
		(width 0.35)
		(layer "B.Cu")
		(net 632)
	)
	(segment
		(start 181.2 139)
		(end 181.4 139)
		(width 0.35)
		(layer "B.Cu")
		(net 632)
	)
	(segment
		(start 181.825 138.807061)
		(end 181.392939 138.807061)
		(width 0.35)
		(layer "B.Cu")
		(net 632)
	)
	(segment
		(start 181.4 139)
		(end 181.8 138.6)
		(width 0.35)
		(layer "B.Cu")
		(net 632)
	)
	(segment
		(start 181.392939 138.807061)
		(end 181.2 139)
		(width 0.35)
		(layer "B.Cu")
		(net 632)
	)
	(segment
		(start 180.35 143.584885)
		(end 180.35 144.0375)
		(width 0.174)
		(layer "F.Cu")
		(net 633)
	)
	(segment
		(start 180.112837 143.347722)
		(end 180.35 143.584885)
		(width 0.174)
		(layer "F.Cu")
		(net 633)
	)
	(via
		(at 185.15 148.023)
		(size 0.35)
		(drill 0.15)
		(layers "F.Cu" "B.Cu")
		(remove_unused_layers yes)
		(keep_end_layers yes)
		(zone_layer_connections)
		(net 633)
	)
	(via
		(at 180.112837 143.347722)
		(size 0.35)
		(drill 0.15)
		(layers "F.Cu" "B.Cu")
		(remove_unused_layers yes)
		(keep_end_layers yes)
		(zone_layer_connections)
		(net 633)
	)
	(segment
		(start 185.7 148.374014)
		(end 185.7 149.1)
		(width 0.125)
		(layer "B.Cu")
		(net 633)
	)
	(segment
		(start 185.348986 148.023)
		(end 185.7 148.374014)
		(width 0.125)
		(layer "B.Cu")
		(net 633)
	)
	(segment
		(start 180.102278 143.347722)
		(end 179.584 143.866)
		(width 0.174)
		(layer "B.Cu")
		(net 633)
	)
	(segment
		(start 180.112837 143.347722)
		(end 180.102278 143.347722)
		(width 0.174)
		(layer "B.Cu")
		(net 633)
	)
	(segment
		(start 179.584 143.866)
		(end 179.584 144.0125)
		(width 0.174)
		(layer "B.Cu")
		(net 633)
	)
	(segment
		(start 185.15 148.023)
		(end 185.348986 148.023)
		(width 0.2)
		(layer "B.Cu")
		(net 633)
	)
	(segment
		(start 185.7 149.1)
		(end 186.125 149.525)
		(width 0.125)
		(layer "B.Cu")
		(net 633)
	)
	(segment
		(start 181.925 147.15)
		(end 184.277 147.15)
		(width 0.4)
		(layer "In9.Cu")
		(net 633)
	)
	(segment
		(start 184.277 147.15)
		(end 185.15 148.023)
		(width 0.4)
		(layer "In9.Cu")
		(net 633)
	)
	(segment
		(start 180.112837 143.347722)
		(end 180.112837 145.337837)
		(width 0.4)
		(layer "In9.Cu")
		(net 633)
	)
	(segment
		(start 180.112837 145.337837)
		(end 181.925 147.15)
		(width 0.4)
		(layer "In9.Cu")
		(net 633)
	)
	(via
		(at 181.584 144.0125)
		(size 0.35)
		(drill 0.15)
		(layers "F.Cu" "B.Cu")
		(remove_unused_layers yes)
		(keep_end_layers yes)
		(zone_layer_connections)
		(net 634)
	)
	(via
		(at 183.742895 145.886589)
		(size 0.35)
		(drill 0.15)
		(layers "F.Cu" "B.Cu")
		(remove_unused_layers yes)
		(keep_end_layers yes)
		(zone_layer_connections)
		(net 634)
	)
	(segment
		(start 183.923214 145.959953)
		(end 185.359953 145.959953)
		(width 0.2)
		(layer "B.Cu")
		(net 634)
	)
	(segment
		(start 185.359953 145.959953)
		(end 185.4 146)
		(width 0.2)
		(layer "B.Cu")
		(net 634)
	)
	(segment
		(start 182.2125 144.0125)
		(end 181.584 144.0125)
		(width 0.4)
		(layer "In9.Cu")
		(net 634)
	)
	(segment
		(start 183.742895 145.886589)
		(end 183.742895 145.542895)
		(width 0.4)
		(layer "In9.Cu")
		(net 634)
	)
	(segment
		(start 183.742895 145.542895)
		(end 182.2125 144.0125)
		(width 0.4)
		(layer "In9.Cu")
		(net 634)
	)
	(via
		(at 203.699 141.101)
		(size 0.35)
		(drill 0.15)
		(layers "F.Cu" "B.Cu")
		(remove_unused_layers yes)
		(keep_end_layers yes)
		(zone_layer_connections)
		(net 635)
	)
	(via
		(at 210.5 147.485)
		(size 0.35)
		(drill 0.15)
		(layers "F.Cu" "B.Cu")
		(remove_unused_layers yes)
		(keep_end_layers yes)
		(zone_layer_connections)
		(net 635)
	)
	(segment
		(start 208.675 145.775)
		(end 210.275 145.775)
		(width 0.09)
		(layer "In7.Cu")
		(net 635)
	)
	(segment
		(start 210.275 145.775)
		(end 210.5 146)
		(width 0.09)
		(layer "In7.Cu")
		(net 635)
	)
	(segment
		(start 208.425 145.525)
		(end 208.675 145.775)
		(width 0.09)
		(layer "In7.Cu")
		(net 635)
	)
	(segment
		(start 210.5 146)
		(end 210.5 147.485)
		(width 0.09)
		(layer "In7.Cu")
		(net 635)
	)
	(segment
		(start 203.699 141.101)
		(end 204.748 142.15)
		(width 0.09)
		(layer "In7.Cu")
		(net 635)
	)
	(segment
		(start 204.748 142.15)
		(end 207.8 142.15)
		(width 0.09)
		(layer "In7.Cu")
		(net 635)
	)
	(segment
		(start 208.425 142.775)
		(end 208.425 145.525)
		(width 0.09)
		(layer "In7.Cu")
		(net 635)
	)
	(segment
		(start 207.8 142.15)
		(end 208.425 142.775)
		(width 0.09)
		(layer "In7.Cu")
		(net 635)
	)
	(via
		(at 201.3 125.101)
		(size 0.35)
		(drill 0.15)
		(layers "F.Cu" "B.Cu")
		(remove_unused_layers yes)
		(keep_end_layers yes)
		(zone_layer_connections)
		(net 636)
	)
	(via
		(at 216.915 139.25)
		(size 0.35)
		(drill 0.15)
		(layers "F.Cu" "B.Cu")
		(remove_unused_layers yes)
		(keep_end_layers yes)
		(zone_layer_connections)
		(net 636)
	)
	(segment
		(start 216.015 142.115)
		(end 216.015 141.135)
		(width 0.15)
		(layer "B.Cu")
		(net 636)
	)
	(segment
		(start 215.98 141.1)
		(end 216.115 141.1)
		(width 0.15)
		(layer "B.Cu")
		(net 636)
	)
	(segment
		(start 216.115 141.1)
		(end 216.915 140.3)
		(width 0.15)
		(layer "B.Cu")
		(net 636)
	)
	(segment
		(start 216.915 140.3)
		(end 216.915 139.25)
		(width 0.15)
		(layer "B.Cu")
		(net 636)
	)
	(segment
		(start 216.015 141.135)
		(end 215.98 141.1)
		(width 0.15)
		(layer "B.Cu")
		(net 636)
	)
	(segment
		(start 216.364366 137.539671)
		(end 216.364367 137.53967)
		(width 0.09)
		(layer "In2.Cu")
		(net 636)
	)
	(segment
		(start 216.788665 137.9639)
		(end 216.480335 138.272227)
		(width 0.09)
		(layer "In2.Cu")
		(net 636)
	)
	(segment
		(start 211.875 134)
		(end 211.995976 134)
		(width 0.09)
		(layer "In2.Cu")
		(net 636)
	)
	(segment
		(start 216.268204 138.060096)
		(end 216.576533 137.751768)
		(width 0.09)
		(layer "In2.Cu")
		(net 636)
	)
	(segment
		(start 214.146885 135.938775)
		(end 214.146884 135.938776)
		(width 0.09)
		(layer "In2.Cu")
		(net 636)
	)
	(segment
		(start 214.243047 135.41835)
		(end 213.934751 135.726643)
		(width 0.09)
		(layer "In2.Cu")
		(net 636)
	)
	(segment
		(start 201.3 125.101)
		(end 201.633309 125.101)
		(width 0.09)
		(layer "In2.Cu")
		(net 636)
	)
	(segment
		(start 214.783279 136.787303)
		(end 214.78328 136.787304)
		(width 0.09)
		(layer "In2.Cu")
		(net 636)
	)
	(segment
		(start 216.268205 138.060095)
		(end 216.268204 138.060096)
		(width 0.09)
		(layer "In2.Cu")
		(net 636)
	)
	(segment
		(start 207.95 132.7)
		(end 208.95 133.7)
		(width 0.09)
		(layer "In2.Cu")
		(net 636)
	)
	(segment
		(start 214.571149 136.363039)
		(end 214.571148 136.36304)
		(width 0.09)
		(layer "In2.Cu")
		(net 636)
	)
	(segment
		(start 215.84394 137.635832)
		(end 216.152235 137.327538)
		(width 0.09)
		(layer "In2.Cu")
		(net 636)
	)
	(segment
		(start 215.207543 137.211567)
		(end 215.207544 137.211568)
		(width 0.09)
		(layer "In2.Cu")
		(net 636)
	)
	(segment
		(start 215.940075 137.115434)
		(end 215.631807 137.423699)
		(width 0.09)
		(layer "In2.Cu")
		(net 636)
	)
	(segment
		(start 213.722621 135.514511)
		(end 213.72262 135.514512)
		(width 0.09)
		(layer "In2.Cu")
		(net 636)
	)
	(segment
		(start 215.515867 136.691114)
		(end 215.207543 136.999435)
		(width 0.09)
		(layer "In2.Cu")
		(net 636)
	)
	(segment
		(start 214.359015 136.363039)
		(end 214.359016 136.36304)
		(width 0.09)
		(layer "In2.Cu")
		(net 636)
	)
	(segment
		(start 215.419677 137.211567)
		(end 215.419676 137.211568)
		(width 0.09)
		(layer "In2.Cu")
		(net 636)
	)
	(segment
		(start 210.825 133.25)
		(end 210.825 134.05)
		(width 0.09)
		(layer "In2.Cu")
		(net 636)
	)
	(segment
		(start 207.221 125.571)
		(end 207.95 126.3)
		(width 0.09)
		(layer "In2.Cu")
		(net 636)
	)
	(segment
		(start 216.915 138.919024)
		(end 216.915 139.25)
		(width 0.09)
		(layer "In2.Cu")
		(net 636)
	)
	(segment
		(start 213.72262 135.514512)
		(end 214.030915 135.206218)
		(width 0.09)
		(layer "In2.Cu")
		(net 636)
	)
	(segment
		(start 215.091574 136.266879)
		(end 215.091575 136.266878)
		(width 0.09)
		(layer "In2.Cu")
		(net 636)
	)
	(segment
		(start 216.480335 138.484359)
		(end 216.915 138.919024)
		(width 0.09)
		(layer "In2.Cu")
		(net 636)
	)
	(segment
		(start 211.995976 134)
		(end 213.510488 135.514512)
		(width 0.09)
		(layer "In2.Cu")
		(net 636)
	)
	(segment
		(start 215.419676 137.211568)
		(end 215.727943 136.903302)
		(width 0.09)
		(layer "In2.Cu")
		(net 636)
	)
	(segment
		(start 214.667283 135.842642)
		(end 214.359015 136.150907)
		(width 0.09)
		(layer "In2.Cu")
		(net 636)
	)
	(segment
		(start 211.425 133.25)
		(end 211.425 134.15)
		(width 0.09)
		(layer "In2.Cu")
		(net 636)
	)
	(segment
		(start 211.125 134.05)
		(end 211.125 133.25)
		(width 0.09)
		(layer "In2.Cu")
		(net 636)
	)
	(segment
		(start 216.056071 138.060095)
		(end 216.056072 138.060096)
		(width 0.09)
		(layer "In2.Cu")
		(net 636)
	)
	(segment
		(start 208.95 133.7)
		(end 210.075 133.7)
		(width 0.09)
		(layer "In2.Cu")
		(net 636)
	)
	(segment
		(start 215.843941 137.635831)
		(end 215.84394 137.635832)
		(width 0.09)
		(layer "In2.Cu")
		(net 636)
	)
	(segment
		(start 214.667282 135.842643)
		(end 214.667283 135.842642)
		(width 0.09)
		(layer "In2.Cu")
		(net 636)
	)
	(segment
		(start 216.364367 137.53967)
		(end 216.056071 137.847963)
		(width 0.09)
		(layer "In2.Cu")
		(net 636)
	)
	(segment
		(start 213.934751 135.938775)
		(end 213.934752 135.938776)
		(width 0.09)
		(layer "In2.Cu")
		(net 636)
	)
	(segment
		(start 214.995412 136.787304)
		(end 215.303735 136.478982)
		(width 0.09)
		(layer "In2.Cu")
		(net 636)
	)
	(segment
		(start 215.940074 137.115435)
		(end 215.940075 137.115434)
		(width 0.09)
		(layer "In2.Cu")
		(net 636)
	)
	(segment
		(start 215.631807 137.635831)
		(end 215.631808 137.635832)
		(width 0.09)
		(layer "In2.Cu")
		(net 636)
	)
	(segment
		(start 210.525 133.95)
		(end 210.525 133.25)
		(width 0.09)
		(layer "In2.Cu")
		(net 636)
	)
	(segment
		(start 202.103309 125.571)
		(end 207.221 125.571)
		(width 0.09)
		(layer "In2.Cu")
		(net 636)
	)
	(segment
		(start 214.995413 136.787303)
		(end 214.995412 136.787304)
		(width 0.09)
		(layer "In2.Cu")
		(net 636)
	)
	(segment
		(start 201.633309 125.101)
		(end 202.103309 125.571)
		(width 0.09)
		(layer "In2.Cu")
		(net 636)
	)
	(segment
		(start 215.515866 136.691115)
		(end 215.515867 136.691114)
		(width 0.09)
		(layer "In2.Cu")
		(net 636)
	)
	(segment
		(start 214.571148 136.36304)
		(end 214.879443 136.054746)
		(width 0.09)
		(layer "In2.Cu")
		(net 636)
	)
	(segment
		(start 214.146884 135.938776)
		(end 214.455151 135.63051)
		(width 0.09)
		(layer "In2.Cu")
		(net 636)
	)
	(segment
		(start 214.243046 135.418351)
		(end 214.243047 135.41835)
		(width 0.09)
		(layer "In2.Cu")
		(net 636)
	)
	(segment
		(start 215.091575 136.266878)
		(end 214.783279 136.575171)
		(width 0.09)
		(layer "In2.Cu")
		(net 636)
	)
	(segment
		(start 210.225 133.85)
		(end 210.225 133.95)
		(width 0.09)
		(layer "In2.Cu")
		(net 636)
	)
	(segment
		(start 207.95 126.3)
		(end 207.95 132.7)
		(width 0.09)
		(layer "In2.Cu")
		(net 636)
	)
	(segment
		(start 216.788664 137.963901)
		(end 216.788665 137.9639)
		(width 0.09)
		(layer "In2.Cu")
		(net 636)
	)
	(arc
		(start 216.056072 138.060096)
		(mid 216.16214 138.104031)
		(end 216.268205 138.060095)
		(width 0.09)
		(layer "In2.Cu")
		(net 636)
	)
	(arc
		(start 211.725 134.15)
		(mid 211.768934 134.043934)
		(end 211.875 134)
		(width 0.09)
		(layer "In2.Cu")
		(net 636)
	)
	(arc
		(start 215.515867 136.478982)
		(mid 215.5598 136.585048)
		(end 215.515866 136.691115)
		(width 0.09)
		(layer "In2.Cu")
		(net 636)
	)
	(arc
		(start 215.303735 136.478982)
		(mid 215.409801 136.435048)
		(end 215.515867 136.478982)
		(width 0.09)
		(layer "In2.Cu")
		(net 636)
	)
	(arc
		(start 210.375 134.1)
		(mid 210.481066 134.056066)
		(end 210.525 133.95)
		(width 0.09)
		(layer "In2.Cu")
		(net 636)
	)
	(arc
		(start 211.425 134.15)
		(mid 211.468934 134.256066)
		(end 211.575 134.3)
		(width 0.09)
		(layer "In2.Cu")
		(net 636)
	)
	(arc
		(start 214.359015 136.150907)
		(mid 214.315081 136.256973)
		(end 214.359015 136.363039)
		(width 0.09)
		(layer "In2.Cu")
		(net 636)
	)
	(arc
		(start 215.940075 136.903302)
		(mid 215.984008 137.009368)
		(end 215.940074 137.115435)
		(width 0.09)
		(layer "In2.Cu")
		(net 636)
	)
	(arc
		(start 214.243047 135.206218)
		(mid 214.28698 135.312284)
		(end 214.243046 135.418351)
		(width 0.09)
		(layer "In2.Cu")
		(net 636)
	)
	(arc
		(start 210.525 133.25)
		(mid 210.568934 133.143934)
		(end 210.675 133.1)
		(width 0.09)
		(layer "In2.Cu")
		(net 636)
	)
	(arc
		(start 214.667283 135.63051)
		(mid 214.711216 135.736576)
		(end 214.667282 135.842643)
		(width 0.09)
		(layer "In2.Cu")
		(net 636)
	)
	(arc
		(start 211.275 133.1)
		(mid 211.381066 133.143934)
		(end 211.425 133.25)
		(width 0.09)
		(layer "In2.Cu")
		(net 636)
	)
	(arc
		(start 214.879443 136.054746)
		(mid 214.985509 136.010812)
		(end 215.091575 136.054746)
		(width 0.09)
		(layer "In2.Cu")
		(net 636)
	)
	(arc
		(start 216.152235 137.327538)
		(mid 216.258301 137.283604)
		(end 216.364367 137.327538)
		(width 0.09)
		(layer "In2.Cu")
		(net 636)
	)
	(arc
		(start 216.056071 137.847963)
		(mid 216.012137 137.954029)
		(end 216.056071 138.060095)
		(width 0.09)
		(layer "In2.Cu")
		(net 636)
	)
	(arc
		(start 210.675 133.1)
		(mid 210.781066 133.143934)
		(end 210.825 133.25)
		(width 0.09)
		(layer "In2.Cu")
		(net 636)
	)
	(arc
		(start 215.631808 137.635832)
		(mid 215.737876 137.679767)
		(end 215.843941 137.635831)
		(width 0.09)
		(layer "In2.Cu")
		(net 636)
	)
	(arc
		(start 216.576533 137.751768)
		(mid 216.682599 137.707834)
		(end 216.788665 137.751768)
		(width 0.09)
		(layer "In2.Cu")
		(net 636)
	)
	(arc
		(start 215.207544 137.211568)
		(mid 215.313612 137.255503)
		(end 215.419677 137.211567)
		(width 0.09)
		(layer "In2.Cu")
		(net 636)
	)
	(arc
		(start 213.510488 135.514512)
		(mid 213.616556 135.558447)
		(end 213.722621 135.514511)
		(width 0.09)
		(layer "In2.Cu")
		(net 636)
	)
	(arc
		(start 216.788665 137.751768)
		(mid 216.832598 137.857834)
		(end 216.788664 137.963901)
		(width 0.09)
		(layer "In2.Cu")
		(net 636)
	)
	(arc
		(start 215.207543 136.999435)
		(mid 215.163609 137.105501)
		(end 215.207543 137.211567)
		(width 0.09)
		(layer "In2.Cu")
		(net 636)
	)
	(arc
		(start 214.455151 135.63051)
		(mid 214.561217 135.586576)
		(end 214.667283 135.63051)
		(width 0.09)
		(layer "In2.Cu")
		(net 636)
	)
	(arc
		(start 216.480335 138.272227)
		(mid 216.436401 138.378293)
		(end 216.480335 138.484359)
		(width 0.09)
		(layer "In2.Cu")
		(net 636)
	)
	(arc
		(start 215.727943 136.903302)
		(mid 215.834009 136.859368)
		(end 215.940075 136.903302)
		(width 0.09)
		(layer "In2.Cu")
		(net 636)
	)
	(arc
		(start 215.091575 136.054746)
		(mid 215.135508 136.160812)
		(end 215.091574 136.266879)
		(width 0.09)
		(layer "In2.Cu")
		(net 636)
	)
	(arc
		(start 214.359016 136.36304)
		(mid 214.465084 136.406975)
		(end 214.571149 136.363039)
		(width 0.09)
		(layer "In2.Cu")
		(net 636)
	)
	(arc
		(start 214.78328 136.787304)
		(mid 214.889348 136.831239)
		(end 214.995413 136.787303)
		(width 0.09)
		(layer "In2.Cu")
		(net 636)
	)
	(arc
		(start 216.364367 137.327538)
		(mid 216.4083 137.433604)
		(end 216.364366 137.539671)
		(width 0.09)
		(layer "In2.Cu")
		(net 636)
	)
	(arc
		(start 214.030915 135.206218)
		(mid 214.136981 135.162284)
		(end 214.243047 135.206218)
		(width 0.09)
		(layer "In2.Cu")
		(net 636)
	)
	(arc
		(start 211.575 134.3)
		(mid 211.681066 134.256066)
		(end 211.725 134.15)
		(width 0.09)
		(layer "In2.Cu")
		(net 636)
	)
	(arc
		(start 210.075 133.7)
		(mid 210.181066 133.743934)
		(end 210.225 133.85)
		(width 0.09)
		(layer "In2.Cu")
		(net 636)
	)
	(arc
		(start 215.631807 137.423699)
		(mid 215.587873 137.529765)
		(end 215.631807 137.635831)
		(width 0.09)
		(layer "In2.Cu")
		(net 636)
	)
	(arc
		(start 211.125 133.25)
		(mid 211.168934 133.143934)
		(end 211.275 133.1)
		(width 0.09)
		(layer "In2.Cu")
		(net 636)
	)
	(arc
		(start 210.975 134.2)
		(mid 211.081066 134.156066)
		(end 211.125 134.05)
		(width 0.09)
		(layer "In2.Cu")
		(net 636)
	)
	(arc
		(start 213.934752 135.938776)
		(mid 214.04082 135.982711)
		(end 214.146885 135.938775)
		(width 0.09)
		(layer "In2.Cu")
		(net 636)
	)
	(arc
		(start 213.934751 135.726643)
		(mid 213.890817 135.832709)
		(end 213.934751 135.938775)
		(width 0.09)
		(layer "In2.Cu")
		(net 636)
	)
	(arc
		(start 210.225 133.95)
		(mid 210.268934 134.056066)
		(end 210.375 134.1)
		(width 0.09)
		(layer "In2.Cu")
		(net 636)
	)
	(arc
		(start 210.825 134.05)
		(mid 210.868934 134.156066)
		(end 210.975 134.2)
		(width 0.09)
		(layer "In2.Cu")
		(net 636)
	)
	(arc
		(start 214.783279 136.575171)
		(mid 214.739345 136.681237)
		(end 214.783279 136.787303)
		(width 0.09)
		(layer "In2.Cu")
		(net 636)
	)
	(via
		(at 203.699 124.3)
		(size 0.35)
		(drill 0.15)
		(layers "F.Cu" "B.Cu")
		(remove_unused_layers yes)
		(keep_end_layers yes)
		(zone_layer_connections)
		(net 637)
	)
	(via
		(at 216.795836 141.691753)
		(size 0.35)
		(drill 0.15)
		(layers "F.Cu" "B.Cu")
		(remove_unused_layers yes)
		(keep_end_layers yes)
		(zone_layer_connections)
		(net 637)
	)
	(segment
		(start 216.795836 139.745836)
		(end 216.35 139.3)
		(width 0.09)
		(layer "In4.Cu")
		(net 637)
	)
	(segment
		(start 205.075 125.125)
		(end 205.075 124.925)
		(width 0.09)
		(layer "In4.Cu")
		(net 637)
	)
	(segment
		(start 211.093841 127.631159)
		(end 211.093841 127.2)
		(width 0.09)
		(layer "In4.Cu")
		(net 637)
	)
	(segment
		(start 205.425 124.925)
		(end 205.425 125.125)
		(width 0.09)
		(layer "In4.Cu")
		(net 637)
	)
	(segment
		(start 207.05 123.35)
		(end 207.05 123.95)
		(width 0.09)
		(layer "In4.Cu")
		(net 637)
	)
	(segment
		(start 211.093841 126.6)
		(end 211.093841 126.518841)
		(width 0.09)
		(layer "In4.Cu")
		(net 637)
	)
	(segment
		(start 206.45 125.15)
		(end 206.45 124.9)
		(width 0.09)
		(layer "In4.Cu")
		(net 637)
	)
	(segment
		(start 209.775 126.125)
		(end 208.4 124.75)
		(width 0.09)
		(layer "In4.Cu")
		(net 637)
	)
	(segment
		(start 208.4 124.75)
		(end 207.5 124.75)
		(width 0.09)
		(layer "In4.Cu")
		(net 637)
	)
	(segment
		(start 210.7 126.125)
		(end 209.775 126.125)
		(width 0.09)
		(layer "In4.Cu")
		(net 637)
	)
	(segment
		(start 207.2 124.4)
		(end 207.9 124.4)
		(width 0.09)
		(layer "In4.Cu")
		(net 637)
	)
	(segment
		(start 207.35 124.9)
		(end 207.35 125.15)
		(width 0.09)
		(layer "In4.Cu")
		(net 637)
	)
	(segment
		(start 205.775 125.125)
		(end 205.775 124.925)
		(width 0.09)
		(layer "In4.Cu")
		(net 637)
	)
	(segment
		(start 214.05 134.508049)
		(end 213.6 134.058049)
		(width 0.09)
		(layer "In4.Cu")
		(net 637)
	)
	(segment
		(start 212.95 130.675)
		(end 212.2875 130.0125)
		(width 0.09)
		(layer "In4.Cu")
		(net 637)
	)
	(segment
		(start 211.45 127.2)
		(end 211.45 127.411474)
		(width 0.09)
		(layer "In4.Cu")
		(net 637)
	)
	(segment
		(start 212.5 127.05)
		(end 212.843841 127.05)
		(width 0.09)
		(layer "In4.Cu")
		(net 637)
	)
	(segment
		(start 212.35 127.361474)
		(end 212.35 127.2)
		(width 0.09)
		(layer "In4.Cu")
		(net 637)
	)
	(segment
		(start 207.35 123.85)
		(end 207.35 123.95)
		(width 0.09)
		(layer "In4.Cu")
		(net 637)
	)
	(segment
		(start 216.35 137.15)
		(end 214.05 134.85)
		(width 0.09)
		(layer "In4.Cu")
		(net 637)
	)
	(segment
		(start 211.093841 126.518841)
		(end 210.7 126.125)
		(width 0.09)
		(layer "In4.Cu")
		(net 637)
	)
	(segment
		(start 207.05 125.15)
		(end 207.05 124.55)
		(width 0.09)
		(layer "In4.Cu")
		(net 637)
	)
	(segment
		(start 211.75 127.411474)
		(end 211.75 127.2)
		(width 0.09)
		(layer "In4.Cu")
		(net 637)
	)
	(segment
		(start 211.243841 127.05)
		(end 211.3 127.05)
		(width 0.09)
		(layer "In4.Cu")
		(net 637)
	)
	(segment
		(start 212.2875 130.0125)
		(end 211.4875 130.0125)
		(width 0.09)
		(layer "In4.Cu")
		(net 637)
	)
	(segment
		(start 212.95 131.3)
		(end 212.95 130.675)
		(width 0.09)
		(layer "In4.Cu")
		(net 637)
	)
	(segment
		(start 216.35 139.3)
		(end 216.35 137.15)
		(width 0.09)
		(layer "In4.Cu")
		(net 637)
	)
	(segment
		(start 207.9 124.1)
		(end 207.8 124.1)
		(width 0.09)
		(layer "In4.Cu")
		(net 637)
	)
	(segment
		(start 213.6 134.058049)
		(end 213.6 131.95)
		(width 0.09)
		(layer "In4.Cu")
		(net 637)
	)
	(segment
		(start 216.795836 141.691753)
		(end 216.795836 139.745836)
		(width 0.09)
		(layer "In4.Cu")
		(net 637)
	)
	(segment
		(start 204.9 124.75)
		(end 204.149 124.75)
		(width 0.09)
		(layer "In4.Cu")
		(net 637)
	)
	(segment
		(start 211.4875 130.0125)
		(end 211 129.525)
		(width 0.09)
		(layer "In4.Cu")
		(net 637)
	)
	(segment
		(start 212.05 127.2)
		(end 212.05 127.361474)
		(width 0.09)
		(layer "In4.Cu")
		(net 637)
	)
	(segment
		(start 212.843841 126.75)
		(end 211.243841 126.75)
		(width 0.09)
		(layer "In4.Cu")
		(net 637)
	)
	(segment
		(start 211 129.525)
		(end 211 127.725)
		(width 0.09)
		(layer "In4.Cu")
		(net 637)
	)
	(segment
		(start 206.75 123.35)
		(end 206.75 125.15)
		(width 0.09)
		(layer "In4.Cu")
		(net 637)
	)
	(segment
		(start 214.05 134.85)
		(end 214.05 134.508049)
		(width 0.09)
		(layer "In4.Cu")
		(net 637)
	)
	(segment
		(start 204.149 124.75)
		(end 203.699 124.3)
		(width 0.09)
		(layer "In4.Cu")
		(net 637)
	)
	(segment
		(start 207.65 123.95)
		(end 207.65 123.85)
		(width 0.09)
		(layer "In4.Cu")
		(net 637)
	)
	(segment
		(start 211 127.725)
		(end 211.093841 127.631159)
		(width 0.09)
		(layer "In4.Cu")
		(net 637)
	)
	(segment
		(start 206.125 124.925)
		(end 206.125 125.125)
		(width 0.09)
		(layer "In4.Cu")
		(net 637)
	)
	(segment
		(start 213.6 131.95)
		(end 212.95 131.3)
		(width 0.09)
		(layer "In4.Cu")
		(net 637)
	)
	(arc
		(start 212.05 127.361474)
		(mid 212.093934 127.46754)
		(end 212.2 127.511474)
		(width 0.09)
		(layer "In4.Cu")
		(net 637)
	)
	(arc
		(start 211.3 127.05)
		(mid 211.406066 127.093934)
		(end 211.45 127.2)
		(width 0.09)
		(layer "In4.Cu")
		(net 637)
	)
	(arc
		(start 205.425 125.125)
		(mid 205.373744 125.248744)
		(end 205.25 125.3)
		(width 0.09)
		(layer "In4.Cu")
		(net 637)
	)
	(arc
		(start 206.9 123.2)
		(mid 206.793934 123.243934)
		(end 206.75 123.35)
		(width 0.09)
		(layer "In4.Cu")
		(net 637)
	)
	(arc
		(start 206.3 124.75)
		(mid 206.176256 124.801256)
		(end 206.125 124.925)
		(width 0.09)
		(layer "In4.Cu")
		(net 637)
	)
	(arc
		(start 208.05 124.25)
		(mid 208.006066 124.143934)
		(end 207.9 124.1)
		(width 0.09)
		(layer "In4.Cu")
		(net 637)
	)
	(arc
		(start 211.75 127.2)
		(mid 211.793934 127.093934)
		(end 211.9 127.05)
		(width 0.09)
		(layer "In4.Cu")
		(net 637)
	)
	(arc
		(start 205.775 124.925)
		(mid 205.723744 124.801256)
		(end 205.6 124.75)
		(width 0.09)
		(layer "In4.Cu")
		(net 637)
	)
	(arc
		(start 211.9 127.05)
		(mid 212.006066 127.093934)
		(end 212.05 127.2)
		(width 0.09)
		(layer "In4.Cu")
		(net 637)
	)
	(arc
		(start 207.65 123.85)
		(mid 207.606066 123.743934)
		(end 207.5 123.7)
		(width 0.09)
		(layer "In4.Cu")
		(net 637)
	)
	(arc
		(start 211.45 127.411474)
		(mid 211.493934 127.51754)
		(end 211.6 127.561474)
		(width 0.09)
		(layer "In4.Cu")
		(net 637)
	)
	(arc
		(start 205.075 124.925)
		(mid 205.023744 124.801256)
		(end 204.9 124.75)
		(width 0.09)
		(layer "In4.Cu")
		(net 637)
	)
	(arc
		(start 211.6 127.561474)
		(mid 211.706066 127.51754)
		(end 211.75 127.411474)
		(width 0.09)
		(layer "In4.Cu")
		(net 637)
	)
	(arc
		(start 207.2 125.3)
		(mid 207.093934 125.256066)
		(end 207.05 125.15)
		(width 0.09)
		(layer "In4.Cu")
		(net 637)
	)
	(arc
		(start 207.05 123.35)
		(mid 207.006066 123.243934)
		(end 206.9 123.2)
		(width 0.09)
		(layer "In4.Cu")
		(net 637)
	)
	(arc
		(start 211.093841 127.2)
		(mid 211.137775 127.093934)
		(end 211.243841 127.05)
		(width 0.09)
		(layer "In4.Cu")
		(net 637)
	)
	(arc
		(start 206.45 124.9)
		(mid 206.406066 124.793934)
		(end 206.3 124.75)
		(width 0.09)
		(layer "In4.Cu")
		(net 637)
	)
	(arc
		(start 207.5 123.7)
		(mid 207.393934 123.743934)
		(end 207.35 123.85)
		(width 0.09)
		(layer "In4.Cu")
		(net 637)
	)
	(arc
		(start 207.05 124.55)
		(mid 207.093934 124.443934)
		(end 207.2 124.4)
		(width 0.09)
		(layer "In4.Cu")
		(net 637)
	)
	(arc
		(start 212.993841 126.9)
		(mid 212.949907 126.793934)
		(end 212.843841 126.75)
		(width 0.09)
		(layer "In4.Cu")
		(net 637)
	)
	(arc
		(start 211.243841 126.75)
		(mid 211.137775 126.706066)
		(end 211.093841 126.6)
		(width 0.09)
		(layer "In4.Cu")
		(net 637)
	)
	(arc
		(start 212.843841 127.05)
		(mid 212.949907 127.006066)
		(end 212.993841 126.9)
		(width 0.09)
		(layer "In4.Cu")
		(net 637)
	)
	(arc
		(start 205.25 125.3)
		(mid 205.126256 125.248744)
		(end 205.075 125.125)
		(width 0.09)
		(layer "In4.Cu")
		(net 637)
	)
	(arc
		(start 207.35 125.15)
		(mid 207.306066 125.256066)
		(end 207.2 125.3)
		(width 0.09)
		(layer "In4.Cu")
		(net 637)
	)
	(arc
		(start 206.6 125.3)
		(mid 206.493934 125.256066)
		(end 206.45 125.15)
		(width 0.09)
		(layer "In4.Cu")
		(net 637)
	)
	(arc
		(start 206.75 125.15)
		(mid 206.706066 125.256066)
		(end 206.6 125.3)
		(width 0.09)
		(layer "In4.Cu")
		(net 637)
	)
	(arc
		(start 207.9 124.4)
		(mid 208.006066 124.356066)
		(end 208.05 124.25)
		(width 0.09)
		(layer "In4.Cu")
		(net 637)
	)
	(arc
		(start 205.6 124.75)
		(mid 205.476256 124.801256)
		(end 205.425 124.925)
		(width 0.09)
		(layer "In4.Cu")
		(net 637)
	)
	(arc
		(start 207.5 124.75)
		(mid 207.393934 124.793934)
		(end 207.35 124.9)
		(width 0.09)
		(layer "In4.Cu")
		(net 637)
	)
	(arc
		(start 207.2 124.1)
		(mid 207.093934 124.056066)
		(end 207.05 123.95)
		(width 0.09)
		(layer "In4.Cu")
		(net 637)
	)
	(arc
		(start 212.2 127.511474)
		(mid 212.306066 127.46754)
		(end 212.35 127.361474)
		(width 0.09)
		(layer "In4.Cu")
		(net 637)
	)
	(arc
		(start 207.35 123.95)
		(mid 207.306066 124.056066)
		(end 207.2 124.1)
		(width 0.09)
		(layer "In4.Cu")
		(net 637)
	)
	(arc
		(start 207.8 124.1)
		(mid 207.693934 124.056066)
		(end 207.65 123.95)
		(width 0.09)
		(layer "In4.Cu")
		(net 637)
	)
	(arc
		(start 212.35 127.2)
		(mid 212.393934 127.093934)
		(end 212.5 127.05)
		(width 0.09)
		(layer "In4.Cu")
		(net 637)
	)
	(arc
		(start 205.95 125.3)
		(mid 205.826256 125.248744)
		(end 205.775 125.125)
		(width 0.09)
		(layer "In4.Cu")
		(net 637)
	)
	(arc
		(start 206.125 125.125)
		(mid 206.073744 125.248744)
		(end 205.95 125.3)
		(width 0.09)
		(layer "In4.Cu")
		(net 637)
	)
	(via
		(at 217.075 142.15)
		(size 0.35)
		(drill 0.15)
		(layers "F.Cu" "B.Cu")
		(remove_unused_layers yes)
		(keep_end_layers yes)
		(zone_layer_connections)
		(net 638)
	)
	(via
		(at 203.699 125.101)
		(size 0.35)
		(drill 0.15)
		(layers "F.Cu" "B.Cu")
		(remove_unused_layers yes)
		(keep_end_layers yes)
		(zone_layer_connections)
		(net 638)
	)
	(segment
		(start 210.111764 127.036764)
		(end 210.111763 127.036763)
		(width 0.09)
		(layer "In4.Cu")
		(net 638)
	)
	(segment
		(start 213.75 135.4)
		(end 213.25 135.4)
		(width 0.09)
		(layer "In4.Cu")
		(net 638)
	)
	(segment
		(start 212.35 133.95)
		(end 211.85 133.95)
		(width 0.09)
		(layer "In4.Cu")
		(net 638)
	)
	(segment
		(start 215.85 139.35)
		(end 215.85 137.5)
		(width 0.09)
		(layer "In4.Cu")
		(net 638)
	)
	(segment
		(start 206.625 125.675)
		(end 206.625 125.925)
		(width 0.09)
		(layer "In4.Cu")
		(net 638)
	)
	(segment
		(start 204.7 125.5)
		(end 204.098 125.5)
		(width 0.09)
		(layer "In4.Cu")
		(net 638)
	)
	(segment
		(start 213.25 132.75)
		(end 211.85 132.75)
		(width 0.09)
		(layer "In4.Cu")
		(net 638)
	)
	(segment
		(start 212.85 135)
		(end 212.85 134.6)
		(width 0.09)
		(layer "In4.Cu")
		(net 638)
	)
	(segment
		(start 215.85 137.5)
		(end 213.75 135.4)
		(width 0.09)
		(layer "In4.Cu")
		(net 638)
	)
	(segment
		(start 208.485 125.41)
		(end 207.97 125.41)
		(width 0.09)
		(layer "In4.Cu")
		(net 638)
	)
	(segment
		(start 212.5 130.725)
		(end 212.219976 130.444976)
		(width 0.09)
		(layer "In4.Cu")
		(net 638)
	)
	(segment
		(start 210.7 129.889951)
		(end 210.7 127.625)
		(width 0.09)
		(layer "In4.Cu")
		(net 638)
	)
	(segment
		(start 212.85 134.6)
		(end 212.5 134.25)
		(width 0.09)
		(layer "In4.Cu")
		(net 638)
	)
	(segment
		(start 216.787392 142.15)
		(end 216.444 141.806608)
		(width 0.09)
		(layer "In4.Cu")
		(net 638)
	)
	(segment
		(start 211.255024 130.444976)
		(end 210.7 129.889951)
		(width 0.09)
		(layer "In4.Cu")
		(net 638)
	)
	(segment
		(start 207.97 125.41)
		(end 207.88 125.5)
		(width 0.09)
		(layer "In4.Cu")
		(net 638)
	)
	(segment
		(start 210.7 127.625)
		(end 210.536027 127.461027)
		(width 0.09)
		(layer "In4.Cu")
		(net 638)
	)
	(segment
		(start 212.219976 130.444976)
		(end 211.255024 130.444976)
		(width 0.09)
		(layer "In4.Cu")
		(net 638)
	)
	(segment
		(start 211.85 132.45)
		(end 213.25 132.45)
		(width 0.09)
		(layer "In4.Cu")
		(net 638)
	)
	(segment
		(start 204.875 125.925)
		(end 204.875 125.675)
		(width 0.09)
		(layer "In4.Cu")
		(net 638)
	)
	(segment
		(start 212.5 134.25)
		(end 212.5 134.1)
		(width 0.09)
		(layer "In4.Cu")
		(net 638)
	)
	(segment
		(start 212.75 133.35)
		(end 211.85 133.35)
		(width 0.09)
		(layer "In4.Cu")
		(net 638)
	)
	(segment
		(start 213.25 132.15)
		(end 212.65 132.15)
		(width 0.09)
		(layer "In4.Cu")
		(net 638)
	)
	(segment
		(start 210.642095 126.718566)
		(end 210.323897 127.036763)
		(width 0.09)
		(layer "In4.Cu")
		(net 638)
	)
	(segment
		(start 210.854227 126.930698)
		(end 210.854226 126.930699)
		(width 0.09)
		(layer "In4.Cu")
		(net 638)
	)
	(segment
		(start 216.444 141.806608)
		(end 216.444 139.944)
		(width 0.09)
		(layer "In4.Cu")
		(net 638)
	)
	(segment
		(start 206.275 125.925)
		(end 206.275 125.675)
		(width 0.09)
		(layer "In4.Cu")
		(net 638)
	)
	(segment
		(start 205.925 125.675)
		(end 205.925 125.925)
		(width 0.09)
		(layer "In4.Cu")
		(net 638)
	)
	(segment
		(start 210.536027 127.248895)
		(end 210.854227 126.930698)
		(width 0.09)
		(layer "In4.Cu")
		(net 638)
	)
	(segment
		(start 205.575 125.925)
		(end 205.575 125.675)
		(width 0.09)
		(layer "In4.Cu")
		(net 638)
	)
	(segment
		(start 207.325 125.675)
		(end 207.325 125.925)
		(width 0.09)
		(layer "In4.Cu")
		(net 638)
	)
	(segment
		(start 210.111763 126.824631)
		(end 210.253186 126.683211)
		(width 0.09)
		(layer "In4.Cu")
		(net 638)
	)
	(segment
		(start 216.444 139.944)
		(end 215.85 139.35)
		(width 0.09)
		(layer "In4.Cu")
		(net 638)
	)
	(segment
		(start 206.975 125.925)
		(end 206.975 125.675)
		(width 0.09)
		(layer "In4.Cu")
		(net 638)
	)
	(segment
		(start 204.098 125.5)
		(end 203.699 125.101)
		(width 0.09)
		(layer "In4.Cu")
		(net 638)
	)
	(segment
		(start 205.225 125.675)
		(end 205.225 125.925)
		(width 0.09)
		(layer "In4.Cu")
		(net 638)
	)
	(segment
		(start 211.85 133.65)
		(end 212.75 133.65)
		(width 0.09)
		(layer "In4.Cu")
		(net 638)
	)
	(segment
		(start 211.85 133.05)
		(end 213.25 133.05)
		(width 0.09)
		(layer "In4.Cu")
		(net 638)
	)
	(segment
		(start 217.075 142.15)
		(end 216.787392 142.15)
		(width 0.09)
		(layer "In4.Cu")
		(net 638)
	)
	(segment
		(start 209.6875 126.6125)
		(end 208.485 125.41)
		(width 0.09)
		(layer "In4.Cu")
		(net 638)
	)
	(segment
		(start 213.25 135.4)
		(end 212.85 135)
		(width 0.09)
		(layer "In4.Cu")
		(net 638)
	)
	(segment
		(start 210.253186 126.683211)
		(end 210.253185 126.683212)
		(width 0.09)
		(layer "In4.Cu")
		(net 638)
	)
	(segment
		(start 212.5 132)
		(end 212.5 130.725)
		(width 0.09)
		(layer "In4.Cu")
		(net 638)
	)
	(segment
		(start 207.88 125.5)
		(end 207.5 125.5)
		(width 0.09)
		(layer "In4.Cu")
		(net 638)
	)
	(segment
		(start 210.041054 126.471079)
		(end 209.899633 126.612499)
		(width 0.09)
		(layer "In4.Cu")
		(net 638)
	)
	(arc
		(start 211.85 133.95)
		(mid 211.743934 133.906066)
		(end 211.7 133.8)
		(width 0.09)
		(layer "In4.Cu")
		(net 638)
	)
	(arc
		(start 205.925 125.925)
		(mid 205.873744 126.048744)
		(end 205.75 126.1)
		(width 0.09)
		(layer "In4.Cu")
		(net 638)
	)
	(arc
		(start 205.225 125.925)
		(mid 205.173744 126.048744)
		(end 205.05 126.1)
		(width 0.09)
		(layer "In4.Cu")
		(net 638)
	)
	(arc
		(start 205.575 125.675)
		(mid 205.523744 125.551256)
		(end 205.4 125.5)
		(width 0.09)
		(layer "In4.Cu")
		(net 638)
	)
	(arc
		(start 205.05 126.1)
		(mid 204.926256 126.048744)
		(end 204.875 125.925)
		(width 0.09)
		(layer "In4.Cu")
		(net 638)
	)
	(arc
		(start 211.7 133.2)
		(mid 211.743934 133.093934)
		(end 211.85 133.05)
		(width 0.09)
		(layer "In4.Cu")
		(net 638)
	)
	(arc
		(start 213.25 132.45)
		(mid 213.356066 132.406066)
		(end 213.4 132.3)
		(width 0.09)
		(layer "In4.Cu")
		(net 638)
	)
	(arc
		(start 211.85 133.35)
		(mid 211.743934 133.306066)
		(end 211.7 133.2)
		(width 0.09)
		(layer "In4.Cu")
		(net 638)
	)
	(arc
		(start 212.9 133.5)
		(mid 212.856066 133.393934)
		(end 212.75 133.35)
		(width 0.09)
		(layer "In4.Cu")
		(net 638)
	)
	(arc
		(start 213.4 132.3)
		(mid 213.356066 132.193934)
		(end 213.25 132.15)
		(width 0.09)
		(layer "In4.Cu")
		(net 638)
	)
	(arc
		(start 213.25 133.05)
		(mid 213.356066 133.006066)
		(end 213.4 132.9)
		(width 0.09)
		(layer "In4.Cu")
		(net 638)
	)
	(arc
		(start 212.5 134.1)
		(mid 212.456066 133.993934)
		(end 212.35 133.95)
		(width 0.09)
		(layer "In4.Cu")
		(net 638)
	)
	(arc
		(start 211.7 133.8)
		(mid 211.743934 133.693934)
		(end 211.85 133.65)
		(width 0.09)
		(layer "In4.Cu")
		(net 638)
	)
	(arc
		(start 210.323897 127.036763)
		(mid 210.217832 127.080699)
		(end 210.111764 127.036764)
		(width 0.09)
		(layer "In4.Cu")
		(net 638)
	)
	(arc
		(start 206.1 125.5)
		(mid 205.976256 125.551256)
		(end 205.925 125.675)
		(width 0.09)
		(layer "In4.Cu")
		(net 638)
	)
	(arc
		(start 210.253186 126.471079)
		(mid 210.14712 126.427145)
		(end 210.041054 126.471079)
		(width 0.09)
		(layer "In4.Cu")
		(net 638)
	)
	(arc
		(start 210.854227 126.718566)
		(mid 210.748161 126.674632)
		(end 210.642095 126.718566)
		(width 0.09)
		(layer "In4.Cu")
		(net 638)
	)
	(arc
		(start 210.854226 126.930699)
		(mid 210.89816 126.824632)
		(end 210.854227 126.718566)
		(width 0.09)
		(layer "In4.Cu")
		(net 638)
	)
	(arc
		(start 210.111763 127.036763)
		(mid 210.067829 126.930697)
		(end 210.111763 126.824631)
		(width 0.09)
		(layer "In4.Cu")
		(net 638)
	)
	(arc
		(start 213.4 132.9)
		(mid 213.356066 132.793934)
		(end 213.25 132.75)
		(width 0.09)
		(layer "In4.Cu")
		(net 638)
	)
	(arc
		(start 210.253185 126.683212)
		(mid 210.297119 126.577145)
		(end 210.253186 126.471079)
		(width 0.09)
		(layer "In4.Cu")
		(net 638)
	)
	(arc
		(start 206.275 125.675)
		(mid 206.223744 125.551256)
		(end 206.1 125.5)
		(width 0.09)
		(layer "In4.Cu")
		(net 638)
	)
	(arc
		(start 207.15 126.1)
		(mid 207.026256 126.048744)
		(end 206.975 125.925)
		(width 0.09)
		(layer "In4.Cu")
		(net 638)
	)
	(arc
		(start 211.85 132.75)
		(mid 211.743934 132.706066)
		(end 211.7 132.6)
		(width 0.09)
		(layer "In4.Cu")
		(net 638)
	)
	(arc
		(start 206.625 125.925)
		(mid 206.573744 126.048744)
		(end 206.45 126.1)
		(width 0.09)
		(layer "In4.Cu")
		(net 638)
	)
	(arc
		(start 207.5 125.5)
		(mid 207.376256 125.551256)
		(end 207.325 125.675)
		(width 0.09)
		(layer "In4.Cu")
		(net 638)
	)
	(arc
		(start 211.7 132.6)
		(mid 211.743934 132.493934)
		(end 211.85 132.45)
		(width 0.09)
		(layer "In4.Cu")
		(net 638)
	)
	(arc
		(start 212.65 132.15)
		(mid 212.543934 132.106066)
		(end 212.5 132)
		(width 0.09)
		(layer "In4.Cu")
		(net 638)
	)
	(arc
		(start 207.325 125.925)
		(mid 207.273744 126.048744)
		(end 207.15 126.1)
		(width 0.09)
		(layer "In4.Cu")
		(net 638)
	)
	(arc
		(start 210.536027 127.461027)
		(mid 210.492093 127.354961)
		(end 210.536027 127.248895)
		(width 0.09)
		(layer "In4.Cu")
		(net 638)
	)
	(arc
		(start 209.899633 126.612499)
		(mid 209.793568 126.656435)
		(end 209.6875 126.6125)
		(width 0.09)
		(layer "In4.Cu")
		(net 638)
	)
	(arc
		(start 205.4 125.5)
		(mid 205.276256 125.551256)
		(end 205.225 125.675)
		(width 0.09)
		(layer "In4.Cu")
		(net 638)
	)
	(arc
		(start 204.875 125.675)
		(mid 204.823744 125.551256)
		(end 204.7 125.5)
		(width 0.09)
		(layer "In4.Cu")
		(net 638)
	)
	(arc
		(start 205.75 126.1)
		(mid 205.626256 126.048744)
		(end 205.575 125.925)
		(width 0.09)
		(layer "In4.Cu")
		(net 638)
	)
	(arc
		(start 206.975 125.675)
		(mid 206.923744 125.551256)
		(end 206.8 125.5)
		(width 0.09)
		(layer "In4.Cu")
		(net 638)
	)
	(arc
		(start 206.45 126.1)
		(mid 206.326256 126.048744)
		(end 206.275 125.925)
		(width 0.09)
		(layer "In4.Cu")
		(net 638)
	)
	(arc
		(start 206.8 125.5)
		(mid 206.676256 125.551256)
		(end 206.625 125.675)
		(width 0.09)
		(layer "In4.Cu")
		(net 638)
	)
	(arc
		(start 212.75 133.65)
		(mid 212.856066 133.606066)
		(end 212.9 133.5)
		(width 0.09)
		(layer "In4.Cu")
		(net 638)
	)
	(via
		(at 202.9 124.3)
		(size 0.35)
		(drill 0.15)
		(layers "F.Cu" "B.Cu")
		(remove_unused_layers yes)
		(keep_end_layers yes)
		(zone_layer_connections)
		(net 639)
	)
	(via
		(at 215.113 140.05)
		(size 0.35)
		(drill 0.15)
		(layers "F.Cu" "B.Cu")
		(remove_unused_layers yes)
		(keep_end_layers yes)
		(zone_layer_connections)
		(net 639)
	)
	(segment
		(start 207.185049 126.375)
		(end 207 126.375)
		(width 0.09)
		(layer "In4.Cu")
		(net 639)
	)
	(segment
		(start 202.85 126.575)
		(end 202.85 126.425)
		(width 0.09)
		(layer "In4.Cu")
		(net 639)
	)
	(segment
		(start 211.585287 132.176789)
		(end 211.625 132.175)
		(width 0.09)
		(layer "In4.Cu")
		(net 639)
	)
	(segment
		(start 210.3 128.393938)
		(end 210.240531 128.334469)
		(width 0.09)
		(layer "In4.Cu")
		(net 639)
	)
	(segment
		(start 206.55 126.725)
		(end 206.55 126.525)
		(width 0.09)
		(layer "In4.Cu")
		(net 639)
	)
	(segment
		(start 212.106215 132.173211)
		(end 212.175 132.133498)
		(width 0.09)
		(layer "In4.Cu")
		(net 639)
	)
	(segment
		(start 209.377076 126.905328)
		(end 209.377077 126.905328)
		(width 0.09)
		(layer "In4.Cu")
		(net 639)
	)
	(segment
		(start 209.377078 126.657841)
		(end 209.377077 126.65784)
		(width 0.09)
		(layer "In4.Cu")
		(net 639)
	)
	(segment
		(start 203.33 126.59)
		(end 203.33 126.71)
		(width 0.09)
		(layer "In4.Cu")
		(net 639)
	)
	(segment
		(start 208.316419 125.98609)
		(end 208.316419 125.986091)
		(width 0.09)
		(layer "In4.Cu")
		(net 639)
	)
	(segment
		(start 212.066502 132.175)
		(end 212.106215 132.173211)
		(width 0.09)
		(layer "In4.Cu")
		(net 639)
	)
	(segment
		(start 215.5 139.3)
		(end 215.5 137.9)
		(width 0.09)
		(layer "In4.Cu")
		(net 639)
	)
	(segment
		(start 203.19 126.85)
		(end 203.125 126.85)
		(width 0.09)
		(layer "In4.Cu")
		(net 639)
	)
	(segment
		(start 212.214713 131.985287)
		(end 212.214713 130.989713)
		(width 0.09)
		(layer "In4.Cu")
		(net 639)
	)
	(segment
		(start 211.516502 132.216502)
		(end 211.585287 132.176789)
		(width 0.09)
		(layer "In4.Cu")
		(net 639)
	)
	(segment
		(start 208.003768 125.803768)
		(end 208.003765 125.803768)
		(width 0.09)
		(layer "In4.Cu")
		(net 639)
	)
	(segment
		(start 208.634616 126.162867)
		(end 207.927511 126.869975)
		(width 0.09)
		(layer "In4.Cu")
		(net 639)
	)
	(segment
		(start 203.8 126.85)
		(end 203.75 126.85)
		(width 0.09)
		(layer "In4.Cu")
		(net 639)
	)
	(segment
		(start 208.882535 127.605022)
		(end 208.953246 127.675734)
		(width 0.09)
		(layer "In4.Cu")
		(net 639)
	)
	(segment
		(start 211.475 132.325)
		(end 211.476789 132.285287)
		(width 0.09)
		(layer "In4.Cu")
		(net 639)
	)
	(segment
		(start 211.476789 132.285287)
		(end 211.516502 132.216502)
		(width 0.09)
		(layer "In4.Cu")
		(net 639)
	)
	(segment
		(start 210.24053 128.122336)
		(end 210.452663 127.910203)
		(width 0.09)
		(layer "In4.Cu")
		(net 639)
	)
	(segment
		(start 212.214713 130.989713)
		(end 212 130.775)
		(width 0.09)
		(layer "In4.Cu")
		(net 639)
	)
	(segment
		(start 212.216502 132.025)
		(end 212.214713 131.985287)
		(width 0.09)
		(layer "In4.Cu")
		(net 639)
	)
	(segment
		(start 215.5 137.9)
		(end 213.425 135.825)
		(width 0.09)
		(layer "In4.Cu")
		(net 639)
	)
	(segment
		(start 208.705758 128.170708)
		(end 208.705757 128.170707)
		(width 0.09)
		(layer "In4.Cu")
		(net 639)
	)
	(segment
		(start 202.85 125.825)
		(end 202.85 125.725)
		(width 0.09)
		(layer "In4.Cu")
		(net 639)
	)
	(segment
		(start 203.15 125.975)
		(end 203 125.975)
		(width 0.09)
		(layer "In4.Cu")
		(net 639)
	)
	(segment
		(start 209.532688 127.909468)
		(end 209.532689 127.909468)
		(width 0.09)
		(layer "In4.Cu")
		(net 639)
	)
	(segment
		(start 208.003765 125.803768)
		(end 207.650212 126.157321)
		(width 0.09)
		(layer "In4.Cu")
		(net 639)
	)
	(segment
		(start 211.625 132.175)
		(end 212.066502 132.175)
		(width 0.09)
		(layer "In4.Cu")
		(net 639)
	)
	(segment
		(start 210.3 128.525)
		(end 210.3 128.393938)
		(width 0.09)
		(layer "In4.Cu")
		(net 639)
	)
	(segment
		(start 204.275 126.375)
		(end 203.8 126.85)
		(width 0.09)
		(layer "In4.Cu")
		(net 639)
	)
	(segment
		(start 206.85 126.525)
		(end 206.85 126.725)
		(width 0.09)
		(layer "In4.Cu")
		(net 639)
	)
	(segment
		(start 211.05 130.775)
		(end 210.3 130.025)
		(width 0.09)
		(layer "In4.Cu")
		(net 639)
	)
	(segment
		(start 209.506388 128.675)
		(end 210.15 128.675)
		(width 0.09)
		(layer "In4.Cu")
		(net 639)
	)
	(segment
		(start 210.15 128.975)
		(end 209.506388 128.975)
		(width 0.09)
		(layer "In4.Cu")
		(net 639)
	)
	(segment
		(start 208.882105 126.410355)
		(end 208.882103 126.410354)
		(width 0.09)
		(layer "In4.Cu")
		(net 639)
	)
	(segment
		(start 209.235655 127.046749)
		(end 209.377076 126.905328)
		(width 0.09)
		(layer "In4.Cu")
		(net 639)
	)
	(segment
		(start 213.425 135.825)
		(end 212.825 135.825)
		(width 0.09)
		(layer "In4.Cu")
		(net 639)
	)
	(segment
		(start 208.174997 127.11746)
		(end 208.882105 126.410355)
		(width 0.09)
		(layer "In4.Cu")
		(net 639)
	)
	(segment
		(start 209.816265 127.910203)
		(end 209.815531 127.909469)
		(width 0.09)
		(layer "In4.Cu")
		(net 639)
	)
	(segment
		(start 215.113 140.05)
		(end 215.113 139.687)
		(width 0.09)
		(layer "In4.Cu")
		(net 639)
	)
	(segment
		(start 210.3 130.025)
		(end 210.3 129.125)
		(width 0.09)
		(layer "In4.Cu")
		(net 639)
	)
	(segment
		(start 207.432537 126.375001)
		(end 207.432536 126.374999)
		(width 0.09)
		(layer "In4.Cu")
		(net 639)
	)
	(segment
		(start 212.214713 132.064713)
		(end 212.216502 132.025)
		(width 0.09)
		(layer "In4.Cu")
		(net 639)
	)
	(segment
		(start 203.3 124.7)
		(end 202.9 124.3)
		(width 0.09)
		(layer "In4.Cu")
		(net 639)
	)
	(segment
		(start 203.61 126.71)
		(end 203.61 126.59)
		(width 0.09)
		(layer "In4.Cu")
		(net 639)
	)
	(segment
		(start 212.825 135.825)
		(end 211.475 134.475)
		(width 0.09)
		(layer "In4.Cu")
		(net 639)
	)
	(segment
		(start 209.532689 127.909468)
		(end 208.860935 128.581217)
		(width 0.09)
		(layer "In4.Cu")
		(net 639)
	)
	(segment
		(start 211.475 134.475)
		(end 211.475 132.325)
		(width 0.09)
		(layer "In4.Cu")
		(net 639)
	)
	(segment
		(start 207.927511 126.869975)
		(end 207.92751 126.869973)
		(width 0.09)
		(layer "In4.Cu")
		(net 639)
	)
	(segment
		(start 209.12959 126.657841)
		(end 208.422485 127.364949)
		(width 0.09)
		(layer "In4.Cu")
		(net 639)
	)
	(segment
		(start 210.028397 127.910203)
		(end 210.24053 127.69807)
		(width 0.09)
		(layer "In4.Cu")
		(net 639)
	)
	(segment
		(start 209.249845 127.343781)
		(end 209.235655 127.329591)
		(width 0.09)
		(layer "In4.Cu")
		(net 639)
	)
	(segment
		(start 206.4 126.375)
		(end 204.275 126.375)
		(width 0.09)
		(layer "In4.Cu")
		(net 639)
	)
	(segment
		(start 208.635048 127.605022)
		(end 208.635048 127.605021)
		(width 0.09)
		(layer "In4.Cu")
		(net 639)
	)
	(segment
		(start 207.680023 126.622487)
		(end 208.316419 125.98609)
		(width 0.09)
		(layer "In4.Cu")
		(net 639)
	)
	(segment
		(start 208.882104 126.162867)
		(end 208.882103 126.162866)
		(width 0.09)
		(layer "In4.Cu")
		(net 639)
	)
	(segment
		(start 207.650212 126.157321)
		(end 207.432537 126.375001)
		(width 0.09)
		(layer "In4.Cu")
		(net 639)
	)
	(segment
		(start 215.113 139.687)
		(end 215.5 139.3)
		(width 0.09)
		(layer "In4.Cu")
		(net 639)
	)
	(segment
		(start 208.068932 125.738603)
		(end 208.003768 125.803768)
		(width 0.09)
		(layer "In4.Cu")
		(net 639)
	)
	(segment
		(start 208.422485 127.364949)
		(end 208.422484 127.364947)
		(width 0.09)
		(layer "In4.Cu")
		(net 639)
	)
	(segment
		(start 212 130.775)
		(end 211.05 130.775)
		(width 0.09)
		(layer "In4.Cu")
		(net 639)
	)
	(segment
		(start 208.31642 125.738604)
		(end 208.316419 125.738604)
		(width 0.09)
		(layer "In4.Cu")
		(net 639)
	)
	(segment
		(start 207.680023 126.869974)
		(end 207.680024 126.869974)
		(width 0.09)
		(layer "In4.Cu")
		(net 639)
	)
	(segment
		(start 203.3 125.275)
		(end 203.3 124.7)
		(width 0.09)
		(layer "In4.Cu")
		(net 639)
	)
	(segment
		(start 209.200734 127.675734)
		(end 209.249844 127.626624)
		(width 0.09)
		(layer "In4.Cu")
		(net 639)
	)
	(segment
		(start 212.175 132.133498)
		(end 212.214713 132.064713)
		(width 0.09)
		(layer "In4.Cu")
		(net 639)
	)
	(segment
		(start 208.578093 128.581217)
		(end 208.578092 128.581217)
		(width 0.09)
		(layer "In4.Cu")
		(net 639)
	)
	(segment
		(start 208.578093 128.298374)
		(end 208.705758 128.170708)
		(width 0.09)
		(layer "In4.Cu")
		(net 639)
	)
	(segment
		(start 203 126.275)
		(end 203.15 126.275)
		(width 0.09)
		(layer "In4.Cu")
		(net 639)
	)
	(segment
		(start 202.85 125.725)
		(end 203.3 125.275)
		(width 0.09)
		(layer "In4.Cu")
		(net 639)
	)
	(segment
		(start 203.125 126.85)
		(end 202.85 126.575)
		(width 0.09)
		(layer "In4.Cu")
		(net 639)
	)
	(segment
		(start 208.635047 127.852509)
		(end 208.635048 127.852508)
		(width 0.09)
		(layer "In4.Cu")
		(net 639)
	)
	(segment
		(start 208.174997 127.364948)
		(end 208.174996 127.364947)
		(width 0.09)
		(layer "In4.Cu")
		(net 639)
	)
	(segment
		(start 208.705757 127.923219)
		(end 208.635047 127.852509)
		(width 0.09)
		(layer "In4.Cu")
		(net 639)
	)
	(arc
		(start 208.860935 128.581217)
		(mid 208.719513 128.639796)
		(end 208.578093 128.581217)
		(width 0.09)
		(layer "In4.Cu")
		(net 639)
	)
	(arc
		(start 210.240531 128.334469)
		(mid 210.196596 128.228403)
		(end 210.24053 128.122336)
		(width 0.09)
		(layer "In4.Cu")
		(net 639)
	)
	(arc
		(start 210.452663 127.910203)
		(mid 210.496597 127.804137)
		(end 210.452663 127.698071)
		(width 0.09)
		(layer "In4.Cu")
		(net 639)
	)
	(arc
		(start 209.377077 126.65784)
		(mid 209.253333 126.606584)
		(end 209.12959 126.657841)
		(width 0.09)
		(layer "In4.Cu")
		(net 639)
	)
	(arc
		(start 208.174996 127.364947)
		(mid 208.12374 127.241203)
		(end 208.174997 127.11746)
		(width 0.09)
		(layer "In4.Cu")
		(net 639)
	)
	(arc
		(start 208.635048 127.852508)
		(mid 208.583792 127.728765)
		(end 208.635048 127.605022)
		(width 0.09)
		(layer "In4.Cu")
		(net 639)
	)
	(arc
		(start 210.3 129.125)
		(mid 210.256066 129.018934)
		(end 210.15 128.975)
		(width 0.09)
		(layer "In4.Cu")
		(net 639)
	)
	(arc
		(start 209.356388 128.825)
		(mid 209.400322 128.718934)
		(end 209.506388 128.675)
		(width 0.09)
		(layer "In4.Cu")
		(net 639)
	)
	(arc
		(start 208.578092 128.581217)
		(mid 208.519515 128.439796)
		(end 208.578093 128.298374)
		(width 0.09)
		(layer "In4.Cu")
		(net 639)
	)
	(arc
		(start 207.92751 126.869973)
		(mid 207.803767 126.92123)
		(end 207.680023 126.869974)
		(width 0.09)
		(layer "In4.Cu")
		(net 639)
	)
	(arc
		(start 207.680024 126.869974)
		(mid 207.628767 126.746231)
		(end 207.680023 126.622487)
		(width 0.09)
		(layer "In4.Cu")
		(net 639)
	)
	(arc
		(start 208.705757 128.170707)
		(mid 208.757013 128.046963)
		(end 208.705757 127.923219)
		(width 0.09)
		(layer "In4.Cu")
		(net 639)
	)
	(arc
		(start 203.61 126.59)
		(mid 203.568995 126.491005)
		(end 203.47 126.45)
		(width 0.09)
		(layer "In4.Cu")
		(net 639)
	)
	(arc
		(start 203.75 126.85)
		(mid 203.651005 126.808995)
		(end 203.61 126.71)
		(width 0.09)
		(layer "In4.Cu")
		(net 639)
	)
	(arc
		(start 210.15 128.675)
		(mid 210.256066 128.631066)
		(end 210.3 128.525)
		(width 0.09)
		(layer "In4.Cu")
		(net 639)
	)
	(arc
		(start 210.028397 127.910203)
		(mid 209.922331 127.954137)
		(end 209.816265 127.910203)
		(width 0.09)
		(layer "In4.Cu")
		(net 639)
	)
	(arc
		(start 207.432536 126.374999)
		(mid 207.308793 126.426256)
		(end 207.185049 126.375)
		(width 0.09)
		(layer "In4.Cu")
		(net 639)
	)
	(arc
		(start 209.377077 126.905328)
		(mid 209.428334 126.781585)
		(end 209.377078 126.657841)
		(width 0.09)
		(layer "In4.Cu")
		(net 639)
	)
	(arc
		(start 209.815531 127.909469)
		(mid 209.67411 127.85089)
		(end 209.532688 127.909468)
		(width 0.09)
		(layer "In4.Cu")
		(net 639)
	)
	(arc
		(start 203.15 126.275)
		(mid 203.256066 126.231066)
		(end 203.3 126.125)
		(width 0.09)
		(layer "In4.Cu")
		(net 639)
	)
	(arc
		(start 209.506388 128.975)
		(mid 209.400322 128.931066)
		(end 209.356388 128.825)
		(width 0.09)
		(layer "In4.Cu")
		(net 639)
	)
	(arc
		(start 208.953246 127.675734)
		(mid 209.07699 127.72699)
		(end 209.200734 127.675734)
		(width 0.09)
		(layer "In4.Cu")
		(net 639)
	)
	(arc
		(start 203 125.975)
		(mid 202.893934 125.931066)
		(end 202.85 125.825)
		(width 0.09)
		(layer "In4.Cu")
		(net 639)
	)
	(arc
		(start 206.7 126.875)
		(mid 206.593934 126.831066)
		(end 206.55 126.725)
		(width 0.09)
		(layer "In4.Cu")
		(net 639)
	)
	(arc
		(start 203.3 126.125)
		(mid 203.256066 126.018934)
		(end 203.15 125.975)
		(width 0.09)
		(layer "In4.Cu")
		(net 639)
	)
	(arc
		(start 202.85 126.425)
		(mid 202.893934 126.318934)
		(end 203 126.275)
		(width 0.09)
		(layer "In4.Cu")
		(net 639)
	)
	(arc
		(start 208.316419 125.986091)
		(mid 208.367676 125.862348)
		(end 208.31642 125.738604)
		(width 0.09)
		(layer "In4.Cu")
		(net 639)
	)
	(arc
		(start 208.882103 126.410354)
		(mid 208.93336 126.286611)
		(end 208.882104 126.162867)
		(width 0.09)
		(layer "In4.Cu")
		(net 639)
	)
	(arc
		(start 209.249844 127.626624)
		(mid 209.308424 127.485202)
		(end 209.249845 127.343781)
		(width 0.09)
		(layer "In4.Cu")
		(net 639)
	)
	(arc
		(start 208.422484 127.364947)
		(mid 208.298741 127.416204)
		(end 208.174997 127.364948)
		(width 0.09)
		(layer "In4.Cu")
		(net 639)
	)
	(arc
		(start 203.47 126.45)
		(mid 203.371005 126.491005)
		(end 203.33 126.59)
		(width 0.09)
		(layer "In4.Cu")
		(net 639)
	)
	(arc
		(start 209.235655 127.329591)
		(mid 209.177077 127.18817)
		(end 209.235655 127.046749)
		(width 0.09)
		(layer "In4.Cu")
		(net 639)
	)
	(arc
		(start 206.55 126.525)
		(mid 206.506066 126.418934)
		(end 206.4 126.375)
		(width 0.09)
		(layer "In4.Cu")
		(net 639)
	)
	(arc
		(start 203.33 126.71)
		(mid 203.288995 126.808995)
		(end 203.19 126.85)
		(width 0.09)
		(layer "In4.Cu")
		(net 639)
	)
	(arc
		(start 210.452663 127.698071)
		(mid 210.346597 127.654136)
		(end 210.24053 127.69807)
		(width 0.09)
		(layer "In4.Cu")
		(net 639)
	)
	(arc
		(start 206.85 126.725)
		(mid 206.806066 126.831066)
		(end 206.7 126.875)
		(width 0.09)
		(layer "In4.Cu")
		(net 639)
	)
	(arc
		(start 207 126.375)
		(mid 206.893934 126.418934)
		(end 206.85 126.525)
		(width 0.09)
		(layer "In4.Cu")
		(net 639)
	)
	(arc
		(start 208.316419 125.738604)
		(mid 208.192676 125.687347)
		(end 208.068932 125.738603)
		(width 0.09)
		(layer "In4.Cu")
		(net 639)
	)
	(arc
		(start 208.882103 126.162866)
		(mid 208.758359 126.11161)
		(end 208.634616 126.162867)
		(width 0.09)
		(layer "In4.Cu")
		(net 639)
	)
	(arc
		(start 208.635048 127.605021)
		(mid 208.758792 127.553765)
		(end 208.882535 127.605022)
		(width 0.09)
		(layer "In4.Cu")
		(net 639)
	)
	(via
		(at 202.1 124.3)
		(size 0.35)
		(drill 0.15)
		(layers "F.Cu" "B.Cu")
		(remove_unused_layers yes)
		(keep_end_layers yes)
		(zone_layer_connections)
		(net 640)
	)
	(via
		(at 212.927 141.151)
		(size 0.35)
		(drill 0.15)
		(layers "F.Cu" "B.Cu")
		(remove_unused_layers yes)
		(keep_end_layers yes)
		(zone_layer_connections)
		(net 640)
	)
	(segment
		(start 213.47 142.67)
		(end 212.927 142.127)
		(width 0.09)
		(layer "In2.Cu")
		(net 640)
	)
	(segment
		(start 214.942449 133.952524)
		(end 214.94245 133.952524)
		(width 0.09)
		(layer "In2.Cu")
		(net 640)
	)
	(segment
		(start 208.45 132.3)
		(end 209.05 132.9)
		(width 0.09)
		(layer "In2.Cu")
		(net 640)
	)
	(segment
		(start 214.960924 135.418972)
		(end 214.960922 135.418971)
		(width 0.09)
		(layer "In2.Cu")
		(net 640)
	)
	(segment
		(start 209.05 132.9)
		(end 212.441951 132.9)
		(width 0.09)
		(layer "In2.Cu")
		(net 640)
	)
	(segment
		(start 202.1 124.3)
		(end 202.65 123.75)
		(width 0.09)
		(layer "In2.Cu")
		(net 640)
	)
	(segment
		(start 214.52 142.67)
		(end 213.47 142.67)
		(width 0.09)
		(layer "In2.Cu")
		(net 640)
	)
	(segment
		(start 217.75 138.208049)
		(end 217.75 143.265)
		(width 0.09)
		(layer "In2.Cu")
		(net 640)
	)
	(segment
		(start 214.713437 134.923999)
		(end 215.189979 134.447454)
		(width 0.09)
		(layer "In2.Cu")
		(net 640)
	)
	(segment
		(start 212.927 142.127)
		(end 212.927 141.151)
		(width 0.09)
		(layer "In2.Cu")
		(net 640)
	)
	(segment
		(start 214.942449 134.20001)
		(end 214.465949 134.676511)
		(width 0.09)
		(layer "In2.Cu")
		(net 640)
	)
	(segment
		(start 214.960922 135.418971)
		(end 217.75 138.208049)
		(width 0.09)
		(layer "In2.Cu")
		(net 640)
	)
	(segment
		(start 208.45 124.7)
		(end 208.45 132.3)
		(width 0.09)
		(layer "In2.Cu")
		(net 640)
	)
	(segment
		(start 215.437466 134.447455)
		(end 215.437467 134.447455)
		(width 0.09)
		(layer "In2.Cu")
		(net 640)
	)
	(segment
		(start 214.218462 134.429023)
		(end 214.218463 134.429025)
		(width 0.09)
		(layer "In2.Cu")
		(net 640)
	)
	(segment
		(start 214.218463 134.429025)
		(end 214.694962 133.952523)
		(width 0.09)
		(layer "In2.Cu")
		(net 640)
	)
	(segment
		(start 207.5 123.75)
		(end 208.45 124.7)
		(width 0.09)
		(layer "In2.Cu")
		(net 640)
	)
	(segment
		(start 215.894442 143.099)
		(end 214.949 143.099)
		(width 0.09)
		(layer "In2.Cu")
		(net 640)
	)
	(segment
		(start 214.942449 134.200011)
		(end 214.942449 134.20001)
		(width 0.09)
		(layer "In2.Cu")
		(net 640)
	)
	(segment
		(start 215.437466 134.694941)
		(end 214.960923 135.171485)
		(width 0.09)
		(layer "In2.Cu")
		(net 640)
	)
	(segment
		(start 212.441951 132.9)
		(end 213.970975 134.429024)
		(width 0.09)
		(layer "In2.Cu")
		(net 640)
	)
	(segment
		(start 214.46595 134.923998)
		(end 214.465949 134.923998)
		(width 0.09)
		(layer "In2.Cu")
		(net 640)
	)
	(segment
		(start 217.315 143.7)
		(end 216.495442 143.7)
		(width 0.09)
		(layer "In2.Cu")
		(net 640)
	)
	(segment
		(start 214.949 143.099)
		(end 214.52 142.67)
		(width 0.09)
		(layer "In2.Cu")
		(net 640)
	)
	(segment
		(start 216.495442 143.7)
		(end 215.894442 143.099)
		(width 0.09)
		(layer "In2.Cu")
		(net 640)
	)
	(segment
		(start 215.437466 134.694942)
		(end 215.437466 134.694941)
		(width 0.09)
		(layer "In2.Cu")
		(net 640)
	)
	(segment
		(start 214.713436 134.923997)
		(end 214.713437 134.923999)
		(width 0.09)
		(layer "In2.Cu")
		(net 640)
	)
	(segment
		(start 202.65 123.75)
		(end 207.5 123.75)
		(width 0.09)
		(layer "In2.Cu")
		(net 640)
	)
	(segment
		(start 217.75 143.265)
		(end 217.315 143.7)
		(width 0.09)
		(layer "In2.Cu")
		(net 640)
	)
	(arc
		(start 215.189979 134.447454)
		(mid 215.313723 134.396198)
		(end 215.437466 134.447455)
		(width 0.09)
		(layer "In2.Cu")
		(net 640)
	)
	(arc
		(start 214.465949 134.923998)
		(mid 214.589693 134.975254)
		(end 214.713436 134.923997)
		(width 0.09)
		(layer "In2.Cu")
		(net 640)
	)
	(arc
		(start 214.694962 133.952523)
		(mid 214.818706 133.901267)
		(end 214.942449 133.952524)
		(width 0.09)
		(layer "In2.Cu")
		(net 640)
	)
	(arc
		(start 214.465949 134.676511)
		(mid 214.414693 134.800255)
		(end 214.46595 134.923998)
		(width 0.09)
		(layer "In2.Cu")
		(net 640)
	)
	(arc
		(start 214.94245 133.952524)
		(mid 214.993706 134.076268)
		(end 214.942449 134.200011)
		(width 0.09)
		(layer "In2.Cu")
		(net 640)
	)
	(arc
		(start 215.437467 134.447455)
		(mid 215.488723 134.571199)
		(end 215.437466 134.694942)
		(width 0.09)
		(layer "In2.Cu")
		(net 640)
	)
	(arc
		(start 213.970975 134.429024)
		(mid 214.094719 134.48028)
		(end 214.218462 134.429023)
		(width 0.09)
		(layer "In2.Cu")
		(net 640)
	)
	(arc
		(start 214.960923 135.171485)
		(mid 214.909667 135.295229)
		(end 214.960924 135.418972)
		(width 0.09)
		(layer "In2.Cu")
		(net 640)
	)
	(via
		(at 202.1 125.101)
		(size 0.35)
		(drill 0.15)
		(layers "F.Cu" "B.Cu")
		(remove_unused_layers yes)
		(keep_end_layers yes)
		(zone_layer_connections)
		(net 641)
	)
	(via
		(at 214.615 140.05)
		(size 0.35)
		(drill 0.15)
		(layers "F.Cu" "B.Cu")
		(remove_unused_layers yes)
		(keep_end_layers yes)
		(zone_layer_connections)
		(net 641)
	)
	(segment
		(start 210.375 130.425)
		(end 210.375 131.325)
		(width 0.09)
		(layer "In4.Cu")
		(net 641)
	)
	(segment
		(start 205.825 127.25)
		(end 205.825 127.5)
		(width 0.09)
		(layer "In4.Cu")
		(net 641)
	)
	(segment
		(start 210.375 132.125)
		(end 210.375 132.225)
		(width 0.09)
		(layer "In4.Cu")
		(net 641)
	)
	(segment
		(start 214.615 137.59)
		(end 214.615 137.825)
		(width 0.09)
		(layer "In4.Cu")
		(net 641)
	)
	(segment
		(start 209.8 129.975)
		(end 209.3875 129.975)
		(width 0.09)
		(layer "In4.Cu")
		(net 641)
	)
	(segment
		(start 211.025 134.65)
		(end 212.55 136.175)
		(width 0.09)
		(layer "In4.Cu")
		(net 641)
	)
	(segment
		(start 202.5 126.825)
		(end 202.775 127.1)
		(width 0.09)
		(layer "In4.Cu")
		(net 641)
	)
	(segment
		(start 207.475 127.1)
		(end 207.55 127.175)
		(width 0.09)
		(layer "In4.Cu")
		(net 641)
	)
	(segment
		(start 207.09038 128.129594)
		(end 207.09038 128.129593)
		(width 0.09)
		(layer "In4.Cu")
		(net 641)
	)
	(segment
		(start 208.2 127.825)
		(end 208.2 127.925)
		(width 0.09)
		(layer "In4.Cu")
		(net 641)
	)
	(segment
		(start 207.125733 127.634616)
		(end 207.125733 127.634617)
		(width 0.09)
		(layer "In4.Cu")
		(net 641)
	)
	(segment
		(start 209.2375 129.1875)
		(end 209.2375 129.525)
		(width 0.09)
		(layer "In4.Cu")
		(net 641)
	)
	(segment
		(start 215.165 138.875)
		(end 214.765 138.875)
		(width 0.09)
		(layer "In4.Cu")
		(net 641)
	)
	(segment
		(start 213.686982 137.297941)
		(end 213.898895 137.086027)
		(width 0.09)
		(layer "In4.Cu")
		(net 641)
	)
	(segment
		(start 210.075 130.925)
		(end 210.075 130.425)
		(width 0.09)
		(layer "In4.Cu")
		(net 641)
	)
	(segment
		(start 214.615 139.025)
		(end 214.615 140.05)
		(width 0.09)
		(layer "In4.Cu")
		(net 641)
	)
	(segment
		(start 211.05 131.25)
		(end 211.05 131.4)
		(width 0.09)
		(layer "In4.Cu")
		(net 641)
	)
	(segment
		(start 214.765 137.975)
		(end 215.165 137.975)
		(width 0.09)
		(layer "In4.Cu")
		(net 641)
	)
	(segment
		(start 214.111237 137.722214)
		(end 214.323159 137.510291)
		(width 0.09)
		(layer "In4.Cu")
		(net 641)
	)
	(segment
		(start 206.875 127.1)
		(end 207.475 127.1)
		(width 0.09)
		(layer "In4.Cu")
		(net 641)
	)
	(segment
		(start 206.425 127.25)
		(end 206.425 127.5)
		(width 0.09)
		(layer "In4.Cu")
		(net 641)
	)
	(segment
		(start 209.2375 130.125)
		(end 209.2375 130.3875)
		(width 0.09)
		(layer "In4.Cu")
		(net 641)
	)
	(segment
		(start 211.3 131.9)
		(end 211.025 132.175)
		(width 0.09)
		(layer "In4.Cu")
		(net 641)
	)
	(segment
		(start 207.125735 127.84675)
		(end 207.09038 127.882106)
		(width 0.09)
		(layer "In4.Cu")
		(net 641)
	)
	(segment
		(start 210.825 131.075)
		(end 210.875 131.075)
		(width 0.09)
		(layer "In4.Cu")
		(net 641)
	)
	(segment
		(start 202.5 125.501)
		(end 202.5 126.825)
		(width 0.09)
		(layer "In4.Cu")
		(net 641)
	)
	(segment
		(start 211.725 131.075)
		(end 211.9 131.25)
		(width 0.09)
		(layer "In4.Cu")
		(net 641)
	)
	(segment
		(start 213.686763 136.873897)
		(end 213.474849 137.08581)
		(width 0.09)
		(layer "In4.Cu")
		(net 641)
	)
	(segment
		(start 211.575 131.075)
		(end 211.725 131.075)
		(width 0.09)
		(layer "In4.Cu")
		(net 641)
	)
	(segment
		(start 210.125 131.925)
		(end 210.175 131.925)
		(width 0.09)
		(layer "In4.Cu")
		(net 641)
	)
	(segment
		(start 206.125 127.5)
		(end 206.125 127.25)
		(width 0.09)
		(layer "In4.Cu")
		(net 641)
	)
	(segment
		(start 214.111027 137.298161)
		(end 213.899104 137.510083)
		(width 0.09)
		(layer "In4.Cu")
		(net 641)
	)
	(segment
		(start 211.4 131.4)
		(end 211.4 131.25)
		(width 0.09)
		(layer "In4.Cu")
		(net 641)
	)
	(segment
		(start 210.675 132.225)
		(end 210.675 131.225)
		(width 0.09)
		(layer "In4.Cu")
		(net 641)
	)
	(segment
		(start 211.9 131.25)
		(end 211.9 131.825)
		(width 0.09)
		(layer "In4.Cu")
		(net 641)
	)
	(segment
		(start 209.05 129)
		(end 209.2375 129.1875)
		(width 0.09)
		(layer "In4.Cu")
		(net 641)
	)
	(segment
		(start 208.2 128.675)
		(end 208.525 129)
		(width 0.09)
		(layer "In4.Cu")
		(net 641)
	)
	(segment
		(start 210.175 131.525)
		(end 210.125 131.525)
		(width 0.09)
		(layer "In4.Cu")
		(net 641)
	)
	(segment
		(start 207.875 128.45)
		(end 208.025 128.45)
		(width 0.09)
		(layer "In4.Cu")
		(net 641)
	)
	(segment
		(start 214.111027 137.086027)
		(end 214.111028 137.086028)
		(width 0.09)
		(layer "In4.Cu")
		(net 641)
	)
	(segment
		(start 202.1 125.101)
		(end 202.5 125.501)
		(width 0.09)
		(layer "In4.Cu")
		(net 641)
	)
	(segment
		(start 202.775 127.1)
		(end 205.675 127.1)
		(width 0.09)
		(layer "In4.Cu")
		(net 641)
	)
	(segment
		(start 213.686763 136.661763)
		(end 213.686764 136.661764)
		(width 0.09)
		(layer "In4.Cu")
		(net 641)
	)
	(segment
		(start 211.825 131.9)
		(end 211.3 131.9)
		(width 0.09)
		(layer "In4.Cu")
		(net 641)
	)
	(segment
		(start 209.3875 129.675)
		(end 209.8 129.675)
		(width 0.09)
		(layer "In4.Cu")
		(net 641)
	)
	(segment
		(start 208.525 129)
		(end 209.05 129)
		(width 0.09)
		(layer "In4.Cu")
		(net 641)
	)
	(segment
		(start 209.2375 130.3875)
		(end 209.925 131.075)
		(width 0.09)
		(layer "In4.Cu")
		(net 641)
	)
	(segment
		(start 214.535291 137.510291)
		(end 214.615 137.59)
		(width 0.09)
		(layer "In4.Cu")
		(net 641)
	)
	(segment
		(start 215.165 138.275)
		(end 214.765 138.275)
		(width 0.09)
		(layer "In4.Cu")
		(net 641)
	)
	(segment
		(start 207.125731 127.846749)
		(end 207.125735 127.84675)
		(width 0.09)
		(layer "In4.Cu")
		(net 641)
	)
	(segment
		(start 211.025 132.175)
		(end 211.025 134.65)
		(width 0.09)
		(layer "In4.Cu")
		(net 641)
	)
	(segment
		(start 207.125735 127.422484)
		(end 207.125734 127.422485)
		(width 0.09)
		(layer "In4.Cu")
		(net 641)
	)
	(segment
		(start 213.2 136.175)
		(end 213.2625 136.2375)
		(width 0.09)
		(layer "In4.Cu")
		(net 641)
	)
	(segment
		(start 206.725 127.5)
		(end 206.725 127.25)
		(width 0.09)
		(layer "In4.Cu")
		(net 641)
	)
	(segment
		(start 213.262499 136.449633)
		(end 213.050636 136.661495)
		(width 0.09)
		(layer "In4.Cu")
		(net 641)
	)
	(segment
		(start 212.55 136.175)
		(end 213.2 136.175)
		(width 0.09)
		(layer "In4.Cu")
		(net 641)
	)
	(segment
		(start 208.025 128.1)
		(end 207.875 128.1)
		(width 0.09)
		(layer "In4.Cu")
		(net 641)
	)
	(segment
		(start 213.262769 136.873626)
		(end 213.474631 136.661763)
		(width 0.09)
		(layer "In4.Cu")
		(net 641)
	)
	(segment
		(start 208.044974 127.669973)
		(end 208.2 127.825)
		(width 0.09)
		(layer "In4.Cu")
		(net 641)
	)
	(segment
		(start 207.549999 127.422487)
		(end 207.55 127.422487)
		(width 0.09)
		(layer "In4.Cu")
		(net 641)
	)
	(segment
		(start 214.765 138.575)
		(end 215.165 138.575)
		(width 0.09)
		(layer "In4.Cu")
		(net 641)
	)
	(segment
		(start 207.337867 128.129593)
		(end 207.797486 127.669973)
		(width 0.09)
		(layer "In4.Cu")
		(net 641)
	)
	(segment
		(start 207.337867 128.129592)
		(end 207.337867 128.129593)
		(width 0.09)
		(layer "In4.Cu")
		(net 641)
	)
	(segment
		(start 211.9 131.825)
		(end 211.825 131.9)
		(width 0.09)
		(layer "In4.Cu")
		(net 641)
	)
	(segment
		(start 208.2 128.625)
		(end 208.2 128.675)
		(width 0.09)
		(layer "In4.Cu")
		(net 641)
	)
	(arc
		(start 210.675 131.225)
		(mid 210.718934 131.118934)
		(end 210.825 131.075)
		(width 0.09)
		(layer "In4.Cu")
		(net 641)
	)
	(arc
		(start 206.125 127.25)
		(mid 206.168934 127.143934)
		(end 206.275 127.1)
		(width 0.09)
		(layer "In4.Cu")
		(net 641)
	)
	(arc
		(start 215.165 137.975)
		(mid 215.271066 138.018934)
		(end 215.315 138.125)
		(width 0.09)
		(layer "In4.Cu")
		(net 641)
	)
	(arc
		(start 213.898895 137.086027)
		(mid 214.004961 137.042093)
		(end 214.111027 137.086027)
		(width 0.09)
		(layer "In4.Cu")
		(net 641)
	)
	(arc
		(start 215.315 138.125)
		(mid 215.271066 138.231066)
		(end 215.165 138.275)
		(width 0.09)
		(layer "In4.Cu")
		(net 641)
	)
	(arc
		(start 208.2 127.925)
		(mid 208.148744 128.048744)
		(end 208.025 128.1)
		(width 0.09)
		(layer "In4.Cu")
		(net 641)
	)
	(arc
		(start 213.474849 137.08581)
		(mid 213.430915 137.191876)
		(end 213.474849 137.297942)
		(width 0.09)
		(layer "In4.Cu")
		(net 641)
	)
	(arc
		(start 213.050636 136.661495)
		(mid 213.006702 136.767561)
		(end 213.050636 136.873627)
		(width 0.09)
		(layer "In4.Cu")
		(net 641)
	)
	(arc
		(start 214.323159 137.510291)
		(mid 214.429225 137.466357)
		(end 214.535291 137.510291)
		(width 0.09)
		(layer "In4.Cu")
		(net 641)
	)
	(arc
		(start 210.075 130.425)
		(mid 210.118934 130.318934)
		(end 210.225 130.275)
		(width 0.09)
		(layer "In4.Cu")
		(net 641)
	)
	(arc
		(start 214.615 138.425)
		(mid 214.658934 138.531066)
		(end 214.765 138.575)
		(width 0.09)
		(layer "In4.Cu")
		(net 641)
	)
	(arc
		(start 209.3875 129.975)
		(mid 209.281434 130.018934)
		(end 209.2375 130.125)
		(width 0.09)
		(layer "In4.Cu")
		(net 641)
	)
	(arc
		(start 210.175 131.925)
		(mid 210.316421 131.983579)
		(end 210.375 132.125)
		(width 0.09)
		(layer "In4.Cu")
		(net 641)
	)
	(arc
		(start 214.111028 137.086028)
		(mid 214.154962 137.192095)
		(end 214.111027 137.298161)
		(width 0.09)
		(layer "In4.Cu")
		(net 641)
	)
	(arc
		(start 205.975 127.65)
		(mid 206.081066 127.606066)
		(end 206.125 127.5)
		(width 0.09)
		(layer "In4.Cu")
		(net 641)
	)
	(arc
		(start 205.675 127.1)
		(mid 205.781066 127.143934)
		(end 205.825 127.25)
		(width 0.09)
		(layer "In4.Cu")
		(net 641)
	)
	(arc
		(start 213.474631 136.661763)
		(mid 213.580697 136.617829)
		(end 213.686763 136.661763)
		(width 0.09)
		(layer "In4.Cu")
		(net 641)
	)
	(arc
		(start 209.95 129.825)
		(mid 209.906066 129.931066)
		(end 209.8 129.975)
		(width 0.09)
		(layer "In4.Cu")
		(net 641)
	)
	(arc
		(start 211.4 131.25)
		(mid 211.451256 131.126256)
		(end 211.575 131.075)
		(width 0.09)
		(layer "In4.Cu")
		(net 641)
	)
	(arc
		(start 206.275 127.1)
		(mid 206.381066 127.143934)
		(end 206.425 127.25)
		(width 0.09)
		(layer "In4.Cu")
		(net 641)
	)
	(arc
		(start 209.2375 129.525)
		(mid 209.281434 129.631066)
		(end 209.3875 129.675)
		(width 0.09)
		(layer "In4.Cu")
		(net 641)
	)
	(arc
		(start 209.925 131.075)
		(mid 210.031066 131.031066)
		(end 210.075 130.925)
		(width 0.09)
		(layer "In4.Cu")
		(net 641)
	)
	(arc
		(start 207.797486 127.669973)
		(mid 207.92123 127.618717)
		(end 208.044974 127.669973)
		(width 0.09)
		(layer "In4.Cu")
		(net 641)
	)
	(arc
		(start 207.09038 128.129593)
		(mid 207.214124 128.180849)
		(end 207.337867 128.129592)
		(width 0.09)
		(layer "In4.Cu")
		(net 641)
	)
	(arc
		(start 207.337867 127.422486)
		(mid 207.231801 127.378551)
		(end 207.125735 127.422484)
		(width 0.09)
		(layer "In4.Cu")
		(net 641)
	)
	(arc
		(start 210.525 132.375)
		(mid 210.631066 132.331066)
		(end 210.675 132.225)
		(width 0.09)
		(layer "In4.Cu")
		(net 641)
	)
	(arc
		(start 209.925 131.725)
		(mid 209.983579 131.866421)
		(end 210.125 131.925)
		(width 0.09)
		(layer "In4.Cu")
		(net 641)
	)
	(arc
		(start 207.55 127.175)
		(mid 207.601256 127.298744)
		(end 207.549999 127.422487)
		(width 0.09)
		(layer "In4.Cu")
		(net 641)
	)
	(arc
		(start 206.725 127.25)
		(mid 206.768934 127.143934)
		(end 206.875 127.1)
		(width 0.09)
		(layer "In4.Cu")
		(net 641)
	)
	(arc
		(start 213.686764 136.661764)
		(mid 213.730698 136.767831)
		(end 213.686763 136.873897)
		(width 0.09)
		(layer "In4.Cu")
		(net 641)
	)
	(arc
		(start 207.875 128.1)
		(mid 207.751256 128.151256)
		(end 207.7 128.275)
		(width 0.09)
		(layer "In4.Cu")
		(net 641)
	)
	(arc
		(start 211.225 131.575)
		(mid 211.348744 131.523744)
		(end 211.4 131.4)
		(width 0.09)
		(layer "In4.Cu")
		(net 641)
	)
	(arc
		(start 215.315 138.725)
		(mid 215.271066 138.831066)
		(end 215.165 138.875)
		(width 0.09)
		(layer "In4.Cu")
		(net 641)
	)
	(arc
		(start 214.765 138.275)
		(mid 214.658934 138.318934)
		(end 214.615 138.425)
		(width 0.09)
		(layer "In4.Cu")
		(net 641)
	)
	(arc
		(start 210.375 131.325)
		(mid 210.316421 131.466421)
		(end 210.175 131.525)
		(width 0.09)
		(layer "In4.Cu")
		(net 641)
	)
	(arc
		(start 213.899104 137.722215)
		(mid 214.005171 137.766149)
		(end 214.111237 137.722214)
		(width 0.09)
		(layer "In4.Cu")
		(net 641)
	)
	(arc
		(start 210.125 131.525)
		(mid 209.983579 131.583579)
		(end 209.925 131.725)
		(width 0.09)
		(layer "In4.Cu")
		(net 641)
	)
	(arc
		(start 207.55 127.422487)
		(mid 207.443933 127.466421)
		(end 207.337867 127.422486)
		(width 0.09)
		(layer "In4.Cu")
		(net 641)
	)
	(arc
		(start 213.2625 136.2375)
		(mid 213.306434 136.343567)
		(end 213.262499 136.449633)
		(width 0.09)
		(layer "In4.Cu")
		(net 641)
	)
	(arc
		(start 213.899104 137.510083)
		(mid 213.85517 137.616149)
		(end 213.899104 137.722215)
		(width 0.09)
		(layer "In4.Cu")
		(net 641)
	)
	(arc
		(start 210.225 130.275)
		(mid 210.331066 130.318934)
		(end 210.375 130.425)
		(width 0.09)
		(layer "In4.Cu")
		(net 641)
	)
	(arc
		(start 213.474849 137.297942)
		(mid 213.580916 137.341876)
		(end 213.686982 137.297941)
		(width 0.09)
		(layer "In4.Cu")
		(net 641)
	)
	(arc
		(start 207.125733 127.634617)
		(mid 207.169666 127.740683)
		(end 207.125731 127.846749)
		(width 0.09)
		(layer "In4.Cu")
		(net 641)
	)
	(arc
		(start 211.05 131.4)
		(mid 211.101256 131.523744)
		(end 211.225 131.575)
		(width 0.09)
		(layer "In4.Cu")
		(net 641)
	)
	(arc
		(start 215.165 138.575)
		(mid 215.271066 138.618934)
		(end 215.315 138.725)
		(width 0.09)
		(layer "In4.Cu")
		(net 641)
	)
	(arc
		(start 209.8 129.675)
		(mid 209.906066 129.718934)
		(end 209.95 129.825)
		(width 0.09)
		(layer "In4.Cu")
		(net 641)
	)
	(arc
		(start 207.09038 127.882106)
		(mid 207.039124 128.00585)
		(end 207.09038 128.129594)
		(width 0.09)
		(layer "In4.Cu")
		(net 641)
	)
	(arc
		(start 214.615 137.825)
		(mid 214.658934 137.931066)
		(end 214.765 137.975)
		(width 0.09)
		(layer "In4.Cu")
		(net 641)
	)
	(arc
		(start 210.875 131.075)
		(mid 210.998744 131.126256)
		(end 211.05 131.25)
		(width 0.09)
		(layer "In4.Cu")
		(net 641)
	)
	(arc
		(start 210.375 132.225)
		(mid 210.418934 132.331066)
		(end 210.525 132.375)
		(width 0.09)
		(layer "In4.Cu")
		(net 641)
	)
	(arc
		(start 205.825 127.5)
		(mid 205.868934 127.606066)
		(end 205.975 127.65)
		(width 0.09)
		(layer "In4.Cu")
		(net 641)
	)
	(arc
		(start 214.765 138.875)
		(mid 214.658934 138.918934)
		(end 214.615 139.025)
		(width 0.09)
		(layer "In4.Cu")
		(net 641)
	)
	(arc
		(start 206.575 127.65)
		(mid 206.681066 127.606066)
		(end 206.725 127.5)
		(width 0.09)
		(layer "In4.Cu")
		(net 641)
	)
	(arc
		(start 207.7 128.275)
		(mid 207.751256 128.398744)
		(end 207.875 128.45)
		(width 0.09)
		(layer "In4.Cu")
		(net 641)
	)
	(arc
		(start 206.425 127.5)
		(mid 206.468934 127.606066)
		(end 206.575 127.65)
		(width 0.09)
		(layer "In4.Cu")
		(net 641)
	)
	(arc
		(start 208.025 128.45)
		(mid 208.148744 128.501256)
		(end 208.2 128.625)
		(width 0.09)
		(layer "In4.Cu")
		(net 641)
	)
	(arc
		(start 207.125734 127.422485)
		(mid 207.0818 127.52855)
		(end 207.125733 127.634616)
		(width 0.09)
		(layer "In4.Cu")
		(net 641)
	)
	(arc
		(start 213.050636 136.873627)
		(mid 213.156703 136.917561)
		(end 213.262769 136.873626)
		(width 0.09)
		(layer "In4.Cu")
		(net 641)
	)
	(via
		(at 216.802 143.148)
		(size 0.35)
		(drill 0.15)
		(layers "F.Cu" "B.Cu")
		(remove_unused_layers yes)
		(keep_end_layers yes)
		(zone_layer_connections)
		(net 642)
	)
	(via
		(at 202.1 125.901)
		(size 0.35)
		(drill 0.15)
		(layers "F.Cu" "B.Cu")
		(remove_unused_layers yes)
		(keep_end_layers yes)
		(zone_layer_connections)
		(net 642)
	)
	(segment
		(start 199.835691 126.231)
		(end 200.029 126.037691)
		(width 0.09)
		(layer "In2.Cu")
		(net 642)
	)
	(segment
		(start 212.559313 138.759313)
		(end 212.3 138.5)
		(width 0.09)
		(layer "In2.Cu")
		(net 642)
	)
	(segment
		(start 210.4 138.5)
		(end 210.35 138.5)
		(width 0.09)
		(layer "In2.Cu")
		(net 642)
	)
	(segment
		(start 204.085876 129.311671)
		(end 204.085876 129.311672)
		(width 0.09)
		(layer "In2.Cu")
		(net 642)
	)
	(segment
		(start 201.77 125.571)
		(end 202.1 125.901)
		(width 0.09)
		(layer "In2.Cu")
		(net 642)
	)
	(segment
		(start 200.029 126.037691)
		(end 200.029 125.904309)
		(width 0.09)
		(layer "In2.Cu")
		(net 642)
	)
	(segment
		(start 211 138.3)
		(end 211 137.7)
		(width 0.09)
		(layer "In2.Cu")
		(net 642)
	)
	(segment
		(start 208.8 138.5)
		(end 208.55 138.5)
		(width 0.09)
		(layer "In2.Cu")
		(net 642)
	)
	(segment
		(start 203.501652 129.127447)
		(end 203.47 129.127447)
		(width 0.09)
		(layer "In2.Cu")
		(net 642)
	)
	(segment
		(start 198.7 126.231)
		(end 199.835691 126.231)
		(width 0.09)
		(layer "In2.Cu")
		(net 642)
	)
	(segment
		(start 200.26 128.99)
		(end 199.97 128.7)
		(width 0.09)
		(layer "In2.Cu")
		(net 642)
	)
	(segment
		(start 198.5 126.431)
		(end 198.7 126.231)
		(width 0.09)
		(layer "In2.Cu")
		(net 642)
	)
	(segment
		(start 215.7055 141.2055)
		(end 213.9055 141.2055)
		(width 0.09)
		(layer "In2.Cu")
		(net 642)
	)
	(segment
		(start 216.04 142.656691)
		(end 216.04 141.54)
		(width 0.09)
		(layer "In2.Cu")
		(net 642)
	)
	(segment
		(start 199.97 128.7)
		(end 199.01 128.7)
		(width 0.09)
		(layer "In2.Cu")
		(net 642)
	)
	(segment
		(start 206.084204 129.495796)
		(end 204.67 129.495796)
		(width 0.09)
		(layer "In2.Cu")
		(net 642)
	)
	(segment
		(start 209.4 138.3)
		(end 209.4 137.9)
		(width 0.09)
		(layer "In2.Cu")
		(net 642)
	)
	(segment
		(start 207.55 136.3)
		(end 206.48 135.23)
		(width 0.09)
		(layer "In2.Cu")
		(net 642)
	)
	(segment
		(start 216.802 143.148)
		(end 216.531309 143.148)
		(width 0.09)
		(layer "In2.Cu")
		(net 642)
	)
	(segment
		(start 204.301752 129.127547)
		(end 204.27 129.127547)
		(width 0.09)
		(layer "In2.Cu")
		(net 642)
	)
	(segment
		(start 209 137.9)
		(end 209 138.3)
		(width 0.09)
		(layer "In2.Cu")
		(net 642)
	)
	(segment
		(start 199.01 128.7)
		(end 198.5 128.19)
		(width 0.09)
		(layer "In2.Cu")
		(net 642)
	)
	(segment
		(start 200.029 125.904309)
		(end 200.362309 125.571)
		(width 0.09)
		(layer "In2.Cu")
		(net 642)
	)
	(segment
		(start 202.605796 129.495796)
		(end 203.101652 129.495796)
		(width 0.09)
		(layer "In2.Cu")
		(net 642)
	)
	(segment
		(start 213.2 139.4)
		(end 213.125 139.325)
		(width 0.09)
		(layer "In2.Cu")
		(net 642)
	)
	(segment
		(start 203.285826 129.311621)
		(end 203.285826 129.311622)
		(width 0.09)
		(layer "In2.Cu")
		(net 642)
	)
	(segment
		(start 213.9055 141.2055)
		(end 213.2 140.5)
		(width 0.09)
		(layer "In2.Cu")
		(net 642)
	)
	(segment
		(start 210 138.15)
		(end 209.95 138.15)
		(width 0.09)
		(layer "In2.Cu")
		(net 642)
	)
	(segment
		(start 213.2 140.5)
		(end 213.2 139.4)
		(width 0.09)
		(layer "In2.Cu")
		(net 642)
	)
	(segment
		(start 213.266421 138.335049)
		(end 213.266421 138.33505)
		(width 0.09)
		(layer "In2.Cu")
		(net 642)
	)
	(segment
		(start 216.04 141.54)
		(end 215.7055 141.2055)
		(width 0.09)
		(layer "In2.Cu")
		(net 642)
	)
	(segment
		(start 203.901752 129.495796)
		(end 203.87 129.495796)
		(width 0.09)
		(layer "In2.Cu")
		(net 642)
	)
	(segment
		(start 206.48 135.23)
		(end 206.48 129.891593)
		(width 0.09)
		(layer "In2.Cu")
		(net 642)
	)
	(segment
		(start 216.531309 143.148)
		(end 216.04 142.656691)
		(width 0.09)
		(layer "In2.Cu")
		(net 642)
	)
	(segment
		(start 204.485876 129.311672)
		(end 204.485876 129.311671)
		(width 0.09)
		(layer "In2.Cu")
		(net 642)
	)
	(segment
		(start 198.5 128.19)
		(end 198.5 126.431)
		(width 0.09)
		(layer "In2.Cu")
		(net 642)
	)
	(segment
		(start 213.549263 138.335049)
		(end 213.549264 138.33505)
		(width 0.09)
		(layer "In2.Cu")
		(net 642)
	)
	(segment
		(start 213.266421 138.33505)
		(end 212.842156 138.759314)
		(width 0.09)
		(layer "In2.Cu")
		(net 642)
	)
	(segment
		(start 212.3 138.5)
		(end 212 138.5)
		(width 0.09)
		(layer "In2.Cu")
		(net 642)
	)
	(segment
		(start 200.362309 125.571)
		(end 201.77 125.571)
		(width 0.09)
		(layer "In2.Cu")
		(net 642)
	)
	(segment
		(start 202.1 128.99)
		(end 200.26 128.99)
		(width 0.09)
		(layer "In2.Cu")
		(net 642)
	)
	(segment
		(start 213.124999 139.042157)
		(end 213.549264 138.617892)
		(width 0.09)
		(layer "In2.Cu")
		(net 642)
	)
	(segment
		(start 210.6 137.7)
		(end 210.6 138.3)
		(width 0.09)
		(layer "In2.Cu")
		(net 642)
	)
	(segment
		(start 211.8 138.3)
		(end 211.8 138.1)
		(width 0.09)
		(layer "In2.Cu")
		(net 642)
	)
	(segment
		(start 207.55 137.5)
		(end 207.55 136.3)
		(width 0.09)
		(layer "In2.Cu")
		(net 642)
	)
	(segment
		(start 206.48 129.891593)
		(end 206.084204 129.495796)
		(width 0.09)
		(layer "In2.Cu")
		(net 642)
	)
	(segment
		(start 202.605796 129.495796)
		(end 202.1 128.99)
		(width 0.09)
		(layer "In2.Cu")
		(net 642)
	)
	(segment
		(start 211.4 138.1)
		(end 211.4 138.3)
		(width 0.09)
		(layer "In2.Cu")
		(net 642)
	)
	(segment
		(start 203.685826 129.311622)
		(end 203.685826 129.311621)
		(width 0.09)
		(layer "In2.Cu")
		(net 642)
	)
	(segment
		(start 208.55 138.5)
		(end 207.55 137.5)
		(width 0.09)
		(layer "In2.Cu")
		(net 642)
	)
	(arc
		(start 203.285826 129.311622)
		(mid 203.231883 129.441853)
		(end 203.101652 129.495796)
		(width 0.09)
		(layer "In2.Cu")
		(net 642)
	)
	(arc
		(start 204.085876 129.311672)
		(mid 204.031947 129.441867)
		(end 203.901752 129.495796)
		(width 0.09)
		(layer "In2.Cu")
		(net 642)
	)
	(arc
		(start 210.8 137.5)
		(mid 210.658579 137.558579)
		(end 210.6 137.7)
		(width 0.09)
		(layer "In2.Cu")
		(net 642)
	)
	(arc
		(start 209.6 138.5)
		(mid 209.458579 138.441421)
		(end 209.4 138.3)
		(width 0.09)
		(layer "In2.Cu")
		(net 642)
	)
	(arc
		(start 213.125 139.325)
		(mid 213.066421 139.183579)
		(end 213.124999 139.042157)
		(width 0.09)
		(layer "In2.Cu")
		(net 642)
	)
	(arc
		(start 209.2 137.7)
		(mid 209.058579 137.758579)
		(end 209 137.9)
		(width 0.09)
		(layer "In2.Cu")
		(net 642)
	)
	(arc
		(start 211.2 138.5)
		(mid 211.058579 138.441421)
		(end 211 138.3)
		(width 0.09)
		(layer "In2.Cu")
		(net 642)
	)
	(arc
		(start 212.842156 138.759314)
		(mid 212.700734 138.817892)
		(end 212.559313 138.759313)
		(width 0.09)
		(layer "In2.Cu")
		(net 642)
	)
	(arc
		(start 203.87 129.495796)
		(mid 203.739769 129.441853)
		(end 203.685826 129.311622)
		(width 0.09)
		(layer "In2.Cu")
		(net 642)
	)
	(arc
		(start 209.775 138.325)
		(mid 209.723744 138.448744)
		(end 209.6 138.5)
		(width 0.09)
		(layer "In2.Cu")
		(net 642)
	)
	(arc
		(start 211.4 138.3)
		(mid 211.341421 138.441421)
		(end 211.2 138.5)
		(width 0.09)
		(layer "In2.Cu")
		(net 642)
	)
	(arc
		(start 204.485876 129.311671)
		(mid 204.431947 129.181476)
		(end 204.301752 129.127547)
		(width 0.09)
		(layer "In2.Cu")
		(net 642)
	)
	(arc
		(start 213.549264 138.617892)
		(mid 213.607842 138.47647)
		(end 213.549263 138.335049)
		(width 0.09)
		(layer "In2.Cu")
		(net 642)
	)
	(arc
		(start 203.47 129.127447)
		(mid 203.339769 129.18139)
		(end 203.285826 129.311621)
		(width 0.09)
		(layer "In2.Cu")
		(net 642)
	)
	(arc
		(start 209.95 138.15)
		(mid 209.826256 138.201256)
		(end 209.775 138.325)
		(width 0.09)
		(layer "In2.Cu")
		(net 642)
	)
	(arc
		(start 211.8 138.1)
		(mid 211.741421 137.958579)
		(end 211.6 137.9)
		(width 0.09)
		(layer "In2.Cu")
		(net 642)
	)
	(arc
		(start 210.6 138.3)
		(mid 210.541421 138.441421)
		(end 210.4 138.5)
		(width 0.09)
		(layer "In2.Cu")
		(net 642)
	)
	(arc
		(start 212 138.5)
		(mid 211.858579 138.441421)
		(end 211.8 138.3)
		(width 0.09)
		(layer "In2.Cu")
		(net 642)
	)
	(arc
		(start 209.4 137.9)
		(mid 209.341421 137.758579)
		(end 209.2 137.7)
		(width 0.09)
		(layer "In2.Cu")
		(net 642)
	)
	(arc
		(start 209 138.3)
		(mid 208.941421 138.441421)
		(end 208.8 138.5)
		(width 0.09)
		(layer "In2.Cu")
		(net 642)
	)
	(arc
		(start 204.27 129.127547)
		(mid 204.139805 129.181476)
		(end 204.085876 129.311671)
		(width 0.09)
		(layer "In2.Cu")
		(net 642)
	)
	(arc
		(start 213.549264 138.33505)
		(mid 213.407843 138.276471)
		(end 213.266421 138.335049)
		(width 0.09)
		(layer "In2.Cu")
		(net 642)
	)
	(arc
		(start 210.35 138.5)
		(mid 210.226256 138.448744)
		(end 210.175 138.325)
		(width 0.09)
		(layer "In2.Cu")
		(net 642)
	)
	(arc
		(start 204.67 129.495796)
		(mid 204.539805 129.441867)
		(end 204.485876 129.311672)
		(width 0.09)
		(layer "In2.Cu")
		(net 642)
	)
	(arc
		(start 211 137.7)
		(mid 210.941421 137.558579)
		(end 210.8 137.5)
		(width 0.09)
		(layer "In2.Cu")
		(net 642)
	)
	(arc
		(start 211.6 137.9)
		(mid 211.458579 137.958579)
		(end 211.4 138.1)
		(width 0.09)
		(layer "In2.Cu")
		(net 642)
	)
	(arc
		(start 210.175 138.325)
		(mid 210.123744 138.201256)
		(end 210 138.15)
		(width 0.09)
		(layer "In2.Cu")
		(net 642)
	)
	(arc
		(start 203.685826 129.311621)
		(mid 203.631883 129.18139)
		(end 203.501652 129.127447)
		(width 0.09)
		(layer "In2.Cu")
		(net 642)
	)
	(via
		(at 202.1 127.5)
		(size 0.35)
		(drill 0.15)
		(layers "F.Cu" "B.Cu")
		(remove_unused_layers yes)
		(keep_end_layers yes)
		(zone_layer_connections)
		(net 643)
	)
	(via
		(at 216.114 140.463)
		(size 0.35)
		(drill 0.15)
		(layers "F.Cu" "B.Cu")
		(remove_unused_layers yes)
		(keep_end_layers yes)
		(zone_layer_connections)
		(net 643)
	)
	(segment
		(start 208.111421 131.006703)
		(end 208.11142 131.006704)
		(width 0.09)
		(layer "In4.Cu")
		(net 643)
	)
	(segment
		(start 202.1 127.25)
		(end 202.1 127.5)
		(width 0.09)
		(layer "In4.Cu")
		(net 643)
	)
	(segment
		(start 206.997489 128.836091)
		(end 207.068201 128.906804)
		(width 0.09)
		(layer "In4.Cu")
		(net 643)
	)
	(segment
		(start 206.708707 130.326953)
		(end 207.875433 129.160228)
		(width 0.09)
		(layer "In4.Cu")
		(net 643)
	)
	(segment
		(start 216.114 140.463)
		(end 215.927 140.65)
		(width 0.09)
		(layer "In4.Cu")
		(net 643)
	)
	(segment
		(start 206.708707 129.478425)
		(end 206.856066 129.331066)
		(width 0.09)
		(layer "In4.Cu")
		(net 643)
	)
	(segment
		(start 207.28033 128.906802)
		(end 207.451169 128.735964)
		(width 0.09)
		(layer "In4.Cu")
		(net 643)
	)
	(segment
		(start 206.856065 129.118935)
		(end 206.856066 129.118934)
		(width 0.09)
		(layer "In4.Cu")
		(net 643)
	)
	(segment
		(start 207.618197 129.841728)
		(end 206.92084 130.539084)
		(width 0.09)
		(layer "In4.Cu")
		(net 643)
	)
	(segment
		(start 208.925 130.575)
		(end 208.925 130)
		(width 0.09)
		(layer "In4.Cu")
		(net 643)
	)
	(segment
		(start 209.325 130.975)
		(end 208.925 130.575)
		(width 0.09)
		(layer "In4.Cu")
		(net 643)
	)
	(segment
		(start 208.087565 129.372358)
		(end 208.042462 129.417462)
		(width 0.09)
		(layer "In4.Cu")
		(net 643)
	)
	(segment
		(start 207.663301 128.948094)
		(end 206.92084 129.690556)
		(width 0.09)
		(layer "In4.Cu")
		(net 643)
	)
	(segment
		(start 208.36066 130.372059)
		(end 208.325303 130.336702)
		(width 0.09)
		(layer "In4.Cu")
		(net 643)
	)
	(segment
		(start 207.875434 128.948095)
		(end 207.875433 128.948094)
		(width 0.09)
		(layer "In4.Cu")
		(net 643)
	)
	(segment
		(start 207.83033 130.089216)
		(end 207.830329 130.089216)
		(width 0.09)
		(layer "In4.Cu")
		(net 643)
	)
	(segment
		(start 206.4 127.9)
		(end 202.575 127.9)
		(width 0.09)
		(layer "In4.Cu")
		(net 643)
	)
	(segment
		(start 210.475 134.525)
		(end 210.175 134.525)
		(width 0.09)
		(layer "In4.Cu")
		(net 643)
	)
	(segment
		(start 210.625 132.8)
		(end 209.325 131.5)
		(width 0.09)
		(layer "In4.Cu")
		(net 643)
	)
	(segment
		(start 207.45117 128.523831)
		(end 207.427339 128.5)
		(width 0.09)
		(layer "In4.Cu")
		(net 643)
	)
	(segment
		(start 214.748309 140.65)
		(end 214.285 140.186691)
		(width 0.09)
		(layer "In4.Cu")
		(net 643)
	)
	(segment
		(start 208.323551 131.006703)
		(end 208.323552 131.006704)
		(width 0.09)
		(layer "In4.Cu")
		(net 643)
	)
	(segment
		(start 210.175 134.225)
		(end 210.475 134.225)
		(width 0.09)
		(layer "In4.Cu")
		(net 643)
	)
	(segment
		(start 207.618198 129.841729)
		(end 207.618197 129.841728)
		(width 0.09)
		(layer "In4.Cu")
		(net 643)
	)
	(segment
		(start 208.325303 130.336702)
		(end 208.325304 130.336702)
		(width 0.09)
		(layer "In4.Cu")
		(net 643)
	)
	(segment
		(start 208.042461 129.629596)
		(end 208.572792 130.159927)
		(width 0.09)
		(layer "In4.Cu")
		(net 643)
	)
	(segment
		(start 208.077815 130.548835)
		(end 208.077817 130.548834)
		(width 0.09)
		(layer "In4.Cu")
		(net 643)
	)
	(segment
		(start 207.427339 128.5)
		(end 207 128.5)
		(width 0.09)
		(layer "In4.Cu")
		(net 643)
	)
	(segment
		(start 202.5 127.825)
		(end 202.5 127.25)
		(width 0.09)
		(layer "In4.Cu")
		(net 643)
	)
	(segment
		(start 207.052512 131.11452)
		(end 207.052512 131.114521)
		(width 0.09)
		(layer "In4.Cu")
		(net 643)
	)
	(segment
		(start 215.927 140.65)
		(end 214.748309 140.65)
		(width 0.09)
		(layer "In4.Cu")
		(net 643)
	)
	(segment
		(start 210.625 132.875)
		(end 210.625 132.8)
		(width 0.09)
		(layer "In4.Cu")
		(net 643)
	)
	(segment
		(start 208.042462 129.629596)
		(end 208.042461 129.629596)
		(width 0.09)
		(layer "In4.Cu")
		(net 643)
	)
	(segment
		(start 209.325 131.5)
		(end 209.325 130.975)
		(width 0.09)
		(layer "In4.Cu")
		(net 643)
	)
	(segment
		(start 207.653554 130.760969)
		(end 207.653552 130.760966)
		(width 0.09)
		(layer "In4.Cu")
		(net 643)
	)
	(segment
		(start 208.87604 129.314644)
		(end 208.876041 129.314646)
		(width 0.09)
		(layer "In4.Cu")
		(net 643)
	)
	(segment
		(start 207.653552 130.760966)
		(end 207.299999 131.114519)
		(width 0.09)
		(layer "In4.Cu")
		(net 643)
	)
	(segment
		(start 202.5 127.25)
		(end 202.375 127.125)
		(width 0.09)
		(layer "In4.Cu")
		(net 643)
	)
	(segment
		(start 210.025 133.625)
		(end 210.475 133.625)
		(width 0.09)
		(layer "In4.Cu")
		(net 643)
	)
	(segment
		(start 207 128.5)
		(end 206.4 127.9)
		(width 0.09)
		(layer "In4.Cu")
		(net 643)
	)
	(segment
		(start 206.856066 129.118934)
		(end 206.785356 129.048224)
		(width 0.09)
		(layer "In4.Cu")
		(net 643)
	)
	(segment
		(start 202.375 127.125)
		(end 202.225 127.125)
		(width 0.09)
		(layer "In4.Cu")
		(net 643)
	)
	(segment
		(start 202.225 127.125)
		(end 202.1 127.25)
		(width 0.09)
		(layer "In4.Cu")
		(net 643)
	)
	(segment
		(start 208.11142 131.006704)
		(end 207.865686 130.760969)
		(width 0.09)
		(layer "In4.Cu")
		(net 643)
	)
	(segment
		(start 208.304066 129.376727)
		(end 208.299697 129.372358)
		(width 0.09)
		(layer "In4.Cu")
		(net 643)
	)
	(segment
		(start 208.593198 129.314645)
		(end 208.557843 129.349999)
		(width 0.09)
		(layer "In4.Cu")
		(net 643)
	)
	(segment
		(start 208.077817 130.548834)
		(end 208.323552 130.794572)
		(width 0.09)
		(layer "In4.Cu")
		(net 643)
	)
	(segment
		(start 210.175 133.025)
		(end 210.475 133.025)
		(width 0.09)
		(layer "In4.Cu")
		(net 643)
	)
	(segment
		(start 214.285 140.186691)
		(end 214.285 138.56)
		(width 0.09)
		(layer "In4.Cu")
		(net 643)
	)
	(segment
		(start 202.575 127.9)
		(end 202.5 127.825)
		(width 0.09)
		(layer "In4.Cu")
		(net 643)
	)
	(segment
		(start 207.052512 130.867033)
		(end 207.83033 130.089216)
		(width 0.09)
		(layer "In4.Cu")
		(net 643)
	)
	(segment
		(start 208.925 130)
		(end 208.840686 129.915685)
		(width 0.09)
		(layer "In4.Cu")
		(net 643)
	)
	(segment
		(start 210.625 134.9)
		(end 210.625 134.675)
		(width 0.09)
		(layer "In4.Cu")
		(net 643)
	)
	(segment
		(start 208.840685 129.632842)
		(end 208.876039 129.597487)
		(width 0.09)
		(layer "In4.Cu")
		(net 643)
	)
	(segment
		(start 214.285 138.56)
		(end 210.625 134.9)
		(width 0.09)
		(layer "In4.Cu")
		(net 643)
	)
	(segment
		(start 210.475 133.325)
		(end 210.175 133.325)
		(width 0.09)
		(layer "In4.Cu")
		(net 643)
	)
	(segment
		(start 210.475 133.925)
		(end 210.025 133.925)
		(width 0.09)
		(layer "In4.Cu")
		(net 643)
	)
	(segment
		(start 207.280333 128.906804)
		(end 207.28033 128.906802)
		(width 0.09)
		(layer "In4.Cu")
		(net 643)
	)
	(arc
		(start 209.875 133.775)
		(mid 209.918934 133.668934)
		(end 210.025 133.625)
		(width 0.09)
		(layer "In4.Cu")
		(net 643)
	)
	(arc
		(start 207.052512 131.114521)
		(mid 207.001256 130.990777)
		(end 207.052512 130.867033)
		(width 0.09)
		(layer "In4.Cu")
		(net 643)
	)
	(arc
		(start 208.840686 129.915685)
		(mid 208.782107 129.774264)
		(end 208.840685 129.632842)
		(width 0.09)
		(layer "In4.Cu")
		(net 643)
	)
	(arc
		(start 207.451169 128.735964)
		(mid 207.495104 128.629898)
		(end 207.45117 128.523831)
		(width 0.09)
		(layer "In4.Cu")
		(net 643)
	)
	(arc
		(start 207.83033 129.841729)
		(mid 207.724264 129.797795)
		(end 207.618198 129.841729)
		(width 0.09)
		(layer "In4.Cu")
		(net 643)
	)
	(arc
		(start 210.625 134.075)
		(mid 210.581066 133.968934)
		(end 210.475 133.925)
		(width 0.09)
		(layer "In4.Cu")
		(net 643)
	)
	(arc
		(start 208.323552 130.794572)
		(mid 208.367486 130.900637)
		(end 208.323551 131.006703)
		(width 0.09)
		(layer "In4.Cu")
		(net 643)
	)
	(arc
		(start 210.175 133.325)
		(mid 210.068934 133.281066)
		(end 210.025 133.175)
		(width 0.09)
		(layer "In4.Cu")
		(net 643)
	)
	(arc
		(start 206.785356 129.048224)
		(mid 206.741422 128.942158)
		(end 206.785356 128.836092)
		(width 0.09)
		(layer "In4.Cu")
		(net 643)
	)
	(arc
		(start 207.830329 130.089216)
		(mid 207.881586 129.965473)
		(end 207.83033 129.841729)
		(width 0.09)
		(layer "In4.Cu")
		(net 643)
	)
	(arc
		(start 210.475 133.625)
		(mid 210.581066 133.581066)
		(end 210.625 133.475)
		(width 0.09)
		(layer "In4.Cu")
		(net 643)
	)
	(arc
		(start 210.625 133.475)
		(mid 210.581066 133.368934)
		(end 210.475 133.325)
		(width 0.09)
		(layer "In4.Cu")
		(net 643)
	)
	(arc
		(start 208.077816 130.336702)
		(mid 208.033882 130.442769)
		(end 208.077815 130.548835)
		(width 0.09)
		(layer "In4.Cu")
		(net 643)
	)
	(arc
		(start 208.876039 129.597487)
		(mid 208.934618 129.456066)
		(end 208.87604 129.314644)
		(width 0.09)
		(layer "In4.Cu")
		(net 643)
	)
	(arc
		(start 206.785356 128.836092)
		(mid 206.891423 128.792158)
		(end 206.997489 128.836091)
		(width 0.09)
		(layer "In4.Cu")
		(net 643)
	)
	(arc
		(start 206.92084 130.539084)
		(mid 206.814774 130.583019)
		(end 206.708707 130.539085)
		(width 0.09)
		(layer "In4.Cu")
		(net 643)
	)
	(arc
		(start 210.025 133.175)
		(mid 210.068934 133.068934)
		(end 210.175 133.025)
		(width 0.09)
		(layer "In4.Cu")
		(net 643)
	)
	(arc
		(start 210.025 133.925)
		(mid 209.918934 133.881066)
		(end 209.875 133.775)
		(width 0.09)
		(layer "In4.Cu")
		(net 643)
	)
	(arc
		(start 206.92084 129.690556)
		(mid 206.814774 129.734491)
		(end 206.708707 129.690557)
		(width 0.09)
		(layer "In4.Cu")
		(net 643)
	)
	(arc
		(start 206.708707 129.690557)
		(mid 206.664773 129.584491)
		(end 206.708707 129.478425)
		(width 0.09)
		(layer "In4.Cu")
		(net 643)
	)
	(arc
		(start 208.323552 131.006704)
		(mid 208.217487 131.050636)
		(end 208.111421 131.006703)
		(width 0.09)
		(layer "In4.Cu")
		(net 643)
	)
	(arc
		(start 208.042462 129.417462)
		(mid 207.998527 129.52353)
		(end 208.042462 129.629596)
		(width 0.09)
		(layer "In4.Cu")
		(net 643)
	)
	(arc
		(start 208.557843 129.349999)
		(mid 208.436021 129.407635)
		(end 208.304066 129.376727)
		(width 0.09)
		(layer "In4.Cu")
		(net 643)
	)
	(arc
		(start 208.572792 130.159927)
		(mid 208.616726 130.265993)
		(end 208.572792 130.372059)
		(width 0.09)
		(layer "In4.Cu")
		(net 643)
	)
	(arc
		(start 207.875433 129.160228)
		(mid 207.919368 129.054162)
		(end 207.875434 128.948095)
		(width 0.09)
		(layer "In4.Cu")
		(net 643)
	)
	(arc
		(start 208.572792 130.372059)
		(mid 208.466726 130.415993)
		(end 208.36066 130.372059)
		(width 0.09)
		(layer "In4.Cu")
		(net 643)
	)
	(arc
		(start 206.856066 129.331066)
		(mid 206.9 129.225001)
		(end 206.856065 129.118935)
		(width 0.09)
		(layer "In4.Cu")
		(net 643)
	)
	(arc
		(start 207.865686 130.760969)
		(mid 207.75962 130.717035)
		(end 207.653554 130.760969)
		(width 0.09)
		(layer "In4.Cu")
		(net 643)
	)
	(arc
		(start 210.175 134.525)
		(mid 210.068934 134.481066)
		(end 210.025 134.375)
		(width 0.09)
		(layer "In4.Cu")
		(net 643)
	)
	(arc
		(start 210.025 134.375)
		(mid 210.068934 134.268934)
		(end 210.175 134.225)
		(width 0.09)
		(layer "In4.Cu")
		(net 643)
	)
	(arc
		(start 210.475 133.025)
		(mid 210.581066 132.981066)
		(end 210.625 132.875)
		(width 0.09)
		(layer "In4.Cu")
		(net 643)
	)
	(arc
		(start 208.325304 130.336702)
		(mid 208.20156 130.285446)
		(end 208.077816 130.336702)
		(width 0.09)
		(layer "In4.Cu")
		(net 643)
	)
	(arc
		(start 208.299697 129.372358)
		(mid 208.193631 129.328424)
		(end 208.087565 129.372358)
		(width 0.09)
		(layer "In4.Cu")
		(net 643)
	)
	(arc
		(start 208.876041 129.314646)
		(mid 208.73462 129.256067)
		(end 208.593198 129.314645)
		(width 0.09)
		(layer "In4.Cu")
		(net 643)
	)
	(arc
		(start 210.625 134.675)
		(mid 210.581066 134.568934)
		(end 210.475 134.525)
		(width 0.09)
		(layer "In4.Cu")
		(net 643)
	)
	(arc
		(start 207.068201 128.906804)
		(mid 207.174267 128.950738)
		(end 207.280333 128.906804)
		(width 0.09)
		(layer "In4.Cu")
		(net 643)
	)
	(arc
		(start 207.875433 128.948094)
		(mid 207.769367 128.90416)
		(end 207.663301 128.948094)
		(width 0.09)
		(layer "In4.Cu")
		(net 643)
	)
	(arc
		(start 207.299999 131.114519)
		(mid 207.176256 131.165776)
		(end 207.052512 131.11452)
		(width 0.09)
		(layer "In4.Cu")
		(net 643)
	)
	(arc
		(start 206.708707 130.539085)
		(mid 206.664773 130.433019)
		(end 206.708707 130.326953)
		(width 0.09)
		(layer "In4.Cu")
		(net 643)
	)
	(arc
		(start 210.475 134.225)
		(mid 210.581066 134.181066)
		(end 210.625 134.075)
		(width 0.09)
		(layer "In4.Cu")
		(net 643)
	)
	(via
		(at 216.5 142.65)
		(size 0.35)
		(drill 0.15)
		(layers "F.Cu" "B.Cu")
		(remove_unused_layers yes)
		(keep_end_layers yes)
		(zone_layer_connections)
		(net 644)
	)
	(via
		(at 202.1 128.3)
		(size 0.35)
		(drill 0.15)
		(layers "F.Cu" "B.Cu")
		(remove_unused_layers yes)
		(keep_end_layers yes)
		(zone_layer_connections)
		(net 644)
	)
	(segment
		(start 209.62665 132.928859)
		(end 209.626649 132.928857)
		(width 0.09)
		(layer "In4.Cu")
		(net 644)
	)
	(segment
		(start 208.247791 132.822791)
		(end 208.247792 132.822792)
		(width 0.09)
		(layer "In4.Cu")
		(net 644)
	)
	(segment
		(start 209.35 133.925)
		(end 209.35 134.471191)
		(width 0.09)
		(layer "In4.Cu")
		(net 644)
	)
	(segment
		(start 208.919544 131.090381)
		(end 207.823527 132.186395)
		(width 0.09)
		(layer "In4.Cu")
		(net 644)
	)
	(segment
		(start 214.263955 141.869315)
		(end 213.592205 142.541068)
		(width 0.09)
		(layer "In4.Cu")
		(net 644)
	)
	(segment
		(start 213.1 140.316451)
		(end 214.263955 141.480407)
		(width 0.09)
		(layer "In4.Cu")
		(net 644)
	)
	(segment
		(start 214.358032 142.800545)
		(end 214.511309 142.953821)
		(width 0.09)
		(layer "In4.Cu")
		(net 644)
	)
	(segment
		(start 214.758796 142.95382)
		(end 214.758796 142.953821)
		(width 0.09)
		(layer "In4.Cu")
		(net 644)
	)
	(segment
		(start 207.894239 131.267158)
		(end 207.399263 131.762131)
		(width 0.09)
		(layer "In4.Cu")
		(net 644)
	)
	(segment
		(start 207.611397 131.974263)
		(end 208.707412 130.878249)
		(width 0.09)
		(layer "In4.Cu")
		(net 644)
	)
	(segment
		(start 207.823527 132.398527)
		(end 207.823528 132.398528)
		(width 0.09)
		(layer "In4.Cu")
		(net 644)
	)
	(segment
		(start 209.096321 131.762132)
		(end 208.247791 132.610659)
		(width 0.09)
		(layer "In4.Cu")
		(net 644)
	)
	(segment
		(start 206.25 128.7)
		(end 206.475 128.925)
		(width 0.09)
		(layer "In4.Cu")
		(net 644)
	)
	(segment
		(start 203.15 128.3)
		(end 203.55 128.7)
		(width 0.09)
		(layer "In4.Cu")
		(net 644)
	)
	(segment
		(start 209.343807 132.363174)
		(end 209.343808 132.363173)
		(width 0.09)
		(layer "In4.Cu")
		(net 644)
	)
	(segment
		(start 215.487843 142.93)
		(end 216.137157 142.93)
		(width 0.09)
		(layer "In4.Cu")
		(net 644)
	)
	(segment
		(start 214.991769 142.20822)
		(end 215.019343 142.235794)
		(width 0.09)
		(layer "In4.Cu")
		(net 644)
	)
	(segment
		(start 214.60552 142.305569)
		(end 214.605519 142.305569)
		(width 0.09)
		(layer "In4.Cu")
		(net 644)
	)
	(segment
		(start 213.592204 142.929976)
		(end 213.592206 142.929977)
		(width 0.09)
		(layer "In4.Cu")
		(net 644)
	)
	(segment
		(start 213.592205 142.541068)
		(end 213.592203 142.541067)
		(width 0.09)
		(layer "In4.Cu")
		(net 644)
	)
	(segment
		(start 208.919543 131.090382)
		(end 208.919544 131.090381)
		(width 0.09)
		(layer "In4.Cu")
		(net 644)
	)
	(segment
		(start 215.077922 142.377216)
		(end 215.077922 142.520079)
		(width 0.09)
		(layer "In4.Cu")
		(net 644)
	)
	(segment
		(start 216.278578 142.871422)
		(end 216.5 142.65)
		(width 0.09)
		(layer "In4.Cu")
		(net 644)
	)
	(segment
		(start 209.09632 131.762133)
		(end 209.096321 131.762132)
		(width 0.09)
		(layer "In4.Cu")
		(net 644)
	)
	(segment
		(start 214.758796 142.706333)
		(end 214.605519 142.553056)
		(width 0.09)
		(layer "In4.Cu")
		(net 644)
	)
	(segment
		(start 206.475 131.05)
		(end 206.975 131.55)
		(width 0.09)
		(layer "In4.Cu")
		(net 644)
	)
	(segment
		(start 209.096319 133.67132)
		(end 209.35 133.925)
		(width 0.09)
		(layer "In4.Cu")
		(net 644)
	)
	(segment
		(start 209.343808 132.363173)
		(end 208.672055 133.034923)
		(width 0.09)
		(layer "In4.Cu")
		(net 644)
	)
	(segment
		(start 207.187133 131.549999)
		(end 207.682107 131.055026)
		(width 0.09)
		(layer "In4.Cu")
		(net 644)
	)
	(segment
		(start 215.1365 142.6615)
		(end 215.346421 142.871421)
		(width 0.09)
		(layer "In4.Cu")
		(net 644)
	)
	(segment
		(start 214.605519 142.305569)
		(end 214.652865 142.258226)
		(width 0.09)
		(layer "In4.Cu")
		(net 644)
	)
	(segment
		(start 202.1 128.3)
		(end 203.15 128.3)
		(width 0.09)
		(layer "In4.Cu")
		(net 644)
	)
	(segment
		(start 208.035661 132.398527)
		(end 208.884189 131.55)
		(width 0.09)
		(layer "In4.Cu")
		(net 644)
	)
	(segment
		(start 213.1 138.221191)
		(end 213.1 140.316451)
		(width 0.09)
		(layer "In4.Cu")
		(net 644)
	)
	(segment
		(start 208.884189 133.247055)
		(end 209.414519 132.716726)
		(width 0.09)
		(layer "In4.Cu")
		(net 644)
	)
	(segment
		(start 207.894238 131.267159)
		(end 207.894239 131.267158)
		(width 0.09)
		(layer "In4.Cu")
		(net 644)
	)
	(segment
		(start 214.652865 142.258226)
		(end 214.702896 142.208205)
		(width 0.09)
		(layer "In4.Cu")
		(net 644)
	)
	(segment
		(start 209.626649 132.928857)
		(end 209.096319 133.459188)
		(width 0.09)
		(layer "In4.Cu")
		(net 644)
	)
	(segment
		(start 208.672055 133.247055)
		(end 208.672056 133.247056)
		(width 0.09)
		(layer "In4.Cu")
		(net 644)
	)
	(segment
		(start 213.981114 142.929977)
		(end 214.110546 142.800545)
		(width 0.09)
		(layer "In4.Cu")
		(net 644)
	)
	(segment
		(start 207.399263 131.974263)
		(end 207.399264 131.974264)
		(width 0.09)
		(layer "In4.Cu")
		(net 644)
	)
	(segment
		(start 209.35 134.471191)
		(end 213.1 138.221191)
		(width 0.09)
		(layer "In4.Cu")
		(net 644)
	)
	(segment
		(start 206.475 128.925)
		(end 206.475 131.05)
		(width 0.09)
		(layer "In4.Cu")
		(net 644)
	)
	(segment
		(start 203.55 128.7)
		(end 206.25 128.7)
		(width 0.09)
		(layer "In4.Cu")
		(net 644)
	)
	(segment
		(start 208.459925 132.822791)
		(end 209.131676 132.151041)
		(width 0.09)
		(layer "In4.Cu")
		(net 644)
	)
	(arc
		(start 215.077922 142.520079)
		(mid 215.093146 142.596615)
		(end 215.1365 142.6615)
		(width 0.09)
		(layer "In4.Cu")
		(net 644)
	)
	(arc
		(start 208.672056 133.247056)
		(mid 208.778124 133.290991)
		(end 208.884189 133.247055)
		(width 0.09)
		(layer "In4.Cu")
		(net 644)
	)
	(arc
		(start 209.096319 133.459188)
		(mid 209.052385 133.565254)
		(end 209.096319 133.67132)
		(width 0.09)
		(layer "In4.Cu")
		(net 644)
	)
	(arc
		(start 207.682107 131.055026)
		(mid 207.788173 131.011092)
		(end 207.894239 131.055026)
		(width 0.09)
		(layer "In4.Cu")
		(net 644)
	)
	(arc
		(start 208.247791 132.610659)
		(mid 208.203857 132.716725)
		(end 208.247791 132.822791)
		(width 0.09)
		(layer "In4.Cu")
		(net 644)
	)
	(arc
		(start 213.592203 142.541067)
		(mid 213.511658 142.735522)
		(end 213.592204 142.929976)
		(width 0.09)
		(layer "In4.Cu")
		(net 644)
	)
	(arc
		(start 207.399264 131.974264)
		(mid 207.505332 132.018199)
		(end 207.611397 131.974263)
		(width 0.09)
		(layer "In4.Cu")
		(net 644)
	)
	(arc
		(start 207.399263 131.762131)
		(mid 207.355329 131.868197)
		(end 207.399263 131.974263)
		(width 0.09)
		(layer "In4.Cu")
		(net 644)
	)
	(arc
		(start 214.263955 141.480407)
		(mid 214.344501 141.674862)
		(end 214.263955 141.869315)
		(width 0.09)
		(layer "In4.Cu")
		(net 644)
	)
	(arc
		(start 207.823527 132.186395)
		(mid 207.779593 132.292461)
		(end 207.823527 132.398527)
		(width 0.09)
		(layer "In4.Cu")
		(net 644)
	)
	(arc
		(start 216.137157 142.93)
		(mid 216.213693 142.914776)
		(end 216.278578 142.871422)
		(width 0.09)
		(layer "In4.Cu")
		(net 644)
	)
	(arc
		(start 215.346421 142.871421)
		(mid 215.411306 142.914776)
		(end 215.487843 142.93)
		(width 0.09)
		(layer "In4.Cu")
		(net 644)
	)
	(arc
		(start 206.975 131.55)
		(mid 207.081068 131.593935)
		(end 207.187133 131.549999)
		(width 0.09)
		(layer "In4.Cu")
		(net 644)
	)
	(arc
		(start 214.511309 142.953821)
		(mid 214.635053 143.005077)
		(end 214.758796 142.95382)
		(width 0.09)
		(layer "In4.Cu")
		(net 644)
	)
	(arc
		(start 208.919544 130.878249)
		(mid 208.963477 130.984315)
		(end 208.919543 131.090382)
		(width 0.09)
		(layer "In4.Cu")
		(net 644)
	)
	(arc
		(start 207.823528 132.398528)
		(mid 207.929596 132.442463)
		(end 208.035661 132.398527)
		(width 0.09)
		(layer "In4.Cu")
		(net 644)
	)
	(arc
		(start 208.247792 132.822792)
		(mid 208.35386 132.866727)
		(end 208.459925 132.822791)
		(width 0.09)
		(layer "In4.Cu")
		(net 644)
	)
	(arc
		(start 209.343808 132.151041)
		(mid 209.387741 132.257107)
		(end 209.343807 132.363174)
		(width 0.09)
		(layer "In4.Cu")
		(net 644)
	)
	(arc
		(start 209.414519 132.716726)
		(mid 209.520585 132.672792)
		(end 209.626651 132.716726)
		(width 0.09)
		(layer "In4.Cu")
		(net 644)
	)
	(arc
		(start 214.605519 142.553056)
		(mid 214.554263 142.429312)
		(end 214.60552 142.305569)
		(width 0.09)
		(layer "In4.Cu")
		(net 644)
	)
	(arc
		(start 215.019343 142.235794)
		(mid 215.062698 142.300679)
		(end 215.077922 142.377216)
		(width 0.09)
		(layer "In4.Cu")
		(net 644)
	)
	(arc
		(start 209.626651 132.716726)
		(mid 209.670584 132.822792)
		(end 209.62665 132.928859)
		(width 0.09)
		(layer "In4.Cu")
		(net 644)
	)
	(arc
		(start 214.758796 142.953821)
		(mid 214.810052 142.830077)
		(end 214.758796 142.706333)
		(width 0.09)
		(layer "In4.Cu")
		(net 644)
	)
	(arc
		(start 208.707412 130.878249)
		(mid 208.813478 130.834315)
		(end 208.919544 130.878249)
		(width 0.09)
		(layer "In4.Cu")
		(net 644)
	)
	(arc
		(start 213.592206 142.929977)
		(mid 213.786659 143.010521)
		(end 213.981114 142.929977)
		(width 0.09)
		(layer "In4.Cu")
		(net 644)
	)
	(arc
		(start 208.672055 133.034923)
		(mid 208.628121 133.140989)
		(end 208.672055 133.247055)
		(width 0.09)
		(layer "In4.Cu")
		(net 644)
	)
	(arc
		(start 208.884189 131.55)
		(mid 208.990255 131.506066)
		(end 209.096321 131.55)
		(width 0.09)
		(layer "In4.Cu")
		(net 644)
	)
	(arc
		(start 214.110546 142.800545)
		(mid 214.234289 142.749289)
		(end 214.358032 142.800545)
		(width 0.09)
		(layer "In4.Cu")
		(net 644)
	)
	(arc
		(start 214.702896 142.208205)
		(mid 214.847336 142.148389)
		(end 214.991769 142.20822)
		(width 0.09)
		(layer "In4.Cu")
		(net 644)
	)
	(arc
		(start 207.894239 131.055026)
		(mid 207.938172 131.161092)
		(end 207.894238 131.267159)
		(width 0.09)
		(layer "In4.Cu")
		(net 644)
	)
	(arc
		(start 209.131676 132.151041)
		(mid 209.237742 132.107107)
		(end 209.343808 132.151041)
		(width 0.09)
		(layer "In4.Cu")
		(net 644)
	)
	(arc
		(start 209.096321 131.55)
		(mid 209.140254 131.656066)
		(end 209.09632 131.762133)
		(width 0.09)
		(layer "In4.Cu")
		(net 644)
	)
	(via
		(at 215.613 140.05)
		(size 0.35)
		(drill 0.15)
		(layers "F.Cu" "B.Cu")
		(remove_unused_layers yes)
		(keep_end_layers yes)
		(zone_layer_connections)
		(net 645)
	)
	(via
		(at 201.3 125.901)
		(size 0.35)
		(drill 0.15)
		(layers "F.Cu" "B.Cu")
		(remove_unused_layers yes)
		(keep_end_layers yes)
		(zone_layer_connections)
		(net 645)
	)
	(segment
		(start 199.209 127.351)
		(end 199.46 127.1)
		(width 0.09)
		(layer "In2.Cu")
		(net 645)
	)
	(segment
		(start 200.83 126.371)
		(end 201.3 125.901)
		(width 0.09)
		(layer "In2.Cu")
		(net 645)
	)
	(segment
		(start 209.5 137.25)
		(end 209.495206 137.245206)
		(width 0.09)
		(layer "In2.Cu")
		(net 645)
	)
	(segment
		(start 208.038355 136.792874)
		(end 208.038356 136.792873)
		(width 0.09)
		(layer "In2.Cu")
		(net 645)
	)
	(segment
		(start 207.472674 135.661507)
		(end 207.472675 135.661506)
		(width 0.09)
		(layer "In2.Cu")
		(net 645)
	)
	(segment
		(start 208.583282 135.823687)
		(end 208.583281 135.823688)
		(width 0.09)
		(layer "In2.Cu")
		(net 645)
	)
	(segment
		(start 201.04 128.61)
		(end 200.85 128.42)
		(width 0.09)
		(layer "In2.Cu")
		(net 645)
	)
	(segment
		(start 199.46 127.1)
		(end 199.9 127.1)
		(width 0.09)
		(layer "In2.Cu")
		(net 645)
	)
	(segment
		(start 209.431802 135.823691)
		(end 209.431801 135.823692)
		(width 0.09)
		(layer "In2.Cu")
		(net 645)
	)
	(segment
		(start 212.625 137.775)
		(end 211.85 137.775)
		(width 0.09)
		(layer "In2.Cu")
		(net 645)
	)
	(segment
		(start 205.367301 128.852699)
		(end 205.367301 128.8527)
		(width 0.09)
		(layer "In2.Cu")
		(net 645)
	)
	(segment
		(start 205.124602 129.095399)
		(end 205.01 129.095399)
		(width 0.09)
		(layer "In2.Cu")
		(net 645)
	)
	(segment
		(start 206.7 134.45)
		(end 206.7 134.15)
		(width 0.09)
		(layer "In2.Cu")
		(net 645)
	)
	(segment
		(start 204.767301 128.8527)
		(end 204.767301 128.852699)
		(width 0.09)
		(layer "In2.Cu")
		(net 645)
	)
	(segment
		(start 206.836245 135.025148)
		(end 207.239756 134.621641)
		(width 0.09)
		(layer "In2.Cu")
		(net 645)
	)
	(segment
		(start 200.362309 126.371)
		(end 200.83 126.371)
		(width 0.09)
		(layer "In2.Cu")
		(net 645)
	)
	(segment
		(start 208.391934 137.712083)
		(end 209.070942 137.033076)
		(width 0.09)
		(layer "In2.Cu")
		(net 645)
	)
	(segment
		(start 207.896901 136.085804)
		(end 207.896902 136.085803)
		(width 0.09)
		(layer "In2.Cu")
		(net 645)
	)
	(segment
		(start 208.85881 136.820942)
		(end 208.179827 137.499926)
		(width 0.09)
		(layer "In2.Cu")
		(net 645)
	)
	(segment
		(start 199.209 127.669)
		(end 199.209 127.351)
		(width 0.09)
		(layer "In2.Cu")
		(net 645)
	)
	(segment
		(start 199.484423 127.944423)
		(end 199.209 127.669)
		(width 0.09)
		(layer "In2.Cu")
		(net 645)
	)
	(segment
		(start 200.85 128.42)
		(end 200.85 128.04)
		(width 0.09)
		(layer "In2.Cu")
		(net 645)
	)
	(segment
		(start 201.04 128.61)
		(end 204.524602 128.61)
		(width 0.09)
		(layer "In2.Cu")
		(net 645)
	)
	(segment
		(start 207.967694 137.287795)
		(end 209.431802 135.823691)
		(width 0.09)
		(layer "In2.Cu")
		(net 645)
	)
	(segment
		(start 207.876138 135.258039)
		(end 207.472674 135.661507)
		(width 0.09)
		(layer "In2.Cu")
		(net 645)
	)
	(segment
		(start 208.088272 135.25804)
		(end 208.088273 135.25804)
		(width 0.09)
		(layer "In2.Cu")
		(net 645)
	)
	(segment
		(start 209.283074 137.245206)
		(end 208.604067 137.924214)
		(width 0.09)
		(layer "In2.Cu")
		(net 645)
	)
	(segment
		(start 200.169 126.831)
		(end 200.169 126.564309)
		(width 0.09)
		(layer "In2.Cu")
		(net 645)
	)
	(segment
		(start 199.9 127.1)
		(end 200.169 126.831)
		(width 0.09)
		(layer "In2.Cu")
		(net 645)
	)
	(segment
		(start 206.89 129.271593)
		(end 206.228407 128.61)
		(width 0.09)
		(layer "In2.Cu")
		(net 645)
	)
	(segment
		(start 207.904223 135.654222)
		(end 208.088271 135.470173)
		(width 0.09)
		(layer "In2.Cu")
		(net 645)
	)
	(segment
		(start 206.89 133.96)
		(end 206.89 129.271593)
		(width 0.09)
		(layer "In2.Cu")
		(net 645)
	)
	(segment
		(start 200.754423 127.944423)
		(end 199.484423 127.944423)
		(width 0.09)
		(layer "In2.Cu")
		(net 645)
	)
	(segment
		(start 200.85 128.04)
		(end 200.754423 127.944423)
		(width 0.09)
		(layer "In2.Cu")
		(net 645)
	)
	(segment
		(start 215.613 140.05)
		(end 215.613 139.088)
		(width 0.09)
		(layer "In2.Cu")
		(net 645)
	)
	(segment
		(start 211.325 137.25)
		(end 209.5 137.25)
		(width 0.09)
		(layer "In2.Cu")
		(net 645)
	)
	(segment
		(start 215.613 139.088)
		(end 214.55 138.025)
		(width 0.09)
		(layer "In2.Cu")
		(net 645)
	)
	(segment
		(start 211.85 137.775)
		(end 211.325 137.25)
		(width 0.09)
		(layer "In2.Cu")
		(net 645)
	)
	(segment
		(start 209.070943 136.820943)
		(end 209.070942 136.820942)
		(width 0.09)
		(layer "In2.Cu")
		(net 645)
	)
	(segment
		(start 207.684769 135.873672)
		(end 207.904221 135.654221)
		(width 0.09)
		(layer "In2.Cu")
		(net 645)
	)
	(segment
		(start 209.219668 135.611557)
		(end 208.038355 136.792874)
		(width 0.09)
		(layer "In2.Cu")
		(net 645)
	)
	(segment
		(start 207.826223 136.580742)
		(end 208.583282 135.823687)
		(width 0.09)
		(layer "In2.Cu")
		(net 645)
	)
	(segment
		(start 212.875 138.025)
		(end 212.625 137.775)
		(width 0.09)
		(layer "In2.Cu")
		(net 645)
	)
	(segment
		(start 207.664018 135.045903)
		(end 207.664017 135.045904)
		(width 0.09)
		(layer "In2.Cu")
		(net 645)
	)
	(segment
		(start 207.260542 135.449375)
		(end 207.664018 135.045903)
		(width 0.09)
		(layer "In2.Cu")
		(net 645)
	)
	(segment
		(start 207.027624 134.409509)
		(end 206.949633 134.487499)
		(width 0.09)
		(layer "In2.Cu")
		(net 645)
	)
	(segment
		(start 207.451884 134.833769)
		(end 207.048377 135.23728)
		(width 0.09)
		(layer "In2.Cu")
		(net 645)
	)
	(segment
		(start 207.239756 134.621641)
		(end 207.239755 134.621642)
		(width 0.09)
		(layer "In2.Cu")
		(net 645)
	)
	(segment
		(start 206.7 134.15)
		(end 206.89 133.96)
		(width 0.09)
		(layer "In2.Cu")
		(net 645)
	)
	(segment
		(start 200.169 126.564309)
		(end 200.362309 126.371)
		(width 0.09)
		(layer "In2.Cu")
		(net 645)
	)
	(segment
		(start 207.904221 135.654221)
		(end 207.904223 135.654222)
		(width 0.09)
		(layer "In2.Cu")
		(net 645)
	)
	(segment
		(start 206.7375 134.4875)
		(end 206.7 134.45)
		(width 0.09)
		(layer "In2.Cu")
		(net 645)
	)
	(segment
		(start 208.371148 135.611553)
		(end 207.896901 136.085804)
		(width 0.09)
		(layer "In2.Cu")
		(net 645)
	)
	(segment
		(start 214.55 138.025)
		(end 212.875 138.025)
		(width 0.09)
		(layer "In2.Cu")
		(net 645)
	)
	(segment
		(start 206.228407 128.61)
		(end 205.61 128.61)
		(width 0.09)
		(layer "In2.Cu")
		(net 645)
	)
	(segment
		(start 207.048377 135.23728)
		(end 207.048378 135.237279)
		(width 0.09)
		(layer "In2.Cu")
		(net 645)
	)
	(arc
		(start 207.664018 134.833771)
		(mid 207.557952 134.789837)
		(end 207.451884 134.833769)
		(width 0.09)
		(layer "In2.Cu")
		(net 645)
	)
	(arc
		(start 207.684769 136.085804)
		(mid 207.640835 135.979738)
		(end 207.684769 135.873672)
		(width 0.09)
		(layer "In2.Cu")
		(net 645)
	)
	(arc
		(start 207.239755 134.621642)
		(mid 207.283689 134.515575)
		(end 207.239756 134.409509)
		(width 0.09)
		(layer "In2.Cu")
		(net 645)
	)
	(arc
		(start 209.431802 135.611559)
		(mid 209.325736 135.567625)
		(end 209.219668 135.611557)
		(width 0.09)
		(layer "In2.Cu")
		(net 645)
	)
	(arc
		(start 208.391934 137.924215)
		(mid 208.348 137.818149)
		(end 208.391934 137.712083)
		(width 0.09)
		(layer "In2.Cu")
		(net 645)
	)
	(arc
		(start 208.604067 137.924214)
		(mid 208.498001 137.968149)
		(end 208.391934 137.924215)
		(width 0.09)
		(layer "In2.Cu")
		(net 645)
	)
	(arc
		(start 206.949633 134.487499)
		(mid 206.843568 134.531435)
		(end 206.7375 134.4875)
		(width 0.09)
		(layer "In2.Cu")
		(net 645)
	)
	(arc
		(start 208.583281 135.823688)
		(mid 208.627215 135.717621)
		(end 208.583282 135.611555)
		(width 0.09)
		(layer "In2.Cu")
		(net 645)
	)
	(arc
		(start 207.048378 135.237279)
		(mid 206.942312 135.281214)
		(end 206.836245 135.23728)
		(width 0.09)
		(layer "In2.Cu")
		(net 645)
	)
	(arc
		(start 208.179827 137.499926)
		(mid 208.073761 137.543861)
		(end 207.967694 137.499927)
		(width 0.09)
		(layer "In2.Cu")
		(net 645)
	)
	(arc
		(start 209.495206 137.245206)
		(mid 209.38914 137.201272)
		(end 209.283074 137.245206)
		(width 0.09)
		(layer "In2.Cu")
		(net 645)
	)
	(arc
		(start 205.61 128.61)
		(mid 205.438386 128.681085)
		(end 205.367301 128.852699)
		(width 0.09)
		(layer "In2.Cu")
		(net 645)
	)
	(arc
		(start 209.431801 135.823692)
		(mid 209.475735 135.717625)
		(end 209.431802 135.611559)
		(width 0.09)
		(layer "In2.Cu")
		(net 645)
	)
	(arc
		(start 205.367301 128.8527)
		(mid 205.296216 129.024314)
		(end 205.124602 129.095399)
		(width 0.09)
		(layer "In2.Cu")
		(net 645)
	)
	(arc
		(start 207.472675 135.661506)
		(mid 207.366609 135.705441)
		(end 207.260542 135.661507)
		(width 0.09)
		(layer "In2.Cu")
		(net 645)
	)
	(arc
		(start 208.583282 135.611555)
		(mid 208.477216 135.567621)
		(end 208.371148 135.611553)
		(width 0.09)
		(layer "In2.Cu")
		(net 645)
	)
	(arc
		(start 207.664017 135.045904)
		(mid 207.707951 134.939837)
		(end 207.664018 134.833771)
		(width 0.09)
		(layer "In2.Cu")
		(net 645)
	)
	(arc
		(start 207.896902 136.085803)
		(mid 207.790836 136.129738)
		(end 207.684769 136.085804)
		(width 0.09)
		(layer "In2.Cu")
		(net 645)
	)
	(arc
		(start 208.038356 136.792873)
		(mid 207.93229 136.836808)
		(end 207.826223 136.792874)
		(width 0.09)
		(layer "In2.Cu")
		(net 645)
	)
	(arc
		(start 209.070942 136.820942)
		(mid 208.964876 136.777008)
		(end 208.85881 136.820942)
		(width 0.09)
		(layer "In2.Cu")
		(net 645)
	)
	(arc
		(start 207.260542 135.661507)
		(mid 207.216608 135.555441)
		(end 207.260542 135.449375)
		(width 0.09)
		(layer "In2.Cu")
		(net 645)
	)
	(arc
		(start 207.826223 136.792874)
		(mid 207.782289 136.686808)
		(end 207.826223 136.580742)
		(width 0.09)
		(layer "In2.Cu")
		(net 645)
	)
	(arc
		(start 209.070942 137.033076)
		(mid 209.114877 136.92701)
		(end 209.070943 136.820943)
		(width 0.09)
		(layer "In2.Cu")
		(net 645)
	)
	(arc
		(start 207.967694 137.499927)
		(mid 207.92376 137.393861)
		(end 207.967694 137.287795)
		(width 0.09)
		(layer "In2.Cu")
		(net 645)
	)
	(arc
		(start 205.01 129.095399)
		(mid 204.838386 129.024314)
		(end 204.767301 128.8527)
		(width 0.09)
		(layer "In2.Cu")
		(net 645)
	)
	(arc
		(start 208.088273 135.25804)
		(mid 207.982205 135.214105)
		(end 207.876138 135.258039)
		(width 0.09)
		(layer "In2.Cu")
		(net 645)
	)
	(arc
		(start 207.239756 134.409509)
		(mid 207.13369 134.365575)
		(end 207.027624 134.409509)
		(width 0.09)
		(layer "In2.Cu")
		(net 645)
	)
	(arc
		(start 204.767301 128.852699)
		(mid 204.696216 128.681085)
		(end 204.524602 128.61)
		(width 0.09)
		(layer "In2.Cu")
		(net 645)
	)
	(arc
		(start 208.088271 135.470173)
		(mid 208.132207 135.364108)
		(end 208.088272 135.25804)
		(width 0.09)
		(layer "In2.Cu")
		(net 645)
	)
	(arc
		(start 206.836245 135.23728)
		(mid 206.792311 135.131214)
		(end 206.836245 135.025148)
		(width 0.09)
		(layer "In2.Cu")
		(net 645)
	)
	(via
		(at 201.3 126.701)
		(size 0.35)
		(drill 0.15)
		(layers "F.Cu" "B.Cu")
		(remove_unused_layers yes)
		(keep_end_layers yes)
		(zone_layer_connections)
		(net 646)
	)
	(via
		(at 213.252 141.660071)
		(size 0.35)
		(drill 0.15)
		(layers "F.Cu" "B.Cu")
		(remove_unused_layers yes)
		(keep_end_layers yes)
		(zone_layer_connections)
		(net 646)
	)
	(segment
		(start 211.599776 134.805149)
		(end 211.283527 135.121395)
		(width 0.09)
		(layer "In2.Cu")
		(net 646)
	)
	(segment
		(start 211.707791 135.757791)
		(end 211.707792 135.757792)
		(width 0.09)
		(layer "In2.Cu")
		(net 646)
	)
	(segment
		(start 211.495661 135.333527)
		(end 211.847264 134.981925)
		(width 0.09)
		(layer "In2.Cu")
		(net 646)
	)
	(segment
		(start 216.715 139.725)
		(end 216.715 141.05962)
		(width 0.09)
		(layer "In2.Cu")
		(net 646)
	)
	(segment
		(start 210.859263 134.909263)
		(end 210.859264 134.909264)
		(width 0.09)
		(layer "In2.Cu")
		(net 646)
	)
	(segment
		(start 213.125 137.175)
		(end 214.675 137.175)
		(width 0.09)
		(layer "In2.Cu")
		(net 646)
	)
	(segment
		(start 211.071397 134.909263)
		(end 211.387644 134.593017)
		(width 0.09)
		(layer "In2.Cu")
		(net 646)
	)
	(segment
		(start 212.556319 136.606319)
		(end 212.55632 136.60632)
		(width 0.09)
		(layer "In2.Cu")
		(net 646)
	)
	(segment
		(start 210.647133 134.484999)
		(end 210.715913 134.41622)
		(width 0.09)
		(layer "In2.Cu")
		(net 646)
	)
	(segment
		(start 214.720035 142.219035)
		(end 213.810965 142.219035)
		(width 0.09)
		(layer "In2.Cu")
		(net 646)
	)
	(segment
		(start 207.7 133)
		(end 208.65 133.95)
		(width 0.09)
		(layer "In2.Cu")
		(net 646)
	)
	(segment
		(start 207.7 127.3)
		(end 207.7 133)
		(width 0.09)
		(layer "In2.Cu")
		(net 646)
	)
	(segment
		(start 210.928044 134.628353)
		(end 210.928045 134.628352)
		(width 0.09)
		(layer "In2.Cu")
		(net 646)
	)
	(segment
		(start 215.969 142.919)
		(end 215.42 142.919)
		(width 0.09)
		(layer "In2.Cu")
		(net 646)
	)
	(segment
		(start 201.625 126.376)
		(end 206.776 126.376)
		(width 0.09)
		(layer "In2.Cu")
		(net 646)
	)
	(segment
		(start 213.810965 142.219035)
		(end 213.252 141.660071)
		(width 0.09)
		(layer "In2.Cu")
		(net 646)
	)
	(segment
		(start 213.049332 135.901177)
		(end 213.049333 135.901176)
		(width 0.09)
		(layer "In2.Cu")
		(net 646)
	)
	(segment
		(start 212.980583 137.030583)
		(end 213.125 137.175)
		(width 0.09)
		(layer "In2.Cu")
		(net 646)
	)
	(segment
		(start 212.554394 135.547587)
		(end 212.554395 135.547586)
		(width 0.09)
		(layer "In2.Cu")
		(net 646)
	)
	(segment
		(start 213.473596 136.325441)
		(end 213.473597 136.32544)
		(width 0.09)
		(layer "In2.Cu")
		(net 646)
	)
	(segment
		(start 212.132055 136.182055)
		(end 212.132056 136.182056)
		(width 0.09)
		(layer "In2.Cu")
		(net 646)
	)
	(segment
		(start 201.3 126.701)
		(end 201.625 126.376)
		(width 0.09)
		(layer "In2.Cu")
		(net 646)
	)
	(segment
		(start 216.5 139.51)
		(end 216.715 139.725)
		(width 0.09)
		(layer "In2.Cu")
		(net 646)
	)
	(segment
		(start 216.523 143.473)
		(end 215.969 142.919)
		(width 0.09)
		(layer "In2.Cu")
		(net 646)
	)
	(segment
		(start 211.599775 134.80515)
		(end 211.599776 134.805149)
		(width 0.09)
		(layer "In2.Cu")
		(net 646)
	)
	(segment
		(start 212.059396 135.194057)
		(end 211.707791 135.545659)
		(width 0.09)
		(layer "In2.Cu")
		(net 646)
	)
	(segment
		(start 210.928045 134.628352)
		(end 210.859263 134.697131)
		(width 0.09)
		(layer "In2.Cu")
		(net 646)
	)
	(segment
		(start 216.715 141.05962)
		(end 217.4 141.74462)
		(width 0.09)
		(layer "In2.Cu")
		(net 646)
	)
	(segment
		(start 216.992 143.473)
		(end 216.523 143.473)
		(width 0.09)
		(layer "In2.Cu")
		(net 646)
	)
	(segment
		(start 212.554395 135.547586)
		(end 212.132055 135.969923)
		(width 0.09)
		(layer "In2.Cu")
		(net 646)
	)
	(segment
		(start 215.42 142.919)
		(end 214.720035 142.219035)
		(width 0.09)
		(layer "In2.Cu")
		(net 646)
	)
	(segment
		(start 217.4 141.74462)
		(end 217.4 143.065)
		(width 0.09)
		(layer "In2.Cu")
		(net 646)
	)
	(segment
		(start 214.675 137.175)
		(end 216.5 139)
		(width 0.09)
		(layer "In2.Cu")
		(net 646)
	)
	(segment
		(start 211.283527 135.333527)
		(end 211.283528 135.333528)
		(width 0.09)
		(layer "In2.Cu")
		(net 646)
	)
	(segment
		(start 211.919925 135.757791)
		(end 212.342263 135.335454)
		(width 0.09)
		(layer "In2.Cu")
		(net 646)
	)
	(segment
		(start 208.65 133.95)
		(end 209.9 133.95)
		(width 0.09)
		(layer "In2.Cu")
		(net 646)
	)
	(segment
		(start 216.5 139)
		(end 216.5 139.51)
		(width 0.09)
		(layer "In2.Cu")
		(net 646)
	)
	(segment
		(start 212.768453 136.606319)
		(end 213.261465 136.113308)
		(width 0.09)
		(layer "In2.Cu")
		(net 646)
	)
	(segment
		(start 217.4 143.065)
		(end 216.992 143.473)
		(width 0.09)
		(layer "In2.Cu")
		(net 646)
	)
	(segment
		(start 212.344189 136.182055)
		(end 212.837201 135.689044)
		(width 0.09)
		(layer "In2.Cu")
		(net 646)
	)
	(segment
		(start 212.059395 135.194058)
		(end 212.059396 135.194057)
		(width 0.09)
		(layer "In2.Cu")
		(net 646)
	)
	(segment
		(start 209.9 133.95)
		(end 210.435 134.485)
		(width 0.09)
		(layer "In2.Cu")
		(net 646)
	)
	(segment
		(start 213.049333 135.901176)
		(end 212.556319 136.394187)
		(width 0.09)
		(layer "In2.Cu")
		(net 646)
	)
	(segment
		(start 206.776 126.376)
		(end 207.7 127.3)
		(width 0.09)
		(layer "In2.Cu")
		(net 646)
	)
	(segment
		(start 213.473597 136.32544)
		(end 212.980583 136.818451)
		(width 0.09)
		(layer "In2.Cu")
		(net 646)
	)
	(arc
		(start 212.837201 135.689044)
		(mid 212.943267 135.64511)
		(end 213.049333 135.689044)
		(width 0.09)
		(layer "In2.Cu")
		(net 646)
	)
	(arc
		(start 212.059396 134.981925)
		(mid 212.103329 135.087991)
		(end 212.059395 135.194058)
		(width 0.09)
		(layer "In2.Cu")
		(net 646)
	)
	(arc
		(start 212.342263 135.335454)
		(mid 212.448329 135.29152)
		(end 212.554395 135.335454)
		(width 0.09)
		(layer "In2.Cu")
		(net 646)
	)
	(arc
		(start 212.554395 135.335454)
		(mid 212.598328 135.44152)
		(end 212.554394 135.547587)
		(width 0.09)
		(layer "In2.Cu")
		(net 646)
	)
	(arc
		(start 210.859263 134.697131)
		(mid 210.815329 134.803197)
		(end 210.859263 134.909263)
		(width 0.09)
		(layer "In2.Cu")
		(net 646)
	)
	(arc
		(start 210.928045 134.41622)
		(mid 210.971978 134.522286)
		(end 210.928044 134.628353)
		(width 0.09)
		(layer "In2.Cu")
		(net 646)
	)
	(arc
		(start 210.435 134.485)
		(mid 210.541068 134.528935)
		(end 210.647133 134.484999)
		(width 0.09)
		(layer "In2.Cu")
		(net 646)
	)
	(arc
		(start 213.049333 135.689044)
		(mid 213.093266 135.79511)
		(end 213.049332 135.901177)
		(width 0.09)
		(layer "In2.Cu")
		(net 646)
	)
	(arc
		(start 211.283527 135.121395)
		(mid 211.239593 135.227461)
		(end 211.283527 135.333527)
		(width 0.09)
		(layer "In2.Cu")
		(net 646)
	)
	(arc
		(start 212.980583 136.818451)
		(mid 212.936649 136.924517)
		(end 212.980583 137.030583)
		(width 0.09)
		(layer "In2.Cu")
		(net 646)
	)
	(arc
		(start 212.55632 136.60632)
		(mid 212.662388 136.650255)
		(end 212.768453 136.606319)
		(width 0.09)
		(layer "In2.Cu")
		(net 646)
	)
	(arc
		(start 212.556319 136.394187)
		(mid 212.512385 136.500253)
		(end 212.556319 136.606319)
		(width 0.09)
		(layer "In2.Cu")
		(net 646)
	)
	(arc
		(start 212.132056 136.182056)
		(mid 212.238124 136.225991)
		(end 212.344189 136.182055)
		(width 0.09)
		(layer "In2.Cu")
		(net 646)
	)
	(arc
		(start 210.859264 134.909264)
		(mid 210.965332 134.953199)
		(end 211.071397 134.909263)
		(width 0.09)
		(layer "In2.Cu")
		(net 646)
	)
	(arc
		(start 211.847264 134.981925)
		(mid 211.95333 134.937991)
		(end 212.059396 134.981925)
		(width 0.09)
		(layer "In2.Cu")
		(net 646)
	)
	(arc
		(start 213.261465 136.113308)
		(mid 213.367531 136.069374)
		(end 213.473597 136.113308)
		(width 0.09)
		(layer "In2.Cu")
		(net 646)
	)
	(arc
		(start 211.387644 134.593017)
		(mid 211.49371 134.549083)
		(end 211.599776 134.593017)
		(width 0.09)
		(layer "In2.Cu")
		(net 646)
	)
	(arc
		(start 212.132055 135.969923)
		(mid 212.088121 136.075989)
		(end 212.132055 136.182055)
		(width 0.09)
		(layer "In2.Cu")
		(net 646)
	)
	(arc
		(start 213.473597 136.113308)
		(mid 213.51753 136.219374)
		(end 213.473596 136.325441)
		(width 0.09)
		(layer "In2.Cu")
		(net 646)
	)
	(arc
		(start 211.283528 135.333528)
		(mid 211.389596 135.377463)
		(end 211.495661 135.333527)
		(width 0.09)
		(layer "In2.Cu")
		(net 646)
	)
	(arc
		(start 211.707792 135.757792)
		(mid 211.81386 135.801727)
		(end 211.919925 135.757791)
		(width 0.09)
		(layer "In2.Cu")
		(net 646)
	)
	(arc
		(start 211.707791 135.545659)
		(mid 211.663857 135.651725)
		(end 211.707791 135.757791)
		(width 0.09)
		(layer "In2.Cu")
		(net 646)
	)
	(arc
		(start 210.715913 134.41622)
		(mid 210.821979 134.372286)
		(end 210.928045 134.41622)
		(width 0.09)
		(layer "In2.Cu")
		(net 646)
	)
	(arc
		(start 211.599776 134.593017)
		(mid 211.643709 134.699083)
		(end 211.599775 134.80515)
		(width 0.09)
		(layer "In2.Cu")
		(net 646)
	)
	(via
		(at 213.615 140.05)
		(size 0.35)
		(drill 0.15)
		(layers "F.Cu" "B.Cu")
		(remove_unused_layers yes)
		(keep_end_layers yes)
		(zone_layer_connections)
		(net 647)
	)
	(via
		(at 201.3 127.5)
		(size 0.35)
		(drill 0.15)
		(layers "F.Cu" "B.Cu")
		(remove_unused_layers yes)
		(keep_end_layers yes)
		(zone_layer_connections)
		(net 647)
	)
	(segment
		(start 211.015685 136.817767)
		(end 211.015687 136.817768)
		(width 0.09)
		(layer "In2.Cu")
		(net 647)
	)
	(segment
		(start 216.1 139.8)
		(end 216.1 139.05)
		(width 0.09)
		(layer "In2.Cu")
		(net 647)
	)
	(segment
		(start 209.813603 136.322792)
		(end 209.813604 136.322791)
		(width 0.09)
		(layer "In2.Cu")
		(net 647)
	)
	(segment
		(start 208.75 135)
		(end 207.2 133.45)
		(width 0.09)
		(layer "In2.Cu")
		(net 647)
	)
	(segment
		(start 216.315 140.85)
		(end 216.439 140.726)
		(width 0.09)
		(layer "In2.Cu")
		(net 647)
	)
	(segment
		(start 210.2 134.85)
		(end 210.2 134.7)
		(width 0.09)
		(layer "In2.Cu")
		(net 647)
	)
	(segment
		(start 211.263173 136.817767)
		(end 211.790824 137.345416)
		(width 0.09)
		(layer "In2.Cu")
		(net 647)
	)
	(segment
		(start 213.125 137.725)
		(end 211.722791 136.322791)
		(width 0.09)
		(layer "In2.Cu")
		(net 647)
	)
	(segment
		(start 210.45 135.262132)
		(end 210.449999 135.262133)
		(width 0.09)
		(layer "In2.Cu")
		(net 647)
	)
	(segment
		(start 211.015684 136.817766)
		(end 210.838909 136.994542)
		(width 0.09)
		(layer "In2.Cu")
		(net 647)
	)
	(segment
		(start 206.55 127.85)
		(end 201.65 127.85)
		(width 0.09)
		(layer "In2.Cu")
		(net 647)
	)
	(segment
		(start 214.475 137.575)
		(end 214.475 137.525)
		(width 0.09)
		(layer "In2.Cu")
		(net 647)
	)
	(segment
		(start 209.778248 136.782411)
		(end 210.874264 135.686396)
		(width 0.09)
		(layer "In2.Cu")
		(net 647)
	)
	(segment
		(start 211.015687 136.817768)
		(end 211.015684 136.817766)
		(width 0.09)
		(layer "In2.Cu")
		(net 647)
	)
	(segment
		(start 209.9 134.7)
		(end 209.9 134.85)
		(width 0.09)
		(layer "In2.Cu")
		(net 647)
	)
	(segment
		(start 209.601471 136.11066)
		(end 210.45 135.262132)
		(width 0.09)
		(layer "In2.Cu")
		(net 647)
	)
	(segment
		(start 209.75 135)
		(end 209.55 135)
		(width 0.09)
		(layer "In2.Cu")
		(net 647)
	)
	(segment
		(start 210.626776 136.782411)
		(end 211.298528 136.11066)
		(width 0.09)
		(layer "In2.Cu")
		(net 647)
	)
	(segment
		(start 211.298528 135.898528)
		(end 211.298527 135.898527)
		(width 0.09)
		(layer "In2.Cu")
		(net 647)
	)
	(segment
		(start 211.298528 136.11066)
		(end 211.298527 136.110661)
		(width 0.09)
		(layer "In2.Cu")
		(net 647)
	)
	(segment
		(start 207.2 128.5)
		(end 206.55 127.85)
		(width 0.09)
		(layer "In2.Cu")
		(net 647)
	)
	(segment
		(start 211.086395 135.898527)
		(end 209.99038 136.994543)
		(width 0.09)
		(layer "In2.Cu")
		(net 647)
	)
	(segment
		(start 214.065 140.5)
		(end 215.565 140.5)
		(width 0.09)
		(layer "In2.Cu")
		(net 647)
	)
	(segment
		(start 209.025 134.725)
		(end 209.025 134.825)
		(width 0.09)
		(layer "In2.Cu")
		(net 647)
	)
	(segment
		(start 216.439 140.139)
		(end 216.1 139.8)
		(width 0.09)
		(layer "In2.Cu")
		(net 647)
	)
	(segment
		(start 210.874264 135.686396)
		(end 210.874263 135.686397)
		(width 0.09)
		(layer "In2.Cu")
		(net 647)
	)
	(segment
		(start 213.615 140.05)
		(end 214.065 140.5)
		(width 0.09)
		(layer "In2.Cu")
		(net 647)
	)
	(segment
		(start 210.45 135.05)
		(end 210.4 135)
		(width 0.09)
		(layer "In2.Cu")
		(net 647)
	)
	(segment
		(start 210.4 135)
		(end 210.35 135)
		(width 0.09)
		(layer "In2.Cu")
		(net 647)
	)
	(segment
		(start 213.875 137.575)
		(end 213.875 137.525)
		(width 0.09)
		(layer "In2.Cu")
		(net 647)
	)
	(segment
		(start 212.038308 137.345415)
		(end 212.03831 137.345416)
		(width 0.09)
		(layer "In2.Cu")
		(net 647)
	)
	(segment
		(start 207.2 133.45)
		(end 207.2 128.5)
		(width 0.09)
		(layer "In2.Cu")
		(net 647)
	)
	(segment
		(start 214.175 137.525)
		(end 214.175 137.575)
		(width 0.09)
		(layer "In2.Cu")
		(net 647)
	)
	(segment
		(start 215.915 140.85)
		(end 216.315 140.85)
		(width 0.09)
		(layer "In2.Cu")
		(net 647)
	)
	(segment
		(start 215.565 140.5)
		(end 215.915 140.85)
		(width 0.09)
		(layer "In2.Cu")
		(net 647)
	)
	(segment
		(start 213.425 137.725)
		(end 213.125 137.725)
		(width 0.09)
		(layer "In2.Cu")
		(net 647)
	)
	(segment
		(start 209.375 134.825)
		(end 209.375 134.725)
		(width 0.09)
		(layer "In2.Cu")
		(net 647)
	)
	(segment
		(start 210.874264 135.474264)
		(end 210.874263 135.474263)
		(width 0.09)
		(layer "In2.Cu")
		(net 647)
	)
	(segment
		(start 201.65 127.85)
		(end 201.3 127.5)
		(width 0.09)
		(layer "In2.Cu")
		(net 647)
	)
	(segment
		(start 214.775 137.725)
		(end 214.625 137.725)
		(width 0.09)
		(layer "In2.Cu")
		(net 647)
	)
	(segment
		(start 216.1 139.05)
		(end 214.775 137.725)
		(width 0.09)
		(layer "In2.Cu")
		(net 647)
	)
	(segment
		(start 213.575 137.525)
		(end 213.575 137.575)
		(width 0.09)
		(layer "In2.Cu")
		(net 647)
	)
	(segment
		(start 216.439 140.726)
		(end 216.439 140.139)
		(width 0.09)
		(layer "In2.Cu")
		(net 647)
	)
	(segment
		(start 208.85 135)
		(end 208.75 135)
		(width 0.09)
		(layer "In2.Cu")
		(net 647)
	)
	(segment
		(start 211.510659 136.570279)
		(end 212.038309 137.097928)
		(width 0.09)
		(layer "In2.Cu")
		(net 647)
	)
	(segment
		(start 210.662131 135.474263)
		(end 209.813603 136.322792)
		(width 0.09)
		(layer "In2.Cu")
		(net 647)
	)
	(segment
		(start 209.99038 136.994543)
		(end 209.990381 136.994542)
		(width 0.09)
		(layer "In2.Cu")
		(net 647)
	)
	(arc
		(start 211.263173 136.817767)
		(mid 211.139429 136.766511)
		(end 211.015685 136.817767)
		(width 0.09)
		(layer "In2.Cu")
		(net 647)
	)
	(arc
		(start 210.449999 135.262133)
		(mid 210.493934 135.156067)
		(end 210.45 135.05)
		(width 0.09)
		(layer "In2.Cu")
		(net 647)
	)
	(arc
		(start 210.05 134.55)
		(mid 209.943934 134.593934)
		(end 209.9 134.7)
		(width 0.09)
		(layer "In2.Cu")
		(net 647)
	)
	(arc
		(start 209.375 134.725)
		(mid 209.323744 134.601256)
		(end 209.2 134.55)
		(width 0.09)
		(layer "In2.Cu")
		(net 647)
	)
	(arc
		(start 209.813604 136.322791)
		(mid 209.707538 136.366726)
		(end 209.601471 136.322792)
		(width 0.09)
		(layer "In2.Cu")
		(net 647)
	)
	(arc
		(start 210.838909 136.994542)
		(mid 210.732843 137.038477)
		(end 210.626776 136.994543)
		(width 0.09)
		(layer "In2.Cu")
		(net 647)
	)
	(arc
		(start 214.625 137.725)
		(mid 214.518934 137.681066)
		(end 214.475 137.575)
		(width 0.09)
		(layer "In2.Cu")
		(net 647)
	)
	(arc
		(start 211.722791 136.322791)
		(mid 211.616725 136.278857)
		(end 211.510659 136.322791)
		(width 0.09)
		(layer "In2.Cu")
		(net 647)
	)
	(arc
		(start 210.2 134.7)
		(mid 210.156066 134.593934)
		(end 210.05 134.55)
		(width 0.09)
		(layer "In2.Cu")
		(net 647)
	)
	(arc
		(start 213.875 137.525)
		(mid 213.831066 137.418934)
		(end 213.725 137.375)
		(width 0.09)
		(layer "In2.Cu")
		(net 647)
	)
	(arc
		(start 210.874263 135.686397)
		(mid 210.918198 135.580331)
		(end 210.874264 135.474264)
		(width 0.09)
		(layer "In2.Cu")
		(net 647)
	)
	(arc
		(start 209.2 134.55)
		(mid 209.076256 134.601256)
		(end 209.025 134.725)
		(width 0.09)
		(layer "In2.Cu")
		(net 647)
	)
	(arc
		(start 209.025 134.825)
		(mid 208.973744 134.948744)
		(end 208.85 135)
		(width 0.09)
		(layer "In2.Cu")
		(net 647)
	)
	(arc
		(start 214.175 137.575)
		(mid 214.131066 137.681066)
		(end 214.025 137.725)
		(width 0.09)
		(layer "In2.Cu")
		(net 647)
	)
	(arc
		(start 209.9 134.85)
		(mid 209.856066 134.956066)
		(end 209.75 135)
		(width 0.09)
		(layer "In2.Cu")
		(net 647)
	)
	(arc
		(start 210.874263 135.474263)
		(mid 210.768197 135.430329)
		(end 210.662131 135.474263)
		(width 0.09)
		(layer "In2.Cu")
		(net 647)
	)
	(arc
		(start 213.725 137.375)
		(mid 213.618934 137.418934)
		(end 213.575 137.525)
		(width 0.09)
		(layer "In2.Cu")
		(net 647)
	)
	(arc
		(start 209.990381 136.994542)
		(mid 209.884315 137.038477)
		(end 209.778248 136.994543)
		(width 0.09)
		(layer "In2.Cu")
		(net 647)
	)
	(arc
		(start 212.03831 137.345416)
		(mid 211.914566 137.396671)
		(end 211.790824 137.345416)
		(width 0.09)
		(layer "In2.Cu")
		(net 647)
	)
	(arc
		(start 211.298527 135.898527)
		(mid 211.192461 135.854593)
		(end 211.086395 135.898527)
		(width 0.09)
		(layer "In2.Cu")
		(net 647)
	)
	(arc
		(start 214.325 137.375)
		(mid 214.218934 137.418934)
		(end 214.175 137.525)
		(width 0.09)
		(layer "In2.Cu")
		(net 647)
	)
	(arc
		(start 212.038309 137.097928)
		(mid 212.089565 137.221672)
		(end 212.038308 137.345415)
		(width 0.09)
		(layer "In2.Cu")
		(net 647)
	)
	(arc
		(start 209.778248 136.994543)
		(mid 209.734314 136.888477)
		(end 209.778248 136.782411)
		(width 0.09)
		(layer "In2.Cu")
		(net 647)
	)
	(arc
		(start 210.626776 136.994543)
		(mid 210.582842 136.888477)
		(end 210.626776 136.782411)
		(width 0.09)
		(layer "In2.Cu")
		(net 647)
	)
	(arc
		(start 214.475 137.525)
		(mid 214.431066 137.418934)
		(end 214.325 137.375)
		(width 0.09)
		(layer "In2.Cu")
		(net 647)
	)
	(arc
		(start 211.510659 136.322791)
		(mid 211.459403 136.446535)
		(end 211.510659 136.570279)
		(width 0.09)
		(layer "In2.Cu")
		(net 647)
	)
	(arc
		(start 213.575 137.575)
		(mid 213.531066 137.681066)
		(end 213.425 137.725)
		(width 0.09)
		(layer "In2.Cu")
		(net 647)
	)
	(arc
		(start 211.298527 136.110661)
		(mid 211.342462 136.004595)
		(end 211.298528 135.898528)
		(width 0.09)
		(layer "In2.Cu")
		(net 647)
	)
	(arc
		(start 209.55 135)
		(mid 209.426256 134.948744)
		(end 209.375 134.825)
		(width 0.09)
		(layer "In2.Cu")
		(net 647)
	)
	(arc
		(start 209.601471 136.322792)
		(mid 209.557537 136.216726)
		(end 209.601471 136.11066)
		(width 0.09)
		(layer "In2.Cu")
		(net 647)
	)
	(arc
		(start 214.025 137.725)
		(mid 213.918934 137.681066)
		(end 213.875 137.575)
		(width 0.09)
		(layer "In2.Cu")
		(net 647)
	)
	(arc
		(start 210.35 135)
		(mid 210.243934 134.956066)
		(end 210.2 134.85)
		(width 0.09)
		(layer "In2.Cu")
		(net 647)
	)
	(segment
		(start 193.95 121.15)
		(end 193.05 121.15)
		(width 0.15)
		(layer "F.Cu")
		(net 649)
	)
	(segment
		(start 192.43 121.15)
		(end 192.15 121.43)
		(width 0.15)
		(layer "F.Cu")
		(net 649)
	)
	(segment
		(start 190.29356 120.55)
		(end 190.02 120.55)
		(width 0.15)
		(layer "F.Cu")
		(net 649)
	)
	(segment
		(start 224.3 122.63)
		(end 224.53 122.4)
		(width 0.2)
		(layer "F.Cu")
		(net 649)
	)
	(segment
		(start 222.35 120.54)
		(end 222.49 120.4)
		(width 0.2)
		(layer "F.Cu")
		(net 649)
	)
	(segment
		(start 191.17356 121.43)
		(end 190.29356 120.55)
		(width 0.15)
		(layer "F.Cu")
		(net 649)
	)
	(segment
		(start 192.15 121.43)
		(end 191.17356 121.43)
		(width 0.15)
		(layer "F.Cu")
		(net 649)
	)
	(segment
		(start 225.7 122.61)
		(end 225.7 123)
		(width 0.2)
		(layer "F.Cu")
		(net 649)
	)
	(segment
		(start 222.35 120.54)
		(end 222.21 120.4)
		(width 0.2)
		(layer "F.Cu")
		(net 649)
	)
	(segment
		(start 225.7 123)
		(end 225.7 123.9)
		(width 0.2)
		(layer "F.Cu")
		(net 649)
	)
	(segment
		(start 224.53 122.4)
		(end 225.49 122.4)
		(width 0.2)
		(layer "F.Cu")
		(net 649)
	)
	(segment
		(start 224.3 123.48)
		(end 224.3 122.63)
		(width 0.2)
		(layer "F.Cu")
		(net 649)
	)
	(segment
		(start 208.57 146.8)
		(end 209.3385 146.8)
		(width 0.35)
		(layer "F.Cu")
		(net 649)
	)
	(segment
		(start 222.49 120.4)
		(end 222.8 120.4)
		(width 0.2)
		(layer "F.Cu")
		(net 649)
	)
	(segment
		(start 193.05 121.15)
		(end 192.43 121.15)
		(width 0.15)
		(layer "F.Cu")
		(net 649)
	)
	(segment
		(start 222.21 120.4)
		(end 221.9 120.4)
		(width 0.2)
		(layer "F.Cu")
		(net 649)
	)
	(segment
		(start 225.49 122.4)
		(end 225.7 122.61)
		(width 0.2)
		(layer "F.Cu")
		(net 649)
	)
	(via
		(at 202.1 126.701)
		(size 0.35)
		(drill 0.15)
		(layers "F.Cu" "B.Cu")
		(remove_unused_layers yes)
		(keep_end_layers yes)
		(zone_layer_connections "In6.Cu")
		(net 649)
	)
	(via
		(at 217.73 144.24)
		(size 0.35)
		(drill 0.15)
		(layers "F.Cu" "B.Cu")
		(remove_unused_layers yes)
		(keep_end_layers yes)
		(zone_layer_connections)
		(net 649)
	)
	(via
		(at 203.699 131.501)
		(size 0.35)
		(drill 0.15)
		(layers "F.Cu" "B.Cu")
		(remove_unused_layers yes)
		(keep_end_layers yes)
		(zone_layer_connections "In6.Cu")
		(net 649)
	)
	(via
		(at 202.1 134.7)
		(size 0.35)
		(drill 0.15)
		(layers "F.Cu" "B.Cu")
		(remove_unused_layers yes)
		(keep_end_layers yes)
		(zone_layer_connections "In6.Cu")
		(net 649)
	)
	(via
		(at 204.499 140.3)
		(size 0.35)
		(drill 0.15)
		(layers "F.Cu" "B.Cu")
		(remove_unused_layers yes)
		(keep_end_layers yes)
		(zone_layer_connections "In6.Cu")
		(net 649)
	)
	(via
		(at 218.65 139.375)
		(size 0.35)
		(drill 0.15)
		(layers "F.Cu" "B.Cu")
		(remove_unused_layers yes)
		(keep_end_layers yes)
		(zone_layer_connections "In2.Cu")
		(net 649)
	)
	(via
		(at 190.885 142.15)
		(size 0.35)
		(drill 0.15)
		(layers "F.Cu" "B.Cu")
		(remove_unused_layers yes)
		(keep_end_layers yes)
		(zone_layer_connections)
		(net 649)
	)
	(via
		(at 209.3385 146.8)
		(size 0.35)
		(drill 0.15)
		(layers "F.Cu" "B.Cu")
		(remove_unused_layers yes)
		(keep_end_layers yes)
		(zone_layer_connections)
		(net 649)
	)
	(via
		(at 217.875 135.475)
		(size 0.35)
		(drill 0.15)
		(layers "F.Cu" "B.Cu")
		(remove_unused_layers yes)
		(keep_end_layers yes)
		(zone_layer_connections "In2.Cu" "In6.Cu")
		(net 649)
	)
	(via
		(at 217.45 135.475)
		(size 0.35)
		(drill 0.15)
		(layers "F.Cu" "B.Cu")
		(remove_unused_layers yes)
		(keep_end_layers yes)
		(zone_layer_connections "In2.Cu" "In6.Cu")
		(net 649)
	)
	(via
		(at 176.45 147.65)
		(size 0.35)
		(drill 0.15)
		(layers "F.Cu" "B.Cu")
		(remove_unused_layers yes)
		(keep_end_layers yes)
		(zone_layer_connections)
		(net 649)
	)
	(via
		(at 211 147)
		(size 0.35)
		(drill 0.15)
		(layers "F.Cu" "B.Cu")
		(remove_unused_layers yes)
		(keep_end_layers yes)
		(zone_layer_connections)
		(net 649)
	)
	(via
		(at 192.125 121.45)
		(size 0.35)
		(drill 0.15)
		(layers "F.Cu" "B.Cu")
		(remove_unused_layers yes)
		(keep_end_layers yes)
		(zone_layer_connections)
		(net 649)
	)
	(via
		(at 206.1 130.701)
		(size 0.35)
		(drill 0.15)
		(layers "F.Cu" "B.Cu")
		(remove_unused_layers yes)
		(keep_end_layers yes)
		(zone_layer_connections "In6.Cu")
		(net 649)
	)
	(via
		(at 204.499 125.901)
		(size 0.35)
		(drill 0.15)
		(layers "F.Cu" "B.Cu")
		(remove_unused_layers yes)
		(keep_end_layers yes)
		(zone_layer_connections "In6.Cu")
		(net 649)
	)
	(via
		(at 216.55 135.475)
		(size 0.35)
		(drill 0.15)
		(layers "F.Cu" "B.Cu")
		(remove_unused_layers yes)
		(keep_end_layers yes)
		(zone_layer_connections "In2.Cu" "In6.Cu")
		(net 649)
	)
	(via
		(at 222.35 120.54)
		(size 0.35)
		(drill 0.15)
		(layers "F.Cu" "B.Cu")
		(remove_unused_layers yes)
		(keep_end_layers yes)
		(zone_layer_connections)
		(net 649)
	)
	(via
		(at 201.3 124.3)
		(size 0.35)
		(drill 0.15)
		(layers "F.Cu" "B.Cu")
		(remove_unused_layers yes)
		(keep_end_layers yes)
		(zone_layer_connections "In6.Cu")
		(net 649)
	)
	(via
		(at 201.3 132.3)
		(size 0.35)
		(drill 0.15)
		(layers "F.Cu" "B.Cu")
		(remove_unused_layers yes)
		(keep_end_layers yes)
		(zone_layer_connections "In6.Cu")
		(net 649)
	)
	(via
		(at 206.1 138.7)
		(size 0.35)
		(drill 0.15)
		(layers "F.Cu" "B.Cu")
		(remove_unused_layers yes)
		(keep_end_layers yes)
		(zone_layer_connections "In6.Cu")
		(net 649)
	)
	(via
		(at 202.9 137.101)
		(size 0.35)
		(drill 0.15)
		(layers "F.Cu" "B.Cu")
		(remove_unused_layers yes)
		(keep_end_layers yes)
		(zone_layer_connections "In6.Cu")
		(net 649)
	)
	(via
		(at 216.1 135.475)
		(size 0.35)
		(drill 0.15)
		(layers "F.Cu" "B.Cu")
		(remove_unused_layers yes)
		(keep_end_layers yes)
		(zone_layer_connections "In6.Cu")
		(net 649)
	)
	(via
		(at 205.299 128.3)
		(size 0.35)
		(drill 0.15)
		(layers "F.Cu" "B.Cu")
		(remove_unused_layers yes)
		(keep_end_layers yes)
		(zone_layer_connections "In6.Cu")
		(net 649)
	)
	(via
		(at 205.3 136.38)
		(size 0.35)
		(drill 0.15)
		(layers "F.Cu" "B.Cu")
		(remove_unused_layers yes)
		(keep_end_layers yes)
		(zone_layer_connections "In6.Cu")
		(net 649)
	)
	(via
		(at 224.3 123.48)
		(size 0.35)
		(drill 0.15)
		(layers "F.Cu" "B.Cu")
		(remove_unused_layers yes)
		(keep_end_layers yes)
		(zone_layer_connections)
		(net 649)
	)
	(via
		(at 204.49 133.94)
		(size 0.35)
		(drill 0.15)
		(layers "F.Cu" "B.Cu")
		(remove_unused_layers yes)
		(keep_end_layers yes)
		(zone_layer_connections "In6.Cu")
		(net 649)
	)
	(via
		(at 217 135.475)
		(size 0.35)
		(drill 0.15)
		(layers "F.Cu" "B.Cu")
		(remove_unused_layers yes)
		(keep_end_layers yes)
		(zone_layer_connections "In2.Cu" "In6.Cu")
		(net 649)
	)
	(segment
		(start 209.9 146.268831)
		(end 209.368831 146.8)
		(width 0.2)
		(layer "B.Cu")
		(net 649)
	)
	(segment
		(start 188.4835 140.4)
		(end 188.6 140.5165)
		(width 0.174)
		(layer "B.Cu")
		(net 649)
	)
	(segment
		(start 218.195 135.475)
		(end 216.1 135.475)
		(width 0.4)
		(layer "B.Cu")
		(net 649)
	)
	(segment
		(start 218.495 135.775)
		(end 218.195 135.475)
		(width 0.4)
		(layer "B.Cu")
		(net 649)
	)
	(segment
		(start 224.3 123.48)
		(end 224.3 121.9)
		(width 0.2)
		(layer "B.Cu")
		(net 649)
	)
	(segment
		(start 217.98 142.04)
		(end 217.98 142.334999)
		(width 0.15)
		(layer "B.Cu")
		(net 649)
	)
	(segment
		(start 210.5 146.52)
		(end 210.54 146.52)
		(width 0.2)
		(layer "B.Cu")
		(net 649)
	)
	(segment
		(start 223.23 124.62)
		(end 222.06 124.62)
		(width 0.35)
		(layer "B.Cu")
		(net 649)
	)
	(segment
		(start 218.65 138.93)
		(end 218.495 138.775)
		(width 0.256)
		(layer "B.Cu")
		(net 649)
	)
	(segment
		(start 222.06 124.62)
		(end 221.004 125.676)
		(width 0.35)
		(layer "B.Cu")
		(net 649)
	)
	(segment
		(start 222.7 143.291)
		(end 222.851 143.291)
		(width 0.125)
		(layer "B.Cu")
		(net 649)
	)
	(segment
		(start 217.98 143.99)
		(end 217.98 142.525)
		(width 0.15)
		(layer "B.Cu")
		(net 649)
	)
	(segment
		(start 212.4 142.95)
		(end 211.15 142.95)
		(width 0.2)
		(layer "B.Cu")
		(net 649)
	)
	(segment
		(start 208.2 138.67)
		(end 207.72 139.15)
		(width 0.14)
		(layer "B.Cu")
		(net 649)
	)
	(segment
		(start 217.98 142.334999)
		(end 218.1725 142.5275)
		(width 0.15)
		(layer "B.Cu")
		(net 649)
	)
	(segment
		(start 201.02 122.6)
		(end 201.02 124.02)
		(width 0.256)
		(layer "B.Cu")
		(net 649)
	)
	(segment
		(start 176.375 147.725)
		(end 175.891 147.725)
		(width 0.174)
		(layer "B.Cu")
		(net 649)
	)
	(segment
		(start 217 129.63)
		(end 217 135.475)
		(width 0.35)
		(layer "B.Cu")
		(net 649)
	)
	(segment
		(start 204.49 133.94)
		(end 204.49 133.95)
		(width 0.4)
		(layer "B.Cu")
		(net 649)
	)
	(segment
		(start 176.45 147.65)
		(end 176.375 147.725)
		(width 0.174)
		(layer "B.Cu")
		(net 649)
	)
	(segment
		(start 188.6 140.5165)
		(end 188.6 141.55)
		(width 0.174)
		(layer "B.Cu")
		(net 649)
	)
	(segment
		(start 188.147 140.4)
		(end 188.4835 140.4)
		(width 0.174)
		(layer "B.Cu")
		(net 649)
	)
	(segment
		(start 210.54 146.52)
		(end 211.5 147.48)
		(width 0.2)
		(layer "B.Cu")
		(net 649)
	)
	(segment
		(start 217.73 144.24)
		(end 217.98 143.99)
		(width 0.15)
		(layer "B.Cu")
		(net 649)
	)
	(segment
		(start 223.75 123.53)
		(end 223.75 124.1)
		(width 0.35)
		(layer "B.Cu")
		(net 649)
	)
	(segment
		(start 191 142.265)
		(end 190.885 142.15)
		(width 0.1)
		(layer "B.Cu")
		(net 649)
	)
	(segment
		(start 203.69 125.7)
		(end 204.298 125.7)
		(width 0.4)
		(layer "B.Cu")
		(net 649)
	)
	(segment
		(start 218.65 139.375)
		(end 218.65 138.93)
		(width 0.256)
		(layer "B.Cu")
		(net 649)
	)
	(segment
		(start 223.95 121.55)
		(end 222.83 121.55)
		(width 0.2)
		(layer "B.Cu")
		(net 649)
	)
	(segment
		(start 208.2 137.3)
		(end 208.2 138.67)
		(width 0.14)
		(layer "B.Cu")
		(net 649)
	)
	(segment
		(start 207.72 139.15)
		(end 207.025 139.845)
		(width 0.14)
		(layer "B.Cu")
		(net 649)
	)
	(segment
		(start 223.54 144.96)
		(end 223.96 144.96)
		(width 0.15)
		(layer "B.Cu")
		(net 649)
	)
	(segment
		(start 191.403027 142.331)
		(end 191.584027 142.15)
		(width 0.174)
		(layer "B.Cu")
		(net 649)
	)
	(segment
		(start 175.7 146.885)
		(end 175.665 146.85)
		(width 0.174)
		(layer "B.Cu")
		(net 649)
	)
	(segment
		(start 220.676966 143.361)
		(end 220.78253 143.466564)
		(width 0.15)
		(layer "B.Cu")
		(net 649)
	)
	(segment
		(start 209.9 144.2)
		(end 209.9 146.268831)
		(width 0.2)
		(layer "B.Cu")
		(net 649)
	)
	(segment
		(start 201.02 124.02)
		(end 201.3 124.3)
		(width 0.256)
		(layer "B.Cu")
		(net 649)
	)
	(segment
		(start 222.851 143.291)
		(end 223.2175 143.6575)
		(width 0.125)
		(layer "B.Cu")
		(net 649)
	)
	(segment
		(start 218.66 141.36)
		(end 223.22 141.36)
		(width 0.15)
		(layer "B.Cu")
		(net 649)
	)
	(segment
		(start 188.888 141.838)
		(end 190.028 141.838)
		(width 0.174)
		(layer "B.Cu")
		(net 649)
	)
	(segment
		(start 215.83 128.46)
		(end 217 129.63)
		(width 0.35)
		(layer "B.Cu")
		(net 649)
	)
	(segment
		(start 219.006001 143.361)
		(end 220.676966 143.361)
		(width 0.15)
		(layer "B.Cu")
		(net 649)
	)
	(segment
		(start 218.1725 142.5275)
		(end 219.006001 143.361)
		(width 0.15)
		(layer "B.Cu")
		(net 649)
	)
	(segment
		(start 219.604 125.676)
		(end 218.17 127.11)
		(width 0.35)
		(layer "B.Cu")
		(net 649)
	)
	(segment
		(start 190.521 142.331)
		(end 191.403027 142.331)
		(width 0.174)
		(layer "B.Cu")
		(net 649)
	)
	(segment
		(start 204.298 125.7)
		(end 204.499 125.901)
		(width 0.4)
		(layer "B.Cu")
		(net 649)
	)
	(segment
		(start 204.855 139.845)
		(end 204.51 140.19)
		(width 0.14)
		(layer "B.Cu")
		(net 649)
	)
	(segment
		(start 210.151169 146.52)
		(end 210.5 146.52)
		(width 0.2)
		(layer "B.Cu")
		(net 649)
	)
	(segment
		(start 202.109 126.71)
		(end 202.1 126.701)
		(width 0.4)
		(layer "B.Cu")
		(net 649)
	)
	(segment
		(start 218.17 142.525)
		(end 217.98 142.525)
		(width 0.15)
		(layer "B.Cu")
		(net 649)
	)
	(segment
		(start 204.5 133.96)
		(end 204.5 134.526)
		(width 0.4)
		(layer "B.Cu")
		(net 649)
	)
	(segment
		(start 175.7 147.916)
		(end 175.7 146.885)
		(width 0.174)
		(layer "B.Cu")
		(net 649)
	)
	(segment
		(start 218 142.02)
		(end 218.66 141.36)
		(width 0.15)
		(layer "B.Cu")
		(net 649)
	)
	(segment
		(start 175.891 147.725)
		(end 175.7 147.916)
		(width 0.174)
		(layer "B.Cu")
		(net 649)
	)
	(segment
		(start 223.4175 143.6575)
		(end 223.5075 143.7475)
		(width 0.125)
		(layer "B.Cu")
		(net 649)
	)
	(segment
		(start 222.515439 143.291)
		(end 222.7 143.291)
		(width 0.15)
		(layer "B.Cu")
		(net 649)
	)
	(segment
		(start 223.54 144.96)
		(end 223.5075 144.9275)
		(width 0.09)
		(layer "B.Cu")
		(net 649)
	)
	(segment
		(start 202.9 137.054)
		(end 203.51 136.444)
		(width 0.4)
		(layer "B.Cu")
		(net 649)
	)
	(segment
		(start 191.584027 142.15)
		(end 192.63 142.15)
		(width 0.174)
		(layer "B.Cu")
		(net 649)
	)
	(segment
		(start 202.726 126.71)
		(end 202.109 126.71)
		(width 0.4)
		(layer "B.Cu")
		(net 649)
	)
	(segment
		(start 209.368831 146.8)
		(end 209.3385 146.8)
		(width 0.2)
		(layer "B.Cu")
		(net 649)
	)
	(segment
		(start 223.5075 144.9275)
		(end 223.5075 143.783688)
		(width 0.09)
		(layer "B.Cu")
		(net 649)
	)
	(segment
		(start 218.17 127.11)
		(end 216.32 127.11)
		(width 0.35)
		(layer "B.Cu")
		(net 649)
	)
	(segment
		(start 222.35 120.54)
		(end 222.35 121.07)
		(width 0.2)
		(layer "B.Cu")
		(net 649)
	)
	(segment
		(start 223.2175 143.6575)
		(end 223.4175 143.6575)
		(width 0.125)
		(layer "B.Cu")
		(net 649)
	)
	(segment
		(start 188.6 141.55)
		(end 188.888 141.838)
		(width 0.174)
		(layer "B.Cu")
		(net 649)
	)
	(segment
		(start 218.1725 142.5275)
		(end 218.17 142.525)
		(width 0.15)
		(layer "B.Cu")
		(net 649)
	)
	(segment
		(start 211.15 142.95)
		(end 209.9 144.2)
		(width 0.2)
		(layer "B.Cu")
		(net 649)
	)
	(segment
		(start 217.98 142.525)
		(end 217.98 142.04)
		(width 0.15)
		(layer "B.Cu")
		(net 649)
	)
	(segment
		(start 190.028 141.838)
		(end 190.521 142.331)
		(width 0.174)
		(layer "B.Cu")
		(net 649)
	)
	(segment
		(start 220.78253 143.466564)
		(end 222.339875 143.466564)
		(width 0.15)
		(layer "B.Cu")
		(net 649)
	)
	(segment
		(start 204.49 133.95)
		(end 204.5 133.96)
		(width 0.4)
		(layer "B.Cu")
		(net 649)
	)
	(segment
		(start 202.9 137.101)
		(end 202.9 137.054)
		(width 0.4)
		(layer "B.Cu")
		(net 649)
	)
	(segment
		(start 222.35 121.07)
		(end 222.83 121.55)
		(width 0.2)
		(layer "B.Cu")
		(net 649)
	)
	(segment
		(start 222.339875 143.466564)
		(end 222.515439 143.291)
		(width 0.15)
		(layer "B.Cu")
		(net 649)
	)
	(segment
		(start 223.5075 143.7475)
		(end 223.5075 143.783688)
		(width 0.125)
		(layer "B.Cu")
		(net 649)
	)
	(segment
		(start 223.06 144.96)
		(end 223.54 144.96)
		(width 0.15)
		(layer "B.Cu")
		(net 649)
	)
	(segment
		(start 207.025 139.845)
		(end 204.855 139.845)
		(width 0.14)
		(layer "B.Cu")
		(net 649)
	)
	(segment
		(start 224.3 121.9)
		(end 223.95 121.55)
		(width 0.2)
		(layer "B.Cu")
		(net 649)
	)
	(segment
		(start 191 142.331)
		(end 191 142.265)
		(width 0.1)
		(layer "B.Cu")
		(net 649)
	)
	(segment
		(start 216.32 127.11)
		(end 215.83 127.6)
		(width 0.35)
		(layer "B.Cu")
		(net 649)
	)
	(segment
		(start 224.3 123.48)
		(end 223.75 123.48)
		(width 0.2)
		(layer "B.Cu")
		(net 649)
	)
	(segment
		(start 221.004 125.676)
		(end 219.604 125.676)
		(width 0.35)
		(layer "B.Cu")
		(net 649)
	)
	(segment
		(start 209.9 146.268831)
		(end 210.151169 146.52)
		(width 0.2)
		(layer "B.Cu")
		(net 649)
	)
	(segment
		(start 215.83 127.6)
		(end 215.83 128.46)
		(width 0.35)
		(layer "B.Cu")
		(net 649)
	)
	(segment
		(start 223.75 124.1)
		(end 223.23 124.62)
		(width 0.35)
		(layer "B.Cu")
		(net 649)
	)
	(segment
		(start 216.8765 144.2765)
		(end 217.29 144.69)
		(width 0.4)
		(layer "In2.Cu")
		(net 649)
	)
	(segment
		(start 217.29 144.68)
		(end 217.29 144.69)
		(width 0.15)
		(layer "In2.Cu")
		(net 649)
	)
	(segment
		(start 209.8 146.8)
		(end 209.3385 146.8)
		(width 0.35)
		(layer "In2.Cu")
		(net 649)
	)
	(segment
		(start 210.8 146.8)
		(end 210.2 146.8)
		(width 0.4)
		(layer "In2.Cu")
		(net 649)
	)
	(segment
		(start 212.9235 144.2765)
		(end 216.8765 144.2765)
		(width 0.4)
		(layer "In2.Cu")
		(net 649)
	)
	(segment
		(start 217.29 144.69)
		(end 217.7 145.1)
		(width 0.4)
		(layer "In2.Cu")
		(net 649)
	)
	(segment
		(start 211.45 145.75)
		(end 212.9235 144.2765)
		(width 0.4)
		(layer "In2.Cu")
		(net 649)
	)
	(segment
		(start 210.2 146.4)
		(end 210.85 145.75)
		(width 0.4)
		(layer "In2.Cu")
		(net 649)
	)
	(segment
		(start 217.7 145.1)
		(end 218.65 145.1)
		(width 0.4)
		(layer "In2.Cu")
		(net 649)
	)
	(segment
		(start 210.2 146.8)
		(end 209.8 146.8)
		(width 0.4)
		(layer "In2.Cu")
		(net 649)
	)
	(segment
		(start 210.85 145.75)
		(end 211.45 145.75)
		(width 0.4)
		(layer "In2.Cu")
		(net 649)
	)
	(segment
		(start 217.73 144.24)
		(end 217.29 144.68)
		(width 0.15)
		(layer "In2.Cu")
		(net 649)
	)
	(segment
		(start 210.2 146.8)
		(end 210.2 146.4)
		(width 0.4)
		(layer "In2.Cu")
		(net 649)
	)
	(segment
		(start 211 147)
		(end 210.8 146.8)
		(width 0.4)
		(layer "In2.Cu")
		(net 649)
	)
	(segment
		(start 206.45 138.35)
		(end 206.1 138.7)
		(width 0.256)
		(layer "In6.Cu")
		(net 649)
	)
	(segment
		(start 191.543778 142.808778)
		(end 191.543778 144.692293)
		(width 0.256)
		(layer "In6.Cu")
		(net 649)
	)
	(segment
		(start 211.98 138.53)
		(end 212.01 138.5)
		(width 0.256)
		(layer "In6.Cu")
		(net 649)
	)
	(segment
		(start 194.05 118.05)
		(end 194.05 119.7)
		(width 0.182)
		(layer "In6.Cu")
		(net 649)
	)
	(segment
		(start 212.01 138.5)
		(end 211.86 138.35)
		(width 0.256)
		(layer "In6.Cu")
		(net 649)
	)
	(segment
		(start 211.98 142.039929)
		(end 211.98 138.53)
		(width 0.256)
		(layer "In6.Cu")
		(net 649)
	)
	(segment
		(start 194.4 120.05)
		(end 194.4 120.65)
		(width 0.182)
		(layer "In6.Cu")
		(net 649)
	)
	(segment
		(start 198.998071 144.892)
		(end 200.213071 143.677)
		(width 0.256)
		(layer "In6.Cu")
		(net 649)
	)
	(segment
		(start 207.8 144.5)
		(end 209.15 143.15)
		(width 0.256)
		(layer "In6.Cu")
		(net 649)
	)
	(segment
		(start 193.65 117.65)
		(end 194.05 118.05)
		(width 0.182)
		(layer "In6.Cu")
		(net 649)
	)
	(segment
		(start 200.213071 143.677)
		(end 206.517 143.677)
		(width 0.256)
		(layer "In6.Cu")
		(net 649)
	)
	(segment
		(start 193.6 121.45)
		(end 192.125 121.45)
		(width 0.182)
		(layer "In6.Cu")
		(net 649)
	)
	(segment
		(start 190.85 117.65)
		(end 193.65 117.65)
		(width 0.182)
		(layer "In6.Cu")
		(net 649)
	)
	(segment
		(start 196.057 145.023)
		(end 196.188 144.892)
		(width 0.256)
		(layer "In6.Cu")
		(net 649)
	)
	(segment
		(start 196.188 144.892)
		(end 198.998071 144.892)
		(width 0.256)
		(layer "In6.Cu")
		(net 649)
	)
	(segment
		(start 194.4 120.65)
		(end 193.6 121.45)
		(width 0.182)
		(layer "In6.Cu")
		(net 649)
	)
	(segment
		(start 207.34 144.5)
		(end 207.8 144.5)
		(width 0.256)
		(layer "In6.Cu")
		(net 649)
	)
	(segment
		(start 210.869929 143.15)
		(end 211.98 142.039929)
		(width 0.256)
		(layer "In6.Cu")
		(net 649)
	)
	(segment
		(start 191.874485 145.023)
		(end 196.057 145.023)
		(width 0.256)
		(layer "In6.Cu")
		(net 649)
	)
	(segment
		(start 206.517 143.677)
		(end 207.34 144.5)
		(width 0.256)
		(layer "In6.Cu")
		(net 649)
	)
	(segment
		(start 191.543778 144.692293)
		(end 191.874485 145.023)
		(width 0.256)
		(layer "In6.Cu")
		(net 649)
	)
	(segment
		(start 194.05 119.7)
		(end 194.4 120.05)
		(width 0.182)
		(layer "In6.Cu")
		(net 649)
	)
	(segment
		(start 209.15 143.15)
		(end 210.869929 143.15)
		(width 0.256)
		(layer "In6.Cu")
		(net 649)
	)
	(segment
		(start 211.86 138.35)
		(end 206.45 138.35)
		(width 0.256)
		(layer "In6.Cu")
		(net 649)
	)
	(segment
		(start 190.885 142.15)
		(end 191.543778 142.808778)
		(width 0.256)
		(layer "In6.Cu")
		(net 649)
	)
	(segment
		(start 185.83 145.21)
		(end 182.95 145.21)
		(width 0.174)
		(layer "In11.Cu")
		(net 649)
	)
	(segment
		(start 181.494027 146.726999)
		(end 180.718819 146.727)
		(width 0.174)
		(layer "In11.Cu")
		(net 649)
	)
	(segment
		(start 180.481819 146.49)
		(end 179.686989 146.49)
		(width 0.174)
		(layer "In11.Cu")
		(net 649)
	)
	(segment
		(start 182.188 146.033026)
		(end 181.494027 146.726999)
		(width 0.174)
		(layer "In11.Cu")
		(net 649)
	)
	(segment
		(start 189.365 143.67)
		(end 187.37 143.67)
		(width 0.174)
		(layer "In11.Cu")
		(net 649)
	)
	(segment
		(start 179.686989 146.49)
		(end 178.612 147.564989)
		(width 0.174)
		(layer "In11.Cu")
		(net 649)
	)
	(segment
		(start 182.188 145.972)
		(end 182.188 146.033026)
		(width 0.174)
		(layer "In11.Cu")
		(net 649)
	)
	(segment
		(start 176.229383 147.65)
		(end 176.45 147.65)
		(width 0.174)
		(layer "In11.Cu")
		(net 649)
	)
	(segment
		(start 176.800054 149.012)
		(end 176.088 148.299946)
		(width 0.174)
		(layer "In11.Cu")
		(net 649)
	)
	(segment
		(start 187.37 143.67)
		(end 185.83 145.21)
		(width 0.174)
		(layer "In11.Cu")
		(net 649)
	)
	(segment
		(start 182.95 145.21)
		(end 182.188 145.972)
		(width 0.174)
		(layer "In11.Cu")
		(net 649)
	)
	(segment
		(start 178.612 147.564989)
		(end 178.612 148.799946)
		(width 0.174)
		(layer "In11.Cu")
		(net 649)
	)
	(segment
		(start 176.088 148.299946)
		(end 176.088 147.791383)
		(width 0.174)
		(layer "In11.Cu")
		(net 649)
	)
	(segment
		(start 190.885 142.15)
		(end 189.365 143.67)
		(width 0.174)
		(layer "In11.Cu")
		(net 649)
	)
	(segment
		(start 178.612 148.799946)
		(end 178.399946 149.012)
		(width 0.174)
		(layer "In11.Cu")
		(net 649)
	)
	(segment
		(start 180.718819 146.727)
		(end 180.481819 146.49)
		(width 0.174)
		(layer "In11.Cu")
		(net 649)
	)
	(segment
		(start 176.088 147.791383)
		(end 176.229383 147.65)
		(width 0.174)
		(layer "In11.Cu")
		(net 649)
	)
	(segment
		(start 178.399946 149.012)
		(end 176.800054 149.012)
		(width 0.174)
		(layer "In11.Cu")
		(net 649)
	)
	(via
		(at 182.049 154.799)
		(size 0.35)
		(drill 0.15)
		(layers "F.Cu" "B.Cu")
		(remove_unused_layers yes)
		(keep_end_layers yes)
		(zone_layer_connections)
		(net 650)
	)
	(segment
		(start 200.9 128.699)
		(end 200.499 129.1)
		(width 0.1)
		(layer "F.Cu")
		(net 655)
	)
	(segment
		(start 189.65 122.575)
		(end 190.175 123.1)
		(width 0.1)
		(layer "F.Cu")
		(net 655)
	)
	(segment
		(start 199.75 122.6)
		(end 200.9 123.75)
		(width 0.1)
		(layer "F.Cu")
		(net 655)
	)
	(segment
		(start 189.65 121.1)
		(end 189.65 122.575)
		(width 0.1)
		(layer "F.Cu")
		(net 655)
	)
	(segment
		(start 193.975 123.1)
		(end 194.475 122.6)
		(width 0.1)
		(layer "F.Cu")
		(net 655)
	)
	(segment
		(start 190.175 123.1)
		(end 193.975 123.1)
		(width 0.1)
		(layer "F.Cu")
		(net 655)
	)
	(segment
		(start 200.9 123.75)
		(end 200.9 128.699)
		(width 0.1)
		(layer "F.Cu")
		(net 655)
	)
	(segment
		(start 194.475 122.6)
		(end 199.75 122.6)
		(width 0.1)
		(layer "F.Cu")
		(net 655)
	)
	(via
		(at 189.65 121.1)
		(size 0.35)
		(drill 0.15)
		(layers "F.Cu" "B.Cu")
		(remove_unused_layers yes)
		(keep_end_layers yes)
		(zone_layer_connections)
		(net 655)
	)
	(via
		(at 188.645 116.6)
		(size 0.35)
		(drill 0.15)
		(layers "F.Cu" "B.Cu")
		(remove_unused_layers yes)
		(keep_end_layers yes)
		(zone_layer_connections)
		(net 655)
	)
	(segment
		(start 188.67 120.37)
		(end 187.85 120.37)
		(width 0.1)
		(layer "B.Cu")
		(net 655)
	)
	(segment
		(start 182.65 117.997999)
		(end 182.65 117.2)
		(width 0.1)
		(layer "B.Cu")
		(net 655)
	)
	(segment
		(start 189.4 121.1)
		(end 188.67 120.37)
		(width 0.1)
		(layer "B.Cu")
		(net 655)
	)
	(segment
		(start 189.65 121.1)
		(end 189.4 121.1)
		(width 0.1)
		(layer "B.Cu")
		(net 655)
	)
	(segment
		(start 188.445 116.4)
		(end 188.645 116.6)
		(width 0.1)
		(layer "B.Cu")
		(net 655)
	)
	(segment
		(start 183.45 116.4)
		(end 188.445 116.4)
		(width 0.1)
		(layer "B.Cu")
		(net 655)
	)
	(segment
		(start 182.65 117.2)
		(end 183.45 116.4)
		(width 0.1)
		(layer "B.Cu")
		(net 655)
	)
	(segment
		(start 189.65 117.605)
		(end 189.65 121.1)
		(width 0.1)
		(layer "In4.Cu")
		(net 655)
	)
	(segment
		(start 188.645 116.6)
		(end 189.65 117.605)
		(width 0.1)
		(layer "In4.Cu")
		(net 655)
	)
	(segment
		(start 179.035 146.035)
		(end 178.65 145.65)
		(width 0.15)
		(layer "F.Cu")
		(net 656)
	)
	(segment
		(start 179.105 146.035)
		(end 179.035 146.035)
		(width 0.15)
		(layer "F.Cu")
		(net 656)
	)
	(segment
		(start 178.65 145.65)
		(end 178.65 144.95)
		(width 0.15)
		(layer "F.Cu")
		(net 656)
	)
	(segment
		(start 178.65 144.95)
		(end 179 144.6)
		(width 0.15)
		(layer "F.Cu")
		(net 656)
	)
	(segment
		(start 179 144.6)
		(end 179 144.0875)
		(width 0.15)
		(layer "F.Cu")
		(net 656)
	)
	(via
		(at 183.090096 153.848958)
		(size 0.35)
		(drill 0.15)
		(layers "F.Cu" "B.Cu")
		(remove_unused_layers yes)
		(keep_end_layers yes)
		(zone_layer_connections)
		(net 656)
	)
	(via
		(at 179.105 146.035)
		(size 0.35)
		(drill 0.15)
		(layers "F.Cu" "B.Cu")
		(remove_unused_layers yes)
		(keep_end_layers yes)
		(zone_layer_connections)
		(net 656)
	)
	(via
		(at 181.85 147.830489)
		(size 0.35)
		(drill 0.15)
		(layers "F.Cu" "B.Cu")
		(remove_unused_layers yes)
		(keep_end_layers yes)
		(zone_layer_connections)
		(net 656)
	)
	(segment
		(start 179.105 146.035)
		(end 179.75 146.035)
		(width 0.15)
		(layer "B.Cu")
		(net 656)
	)
	(segment
		(start 181.85 147.2)
		(end 181.85 147.830489)
		(width 0.15)
		(layer "B.Cu")
		(net 656)
	)
	(segment
		(start 179.525 146.0375)
		(end 180.6875 146.0375)
		(width 0.15)
		(layer "B.Cu")
		(net 656)
	)
	(segment
		(start 180.6875 146.0375)
		(end 181.85 147.2)
		(width 0.15)
		(layer "B.Cu")
		(net 656)
	)
	(segment
		(start 181.190096 150.598958)
		(end 183.240096 150.598958)
		(width 0.1)
		(layer "In7.Cu")
		(net 656)
	)
	(segment
		(start 184.090096 147.248958)
		(end 182.240096 147.248958)
		(width 0.1)
		(layer "In7.Cu")
		(net 656)
	)
	(segment
		(start 182.240096 147.248958)
		(end 181.85 147.639054)
		(width 0.1)
		(layer "In7.Cu")
		(net 656)
	)
	(segment
		(start 180.940096 150.848958)
		(end 181.190096 150.598958)
		(width 0.1)
		(layer "In7.Cu")
		(net 656)
	)
	(segment
		(start 183.240096 150.598958)
		(end 184.240096 149.598958)
		(width 0.1)
		(layer "In7.Cu")
		(net 656)
	)
	(segment
		(start 184.440096 147.598958)
		(end 184.090096 147.248958)
		(width 0.1)
		(layer "In7.Cu")
		(net 656)
	)
	(segment
		(start 184.240096 149.598958)
		(end 184.240096 148.748958)
		(width 0.1)
		(layer "In7.Cu")
		(net 656)
	)
	(segment
		(start 180.940096 151.698958)
		(end 180.940096 150.848958)
		(width 0.1)
		(layer "In7.Cu")
		(net 656)
	)
	(segment
		(start 184.440096 148.548958)
		(end 184.440096 147.598958)
		(width 0.1)
		(layer "In7.Cu")
		(net 656)
	)
	(segment
		(start 183.090096 153.848958)
		(end 180.940096 151.698958)
		(width 0.1)
		(layer "In7.Cu")
		(net 656)
	)
	(segment
		(start 181.85 147.639054)
		(end 181.85 147.830489)
		(width 0.1)
		(layer "In7.Cu")
		(net 656)
	)
	(segment
		(start 184.240096 148.748958)
		(end 184.440096 148.548958)
		(width 0.1)
		(layer "In7.Cu")
		(net 656)
	)
	(zone
		(net 184)
		(net_name "Net-(U7-SW4)")
		(layer "F.Cu")
		(name "SW4")
		(hatch edge 0.5)
		(priority 2)
		(connect_pads yes
			(clearance 0.1)
		)
		(min_thickness 0.1)
		(filled_areas_thickness no)
		(fill yes
			(thermal_gap 0.15)
			(thermal_bridge_width 0.3)
		)
		(polygon
			(pts
				(xy 180.875 142.3375) (xy 184.2 142.3375) (xy 184.325 142.4625) (xy 184.325 143.2875) (xy 184.2 143.4125)
				(xy 182.55 143.4125) (xy 182.425 143.2875) (xy 182.425 142.9125) (xy 182.05 142.5375) (xy 180.875 142.5375)
			)
		)
	)
	(zone
		(net 417)
		(net_name "GND")
		(layer "F.Cu")
		(name "GND")
		(hatch edge 0.5)
		(connect_pads yes
			(clearance 0.1)
		)
		(min_thickness 0.25)
		(filled_areas_thickness no)
		(fill yes
			(thermal_gap 0.5)
			(thermal_bridge_width 0.5)
			(island_removal_mode 1)
			(island_area_min 10)
		)
		(polygon
			(pts
				(xy 189.100004 146.904531) (xy 189.100504 148.004531) (xy 185.05 148.005587) (xy 184.800004 148.254531)
				(xy 184.800004 149.5) (xy 183.009904 149.5) (xy 182.55 149.954531) (xy 180.600004 149.954531) (xy 179.700642 149.054531)
				(xy 179.700004 147.204531) (xy 180.600004 147.204531) (xy 180.900004 146.904531)
			)
		)
	)
	(zone
		(net 90)
		(net_name "+5V")
		(layer "F.Cu")
		(hatch edge 0.5)
		(connect_pads yes
			(clearance 0.12)
		)
		(min_thickness 0.12)
		(filled_areas_thickness no)
		(fill yes
			(thermal_gap 0.2)
			(thermal_bridge_width 0.2)
		)
		(polygon
			(pts
				(xy 194.4 115.85) (xy 194.4 117.95) (xy 192.5 117.95) (xy 188 122.25) (xy 187.95 132.2) (xy 187.95 143.699074)
				(xy 185.45 146.1875) (xy 185.45 146.7) (xy 185.2 146.95) (xy 181.2 146.95) (xy 180.9 147.25) (xy 180.5 147.25)
				(xy 179.55 146.2) (xy 180.45 145.3) (xy 180.4 143.75) (xy 180.6 143.75) (xy 180.6 144.625) (xy 180.6 143.75)
				(xy 180.6125 143.7375) (xy 181.15 143.7375) (xy 181.15 144.5375) (xy 181.27412 144.675) (xy 181.75 144.67312)
				(xy 181.75 145.163408) (xy 182.35 145.653695) (xy 184.208805 145.653695) (xy 184.376497 145.486003)
				(xy 184.375709 144.820187) (xy 184.495335 144.695335) (xy 185.16875 144.69375) (xy 185.55 144.3125)
				(xy 185.55 139.629695) (xy 184.170305 138.25) (xy 179.15 138.25) (xy 179.15 137.2) (xy 179.25 137.1)
				(xy 185.2 137.1) (xy 185.275 137.03) (xy 185.275 120.75) (xy 190.75 115.85)
			)
		)
	)
	(zone
		(net 417)
		(net_name "GND")
		(layer "F.Cu")
		(name "GND")
		(hatch edge 0.5)
		(priority 14)
		(connect_pads yes
			(clearance 0.34)
		)
		(min_thickness 0.1)
		(filled_areas_thickness no)
		(fill yes
			(thermal_gap 0.5)
			(thermal_bridge_width 0.5)
			(smoothing fillet)
			(radius 0.5)
		)
		(polygon
			(pts
				(xy 224.55 142.25) (xy 224.55 135.355) (xy 229.1 135.355) (xy 229.1 143.105) (xy 226.4 143.1) (xy 226 142.7)
				(xy 225 142.7)
			)
		)
	)
	(zone
		(net 175)
		(net_name "Net-(U7-SW2)")
		(layer "F.Cu")
		(name "SW2")
		(hatch edge 0.5)
		(priority 2)
		(connect_pads yes
			(clearance 0.1)
		)
		(min_thickness 0.1)
		(filled_areas_thickness no)
		(fill yes
			(thermal_gap 0.15)
			(thermal_bridge_width 0.3)
		)
		(polygon
			(pts
				(xy 180.875 141.5375) (xy 184.2 141.5375) (xy 184.325 141.4125) (xy 184.325 140.5875) (xy 184.2 140.4625)
				(xy 182.55 140.4625) (xy 182.425 140.5875) (xy 182.425 140.9625) (xy 182.05 141.3375) (xy 180.875 141.3375)
			)
		)
	)
	(zone
		(net 90)
		(net_name "+5V")
		(layer "F.Cu")
		(name "+5V")
		(hatch edge 0.5)
		(connect_pads yes
			(clearance 0.1)
		)
		(min_thickness 0.25)
		(filled_areas_thickness no)
		(fill yes
			(thermal_gap 0.5)
			(thermal_bridge_width 0.5)
		)
		(polygon
			(pts
				(xy 177.7 139.9) (xy 179.3 139.9) (xy 179.7 139.5) (xy 179.7 138.4) (xy 179.5 138.2) (xy 179.15 138.2)
				(xy 179.15 137.45) (xy 181.15 137.45) (xy 181.15 139.5) (xy 181.45 139.9) (xy 182.55 139.9) (xy 182.55 144)
				(xy 177.65 144)
			)
		)
	)
	(zone
		(net 209)
		(net_name "/Supply/SENSE1_P")
		(layer "F.Cu")
		(name "SENSE1")
		(hatch edge 0.5)
		(priority 2)
		(connect_pads yes
			(clearance 0.1)
		)
		(min_thickness 0.1)
		(filled_areas_thickness no)
		(fill yes
			(thermal_gap 0.15)
			(thermal_bridge_width 0.3)
		)
		(polygon
			(pts
				(xy 177.5 140.0375) (xy 176.025 140.0375) (xy 175.875 140.1875) (xy 175.875 140.8375) (xy 175.075 140.8375)
				(xy 175.075 139.4375) (xy 175.225 139.2875) (xy 176.15 139.2875) (xy 176.3 139.1375) (xy 176.3 138.1375)
				(xy 176.425 138.0125) (xy 177.525 138.0125) (xy 177.65 138.1375) (xy 177.65 139.8875)
			)
		)
	)
	(zone
		(net 417)
		(net_name "GND")
		(layer "F.Cu")
		(name "GND")
		(hatch edge 0.5)
		(priority 1)
		(connect_pads yes
			(clearance 0.1)
		)
		(min_thickness 0.25)
		(filled_areas_thickness no)
		(fill yes
			(thermal_gap 0.15)
			(thermal_bridge_width 0.3)
		)
		(polygon
			(pts
				(xy 179.375 142.0875) (xy 178.05 142.0875) (xy 177.9 142.2375) (xy 176.2 142.2375) (xy 176.05 142.3875)
				(xy 176.05 142.8875) (xy 175 142.8875) (xy 175 141.0375) (xy 176.05 141.0375) (xy 176.05 141.4875)
				(xy 176.2 141.6375) (xy 177.9 141.6375) (xy 178.05 141.7875) (xy 179.375 141.7875)
			)
		)
	)
	(zone
		(net 181)
		(net_name "Net-(U7-SW3)")
		(layer "F.Cu")
		(name "SW3")
		(hatch edge 0.5)
		(priority 2)
		(connect_pads yes
			(clearance 0.1)
		)
		(min_thickness 0.1)
		(filled_areas_thickness no)
		(fill yes
			(thermal_gap 0.15)
			(thermal_bridge_width 0.3)
		)
		(polygon
			(pts
				(xy 179.375 142.3375) (xy 176.425 142.3375) (xy 176.3 142.4625) (xy 176.3 143.6125) (xy 176.425 143.7375)
				(xy 177.525 143.7375) (xy 177.65 143.6125) (xy 177.65 142.9625) (xy 178.075 142.5375) (xy 179.375 142.5375)
			)
		)
	)
	(zone
		(net 409)
		(net_name "/Supply/SENSE4_P")
		(layer "F.Cu")
		(name "SENSE4")
		(hatch edge 0.5)
		(priority 2)
		(connect_pads yes
			(clearance 0.1)
		)
		(min_thickness 0.1)
		(filled_areas_thickness no)
		(fill yes
			(thermal_gap 0.15)
			(thermal_bridge_width 0.3)
		)
		(polygon
			(pts
				(xy 182.55 143.9625) (xy 182.925 143.5875) (xy 184.425 143.5875) (xy 184.575 143.4375) (xy 184.575 143.2625)
				(xy 184.725 143.1125) (xy 185.225 143.1125) (xy 185.375 143.2625) (xy 185.375 144.4375) (xy 185.225 144.5875)
				(xy 184.475 144.5875) (xy 184.325 144.7375) (xy 184.325 145.5125) (xy 184.2 145.6375) (xy 182.55 145.6375)
				(xy 182.425 145.5125) (xy 182.425 144.6875) (xy 182.55 144.5625)
			)
		)
	)
	(zone
		(net 272)
		(net_name "/Supply/SENSE3_P")
		(layer "F.Cu")
		(name "SENSE2")
		(hatch edge 0.5)
		(priority 2)
		(connect_pads yes
			(clearance 0.1)
		)
		(min_thickness 0.1)
		(filled_areas_thickness no)
		(fill yes
			(thermal_gap 0.15)
			(thermal_bridge_width 0.3)
		)
		(polygon
			(pts
				(xy 182.55 140.0875) (xy 182.8 140.3375) (xy 184.45 140.3375) (xy 184.6 140.4875) (xy 184.6 140.6875)
				(xy 184.75 140.8375) (xy 185.25 140.8375) (xy 185.4 140.6875) (xy 185.4 139.9875) (xy 185.4 139.975)
				(xy 184.75 139.3125) (xy 184.475 139.3125) (xy 184.325 139.1625) (xy 184.325 138.3875) (xy 184.2 138.2625)
				(xy 182.55 138.2625) (xy 182.425 138.3875) (xy 182.425 139.2125) (xy 182.55 139.3375)
			)
		)
	)
	(zone
		(net 417)
		(net_name "GND")
		(layer "F.Cu")
		(name "GND")
		(hatch edge 0.5)
		(priority 3)
		(connect_pads yes
			(clearance 0.1)
		)
		(min_thickness 0.25)
		(filled_areas_thickness no)
		(fill yes
			(thermal_gap 0.5)
			(thermal_bridge_width 0.5)
		)
		(polygon
			(pts
				(xy 211.4 141) (xy 211.4 143.2) (xy 209 143.2) (xy 209 141)
			)
		)
	)
	(zone
		(net 47)
		(net_name "+1V05")
		(layer "F.Cu")
		(name "+1V05")
		(hatch edge 0.5)
		(priority 3)
		(connect_pads yes
			(clearance 0.1)
		)
		(min_thickness 0.25)
		(filled_areas_thickness no)
		(fill yes
			(thermal_gap 0.5)
			(thermal_bridge_width 0.5)
		)
		(polygon
			(pts
				(xy 185.6 146.05) (xy 186.9 144.75) (xy 186.9 143.85) (xy 188.35 143.85) (xy 188.35 146.25) (xy 187.7 146.25)
				(xy 187.15 146.8) (xy 185.6 146.8)
			)
		)
	)
	(zone
		(net 150)
		(net_name "/Supply/1V05_SW")
		(layer "F.Cu")
		(name "1V05_SW")
		(hatch edge 0.5)
		(priority 1)
		(connect_pads yes
			(clearance 0.1)
		)
		(min_thickness 0.25)
		(filled_areas_thickness no)
		(fill yes
			(thermal_gap 0.5)
			(thermal_bridge_width 0.5)
		)
		(polygon
			(pts
				(xy 182.684404 150.354531) (xy 184.709404 150.354531) (xy 184.666633 150.5) (xy 184.647357 152.159734)
				(xy 185.584904 153.097281) (xy 189.559904 153.097281) (xy 189.559904 151.972281) (xy 188.611033 151.104531)
				(xy 186.534404 151.104531) (xy 185.984404 150.554531) (xy 185.984404 149.735892) (xy 185.7526 149.5)
				(xy 182.684404 149.5)
			)
		)
	)
	(zone
		(net 417)
		(net_name "GND")
		(layer "F.Cu")
		(hatch edge 0.5)
		(priority 7)
		(connect_pads yes
			(clearance 0.12)
		)
		(min_thickness 0.12)
		(filled_areas_thickness no)
		(fill yes
			(thermal_gap 0.2)
			(thermal_bridge_width 0.2)
		)
		(polygon
			(pts
				(xy 220.9515 143.217) (xy 223.2515 143.217) (xy 223.2515 145.667) (xy 220.9515 145.667)
			)
		)
	)
	(zone
		(net 90)
		(net_name "+5V")
		(layer "F.Cu")
		(name "+5V")
		(hatch edge 0.5)
		(priority 2)
		(connect_pads yes
			(clearance 0.1)
		)
		(min_thickness 0.25)
		(filled_areas_thickness no)
		(fill yes
			(thermal_gap 0.5)
			(thermal_bridge_width 0.5)
		)
		(polygon
			(pts
				(xy 180.422827 150.950245) (xy 180.360478 150.84706) (xy 180.295213 150.748251) (xy 180.215364 150.636316)
				(xy 180.123483 150.525475) (xy 180.040716 150.434323) (xy 179.944095 150.335878) (xy 179.868985 150.267332)
				(xy 179.790959 150.199879) (xy 179.651678 150.090496) (xy 179.535003 150.009918) (xy 179.405203 149.931527)
				(xy 179.303112 149.875377) (xy 179.192271 149.82105) (xy 179.062835 149.762713) (xy 178.951629 149.720783)
				(xy 178.799587 149.671196) (xy 178.652188 149.631065) (xy 178.5 149.6) (xy 178.5 147.25) (xy 179.55 146.2)
				(xy 180.710557 146.2) (xy 180.710557 147.25) (xy 179.810557 147.25) (xy 179.710557 147.35) (xy 179.711195 149.05)
				(xy 180.610557 149.95) (xy 182.110557 149.95) (xy 182.560557 150.4) (xy 183.010557 150.4) (xy 183.010557 150.95)
				(xy 180.910557 150.95)
			)
		)
	)
	(zone
		(net 522)
		(net_name "/Supply/1V05_REG")
		(layer "F.Cu")
		(name "1V05_REG")
		(hatch edge 0.5)
		(priority 1)
		(connect_pads yes
			(clearance 0.1)
		)
		(min_thickness 0.25)
		(filled_areas_thickness no)
		(fill yes
			(thermal_gap 0.5)
			(thermal_bridge_width 0.5)
		)
		(polygon
			(pts
				(xy 189.584404 149.204531) (xy 189.084404 148.804531) (xy 189.084404 148.029531) (xy 185.284404 148.029531)
				(xy 185.284404 148.754531) (xy 186.084404 149.554531) (xy 186.084404 150.679449) (xy 189.584404 150.678531)
			)
		)
	)
	(zone
		(net 417)
		(net_name "GND")
		(layer "F.Cu")
		(name "GND")
		(hatch edge 0.5)
		(priority 1)
		(connect_pads yes
			(clearance 0.1)
		)
		(min_thickness 0.25)
		(filled_areas_thickness no)
		(fill yes
			(thermal_gap 0.5)
			(thermal_bridge_width 0.5)
		)
		(polygon
			(pts
				(xy 177.9 141.6375) (xy 179.4 141.6375) (xy 179.4 141.2375) (xy 180.85 141.2375) (xy 180.85 141.6375)
				(xy 182.35 141.6375) (xy 182.35 142.2375) (xy 180.85 142.2375) (xy 180.85 142.6375) (xy 179.4 142.6375)
				(xy 179.4 142.2375) (xy 177.9 142.2375)
			)
		)
	)
	(zone
		(net 406)
		(net_name "/Supply/SENSE2_P")
		(layer "F.Cu")
		(name "SENSE3")
		(hatch edge 0.5)
		(priority 2)
		(connect_pads yes
			(clearance 0.1)
		)
		(min_thickness 0.1)
		(filled_areas_thickness no)
		(fill yes
			(thermal_gap 0.15)
			(thermal_bridge_width 0.3)
		)
		(polygon
			(pts
				(xy 177.5 143.8375) (xy 176.025 143.8375) (xy 175.875 143.6875) (xy 175.875 143.271305) (xy 175.725 143.121305)
				(xy 175.225 143.121305) (xy 175.075 143.271305) (xy 175.075 144.4125) (xy 175.225 144.5625) (xy 176.15 144.5625)
				(xy 176.3 144.7125) (xy 176.3 145.7125) (xy 176.425 145.8375) (xy 177.525 145.8375) (xy 177.65 145.7125)
				(xy 177.65 143.9875)
			)
		)
	)
	(zone
		(net 417)
		(net_name "GND")
		(layer "F.Cu")
		(name "GND")
		(hatch edge 0.5)
		(priority 3)
		(connect_pads yes
			(clearance 0.1)
		)
		(min_thickness 0.25)
		(filled_areas_thickness no)
		(fill yes
			(thermal_gap 0.5)
			(thermal_bridge_width 0.5)
		)
		(polygon
			(pts
				(xy 189.25 143.85) (xy 191.45 143.85) (xy 191.45 146.25) (xy 189.25 146.25)
			)
		)
	)
	(zone
		(net 168)
		(net_name "Net-(U7-SW1)")
		(layer "F.Cu")
		(name "SW1")
		(hatch edge 0.5)
		(priority 2)
		(connect_pads yes
			(clearance 0.1)
		)
		(min_thickness 0.1)
		(filled_areas_thickness no)
		(fill yes
			(thermal_gap 0.15)
			(thermal_bridge_width 0.3)
		)
		(polygon
			(pts
				(xy 179.375 141.5375) (xy 176.425 141.5375) (xy 176.3 141.4125) (xy 176.3 140.2625) (xy 176.425 140.1375)
				(xy 177.525 140.1375) (xy 177.65 140.2625) (xy 177.65 140.9125) (xy 178.075 141.3375) (xy 179.375 141.3375)
			)
		)
	)
	(zone
		(net 47)
		(net_name "+1V05")
		(layer "F.Cu")
		(name "+1V05")
		(hatch edge 0.5)
		(priority 3)
		(connect_pads yes
			(clearance 0.1)
		)
		(min_thickness 0.25)
		(filled_areas_thickness no)
		(fill yes
			(thermal_gap 0.5)
			(thermal_bridge_width 0.5)
		)
		(polygon
			(pts
				(xy 211.4 138.7) (xy 211.4 140.9) (xy 209 140.9) (xy 209 138.7)
			)
		)
	)
	(zone
		(net 417)
		(net_name "GND")
		(layer "F.Cu")
		(name "GND")
		(hatch edge 0.5)
		(priority 1)
		(connect_pads yes
			(clearance 0.1)
		)
		(min_thickness 0.25)
		(filled_areas_thickness no)
		(fill yes
			(thermal_gap 0.15)
			(thermal_bridge_width 0.3)
		)
		(polygon
			(pts
				(xy 182.2 141.7875) (xy 182.35 141.6375) (xy 184.35 141.6375) (xy 184.5 141.4875) (xy 184.5 141.0375)
				(xy 185.45 141.0375) (xy 185.45 142.9375) (xy 184.45 142.9375) (xy 184.45 142.3875) (xy 184.3 142.2375)
				(xy 182.35 142.2375) (xy 182.2 142.0875) (xy 180.875 142.0875) (xy 180.875 141.7875)
			)
		)
	)
	(zone
		(net 417)
		(net_name "GND")
		(layer "B.Cu")
		(hatch edge 0.5)
		(priority 16)
		(connect_pads yes
			(clearance 0.12)
		)
		(min_thickness 0.12)
		(filled_areas_thickness no)
		(fill yes
			(thermal_gap 0.2)
			(thermal_bridge_width 0.2)
		)
		(polygon
			(pts
				(xy 189.475 142.675) (xy 190.46 142.675) (xy 190.51 142.725) (xy 190.51 143.87) (xy 191 144.36)
				(xy 191.04 144.36) (xy 191.04 146.64) (xy 189.58 146.64) (xy 189.475 146.535)
			)
		)
	)
	(zone
		(net 50)
		(net_name "+3V3")
		(layer "B.Cu")
		(name "+3V3")
		(hatch edge 0.5)
		(priority 1)
		(connect_pads yes
			(clearance 0.1)
		)
		(min_thickness 0.25)
		(filled_areas_thickness no)
		(fill yes
			(thermal_gap 0.5)
			(thermal_bridge_width 0.5)
		)
		(polygon
			(pts
				(xy 177.45 138.05) (xy 176.6 138.05) (xy 176.2 137.6375) (xy 174.8 137.6375) (xy 174.7 137.7375)
				(xy 174.7 139.1375) (xy 174.8 139.2375) (xy 176.2 139.2375) (xy 176.6 138.85) (xy 177.45 138.85)
			)
		)
	)
	(zone
		(net 90)
		(net_name "+5V")
		(layer "B.Cu")
		(hatch edge 0.5)
		(priority 18)
		(connect_pads
			(clearance 0.1)
		)
		(min_thickness 0.25)
		(filled_areas_thickness no)
		(fill yes
			(thermal_gap 0.5)
			(thermal_bridge_width 0.5)
		)
		(polygon
			(pts
				(xy 179.285 142.5675) (xy 180.915 142.5675) (xy 180.915 143.2075) (xy 179.285 143.2075)
			)
		)
	)
	(zone
		(net 90)
		(net_name "+5V")
		(layer "B.Cu")
		(name "+5V")
		(hatch edge 0.5)
		(priority 5)
		(connect_pads yes
			(clearance 0.1)
		)
		(min_thickness 0.25)
		(filled_areas_thickness no)
		(fill yes
			(thermal_gap 0.5)
			(thermal_bridge_width 0.5)
		)
		(polygon
			(pts
				(xy 198.75 145.4) (xy 199.3 145.95) (xy 199.3 146.6) (xy 197.9 148) (xy 197.9 148.5) (xy 196.6 149.8)
				(xy 196.4 149.8) (xy 195.75 149.15) (xy 191.35676 149.15) (xy 189.816219 150.65) (xy 186.9 150.65)
				(xy 186.9 149.05) (xy 188.625 149.05) (xy 189.2875 148.3875) (xy 189.28658 146.825) (xy 190.95 146.825)
				(xy 191.925 147.8) (xy 196.35 147.8)
			)
		)
	)
	(zone
		(net 48)
		(net_name "+1V8")
		(layer "B.Cu")
		(name "+1V8")
		(hatch edge 0.5)
		(priority 1)
		(connect_pads yes
			(clearance 0.1)
		)
		(min_thickness 0.25)
		(filled_areas_thickness no)
		(fill yes
			(thermal_gap 0.5)
			(thermal_bridge_width 0.5)
		)
		(polygon
			(pts
				(xy 177.1 145) (xy 176.45 145) (xy 176.05 144.5875) (xy 174.8 144.5875) (xy 174.7 144.6875) (xy 174.7 146.0875)
				(xy 174.8 146.1875) (xy 176.05 146.1875) (xy 176.45 145.8) (xy 177.1 145.8)
			)
		)
	)
	(zone
		(net 90)
		(net_name "+5V")
		(layer "B.Cu")
		(hatch edge 0.5)
		(priority 18)
		(connect_pads
			(clearance 0.1)
		)
		(min_thickness 0.25)
		(filled_areas_thickness no)
		(fill yes
			(thermal_gap 0.5)
			(thermal_bridge_width 0.5)
		)
		(polygon
			(pts
				(xy 179.285 140.65) (xy 180.915 140.65) (xy 180.915 141.29) (xy 179.285 141.29)
			)
		)
	)
	(zone
		(net 90)
		(net_name "+5V")
		(layer "B.Cu")
		(name "+5V")
		(hatch edge 0.5)
		(priority 4)
		(connect_pads yes
			(clearance 0.1)
		)
		(min_thickness 0.25)
		(filled_areas_thickness no)
		(fill yes
			(thermal_gap 0.15)
			(thermal_bridge_width 0.3)
		)
		(polygon
			(pts
				(xy 192.024 117.349) (xy 192.024 116.714) (xy 192.405 116.206) (xy 194.31 116.206) (xy 194.437 116.333)
				(xy 194.437 116.587) (xy 194.183 116.841) (xy 194.183 117.791) (xy 192.024 117.791)
			)
		)
	)
	(zone
		(net 417)
		(net_name "GND")
		(layer "B.Cu")
		(name "GND")
		(hatch edge 0.5)
		(connect_pads yes
			(clearance 0.1)
		)
		(min_thickness 0.25)
		(filled_areas_thickness no)
		(fill yes
			(thermal_gap 0.5)
			(thermal_bridge_width 0.5)
		)
		(polygon
			(pts
				(xy 215.275 130.275) (xy 215.275 130.95) (xy 214.975 131.25) (xy 213.275 131.25) (xy 213.275 133.1)
				(xy 214.1 133.1) (xy 214.1 132.4) (xy 214.625 131.875) (xy 215.275 131.875) (xy 215.275 132.1) (xy 216.1 132.1)
				(xy 216.1 130.275)
			)
		)
	)
	(zone
		(net 50)
		(net_name "+3V3")
		(layer "B.Cu")
		(name "+5V")
		(hatch edge 0.5)
		(priority 4)
		(connect_pads yes
			(clearance 0.1)
		)
		(min_thickness 0.25)
		(filled_areas_thickness no)
		(fill yes
			(thermal_gap 0.15)
			(thermal_bridge_width 0.3)
		)
		(polygon
			(pts
				(xy 192.325079 120.500921) (xy 193.037 120.501) (xy 193.037 118.814) (xy 193.375 118.476) (xy 193.375 118.026)
				(xy 193.275 117.926) (xy 192.15 117.926) (xy 192.025 118.051) (xy 192.025 118.276) (xy 192.325 118.576)
				(xy 192.325 119.789)
			)
		)
	)
	(zone
		(net 410)
		(net_name "Net-(Q3-D)")
		(layer "B.Cu")
		(name "5V_HDMI")
		(hatch edge 0.5)
		(priority 5)
		(connect_pads yes
			(clearance 0.1)
		)
		(min_thickness 0.25)
		(filled_areas_thickness no)
		(fill yes
			(thermal_gap 0.5)
			(thermal_bridge_width 0.5)
		)
		(polygon
			(pts
				(xy 199.55 151.8) (xy 201.1 151.8) (xy 201.1 150.65) (xy 200.75 150.3) (xy 200.3 150.3) (xy 200.15 150.15)
				(xy 200.15 147.15) (xy 200.35 146.95) (xy 199.7 146.3) (xy 198.9 147.1) (xy 198.8 147.1) (xy 197.9 148)
				(xy 197.9 148.5) (xy 198.95 149.55) (xy 198.95 150.35) (xy 199.55 150.95)
			)
		)
	)
	(zone
		(net 209)
		(net_name "/Supply/SENSE1_P")
		(layer "B.Cu")
		(name "SENSE1")
		(hatch edge 0.5)
		(priority 1)
		(connect_pads yes
			(clearance 0.1)
		)
		(min_thickness 0.25)
		(filled_areas_thickness no)
		(fill yes
			(thermal_gap 0.5)
			(thermal_bridge_width 0.5)
		)
		(polygon
			(pts
				(xy 175.075 140.825) (xy 175.075 139.45) (xy 177.425 139.45) (xy 177.425 140.471015) (xy 176.644704 141.248714)
				(xy 176.249567 141.249567) (xy 175.825 140.825)
			)
		)
	)
	(zone
		(net 409)
		(net_name "/Supply/SENSE4_P")
		(layer "B.Cu")
		(name "SENSE4")
		(hatch edge 0.5)
		(priority 1)
		(connect_pads yes
			(clearance 0.1)
		)
		(min_thickness 0.25)
		(filled_areas_thickness no)
		(fill yes
			(thermal_gap 0.5)
			(thermal_bridge_width 0.5)
		)
		(polygon
			(pts
				(xy 185.375 143.075) (xy 185.375 143.85) (xy 184.85 144.4) (xy 184.325 144.4) (xy 184.225 144.275)
				(xy 184.175 144.275) (xy 183.7 144.75) (xy 183.15 144.25) (xy 183.85 143.55) (xy 184.1 143.55) (xy 184.575 143.074999)
			)
		)
	)
	(zone
		(net 48)
		(net_name "+1V8")
		(layer "B.Cu")
		(name "+5V")
		(hatch edge 0.5)
		(priority 4)
		(connect_pads yes
			(clearance 0.1)
		)
		(min_thickness 0.25)
		(filled_areas_thickness no)
		(fill yes
			(thermal_gap 0.15)
			(thermal_bridge_width 0.3)
		)
		(polygon
			(pts
				(xy 191.602248 119.867248) (xy 191.6 120.501) (xy 192.236 120.501) (xy 192.236 118.601) (xy 191.961 118.326)
				(xy 191.95 118.326) (xy 191.95 118.026) (xy 191.85 117.926) (xy 191.2 117.926) (xy 190.875 118.251)
				(xy 190.875 119.14)
			)
		)
	)
	(zone
		(net 417)
		(net_name "GND")
		(layer "B.Cu")
		(name "GND")
		(hatch edge 0.5)
		(connect_pads yes
			(clearance 0.1)
		)
		(min_thickness 0.25)
		(filled_areas_thickness no)
		(fill yes
			(thermal_gap 0.1)
			(thermal_bridge_width 0.25)
		)
		(polygon
			(pts
				(xy 175 141.0375) (xy 176 141.0375) (xy 179.333334 138.1625) (xy 180.116666 138.1625) (xy 185.45 141.0375)
				(xy 185.45 142.9375) (xy 184.3 143.4375) (xy 181.95 144.5625) (xy 178.025 144.5625) (xy 175 142.8875)
			)
		)
	)
	(zone
		(net 90)
		(net_name "+5V")
		(layer "B.Cu")
		(name "+5V")
		(hatch edge 0.5)
		(priority 16)
		(connect_pads yes
			(clearance 0.1)
		)
		(min_thickness 0.2)
		(filled_areas_thickness no)
		(fill yes
			(thermal_gap 0.5)
			(thermal_bridge_width 0.5)
			(smoothing fillet)
			(radius 0.5)
		)
		(polygon
			(pts
				(xy 184.275 151.57) (xy 188.36 151.6) (xy 188.375 149.05) (xy 185.625 149.05) (xy 185.15 148.575)
				(xy 185.15 146.7) (xy 184 145.55) (xy 182 145.55) (xy 181.8 145.75) (xy 181.8 145.95) (xy 182.55 146.7)
				(xy 182.95 146.7) (xy 184.1 147.85) (xy 184.1 148) (xy 184 148.1) (xy 181.55 148.1) (xy 181.3 147.85)
				(xy 181.3 147) (xy 180.75 146.45) (xy 179.1 146.45) (xy 178.55 147) (xy 178.550048 149.610228) (xy 178.582598 149.617011)
				(xy 178.621965 149.624979) (xy 178.660975 149.633661) (xy 178.705931 149.64496) (xy 178.754813 149.658281)
				(xy 178.806192 149.672434) (xy 178.865539 149.69182) (xy 178.917394 149.708589) (xy 178.969962 149.727024)
				(xy 179.030499 149.749859) (xy 179.084494 149.772099) (xy 179.132424 149.792556) (xy 179.190939 149.818602)
				(xy 179.275262 149.859871) (xy 179.321646 149.884134) (xy 179.383253 149.918148) (xy 179.442125 149.952639)
				(xy 179.502427 149.98882) (xy 179.56736 150.032561) (xy 179.646383 150.087166) (xy 179.727064 150.148274)
				(xy 179.787418 150.197278) (xy 179.82726 150.231273) (xy 179.896737 150.293019) (xy 179.927362 150.321067)
				(xy 179.985341 150.378353) (xy 180.057296 150.452091) (xy 180.101598 150.501448) (xy 180.15482 150.564383)
				(xy 180.187626 150.604424) (xy 180.229148 150.655016) (xy 180.301654 150.756524) (xy 180.370313 150.861584)
				(xy 180.413816 150.933498) (xy 180.437196 150.974634) (xy 180.474485 151.043589) (xy 180.508814 151.111655)
				(xy 180.545807 151.185345) (xy 180.580432 151.267617) (xy 180.610026 151.343674) (xy 180.650274 151.454061)
				(xy 180.682532 151.555273) (xy 180.707391 151.648199) (xy 180.728107 151.731655) (xy 180.747935 151.833163)
				(xy 180.762437 151.91218) (xy 180.777826 152.00629) (xy 180.786704 152.110165) (xy 180.792623 152.227655)
				(xy 180.795582 152.396046) (xy 180.8 155.45) (xy 184.3 155.45)
			)
		)
	)
	(zone
		(net 522)
		(net_name "/Supply/1V05_REG")
		(layer "B.Cu")
		(name "1V05_REG")
		(hatch edge 0.5)
		(priority 3)
		(connect_pads yes
			(clearance 0.1)
		)
		(min_thickness 0.25)
		(filled_areas_thickness no)
		(fill yes
			(thermal_gap 0.5)
			(thermal_bridge_width 0.5)
		)
		(polygon
			(pts
				(xy 189.096875 148.221875) (xy 189.101695 146.9157) (xy 187.825 146.917556) (xy 186.725 148.01875)
				(xy 185.9 148.01875) (xy 185.900586 148.868062) (xy 188.450259 148.868491)
			)
		)
	)
	(zone
		(net 48)
		(net_name "+1V8")
		(layer "B.Cu")
		(hatch edge 0.5)
		(priority 1)
		(connect_pads yes
			(clearance 0.12)
		)
		(min_thickness 0.12)
		(filled_areas_thickness no)
		(fill yes
			(thermal_gap 0.2)
			(thermal_bridge_width 0.2)
		)
		(polygon
			(pts
				(xy 195.405 131.2) (xy 196.58 131.2) (xy 196.58 136.85) (xy 195.04 136.865) (xy 195.05 138.75) (xy 193.5 140.3)
				(xy 193.5 141.65) (xy 188.4065 141.625) (xy 188.3145 141.533) (xy 188.3145 135.8155) (xy 190.48 133.65)
				(xy 190.58 133.65) (xy 194.58 133.65) (xy 194.63 133.6) (xy 194.63 132.725) (xy 195.48 131.875)
				(xy 195.575 131.875) (xy 195.405 131.705)
			)
		)
	)
	(zone
		(net 2)
		(net_name "+1V1")
		(layer "B.Cu")
		(hatch edge 0.5)
		(priority 5)
		(connect_pads yes
			(clearance 0.12)
		)
		(min_thickness 0.12)
		(filled_areas_thickness no)
		(fill yes
			(thermal_gap 0.2)
			(thermal_bridge_width 0.2)
		)
		(polygon
			(pts
				(xy 185.29 122.05) (xy 185.858076 122.618076) (xy 190.35 122.618076) (xy 190.899045 123.15) (xy 196.255 123.15)
				(xy 196.475 123.37) (xy 196.475 126.23) (xy 195.355 127.35) (xy 195.35 131.4) (xy 193.4 133.35)
				(xy 190.35 133.35) (xy 188 135.7) (xy 188 139) (xy 187.355 139.65) (xy 184.836084 139.65) (xy 184.839756 138.618166)
				(xy 184.841644 138.35) (xy 184.55 138.05) (xy 177.54 138.05) (xy 177.04 137.55) (xy 174.34 137.55)
				(xy 174.34 122.05)
			)
		)
	)
	(zone
		(net 96)
		(net_name "+1V2")
		(layer "B.Cu")
		(name "+1V2")
		(hatch edge 0.5)
		(priority 1)
		(connect_pads yes
			(clearance 0.1)
		)
		(min_thickness 0.25)
		(filled_areas_thickness no)
		(fill yes
			(thermal_gap 0.5)
			(thermal_bridge_width 0.5)
		)
		(polygon
			(pts
				(xy 184.7 145.75) (xy 186.85 143.6) (xy 186.85 141.8) (xy 186.65 141.6) (xy 185.95 141.6) (xy 185.75 141.8)
				(xy 185.75 143.6) (xy 184.15 145.2)
			)
		)
	)
	(zone
		(net 47)
		(net_name "+1V05")
		(layer "B.Cu")
		(hatch edge 0.5)
		(priority 14)
		(connect_pads yes
			(clearance 0.12)
		)
		(min_thickness 0.12)
		(filled_areas_thickness no)
		(fill yes
			(thermal_gap 0.2)
			(thermal_bridge_width 0.2)
		)
		(polygon
			(pts
				(xy 195.35 138.875) (xy 198.275 138.875) (xy 198.665 138.485) (xy 198.665 138.42) (xy 199.781 138.42)
				(xy 201.3 139.939) (xy 201.3 140.3) (xy 201.046 140.3) (xy 200.83 140.084) (xy 200.165 140.084)
				(xy 199.87 140.379) (xy 196.25 140.379) (xy 196.250481 140.379494) (xy 194.325 140.376967) (xy 194.325 139.9)
			)
		)
	)
	(zone
		(net 272)
		(net_name "/Supply/SENSE3_P")
		(layer "B.Cu")
		(name "SENSE2")
		(hatch edge 0.5)
		(priority 2)
		(connect_pads yes
			(clearance 0.1)
		)
		(min_thickness 0.25)
		(filled_areas_thickness no)
		(fill yes
			(thermal_gap 0.5)
			(thermal_bridge_width 0.5)
		)
		(polygon
			(pts
				(xy 185.375 140.875) (xy 185.375 140.125) (xy 184.975 140.125) (xy 184.225 139.375) (xy 183.9 139.375)
				(xy 183.9 138.775) (xy 183.15 138.775) (xy 183.135926 140.097918) (xy 183.918922 140.875932)
			)
		)
	)
	(zone
		(net 47)
		(net_name "+1V05")
		(layer "B.Cu")
		(name "+1V05")
		(hatch edge 0.5)
		(priority 1)
		(connect_pads yes
			(clearance 0.1)
		)
		(min_thickness 0.25)
		(filled_areas_thickness no)
		(fill yes
			(thermal_gap 0.5)
			(thermal_bridge_width 0.5)
		)
		(polygon
			(pts
				(xy 186.85 147.35) (xy 187.6 146.6) (xy 188.95 146.6) (xy 189 142.65) (xy 188 142.65) (xy 188 143.15)
				(xy 185.6 145.55) (xy 185.6 147) (xy 185.95 147.35)
			)
		)
	)
	(zone
		(net 406)
		(net_name "/Supply/SENSE2_P")
		(layer "B.Cu")
		(name "SENSE3")
		(hatch edge 0.5)
		(priority 1)
		(connect_pads yes
			(clearance 0.1)
		)
		(min_thickness 0.25)
		(filled_areas_thickness no)
		(fill yes
			(thermal_gap 0.5)
			(thermal_bridge_width 0.5)
		)
		(polygon
			(pts
				(xy 175.075 143.125) (xy 175.075 144.4) (xy 177.1 144.4) (xy 177.1 143.038358) (xy 176.645129 142.598907)
				(xy 176.249956 142.600331) (xy 175.731226 143.125)
			)
		)
	)
	(zone
		(net 0)
		(net_name "")
		(layers "In1.Cu" "In2.Cu")
		(name "RF_trace_GND_cutout")
		(hatch edge 0.5)
		(connect_pads
			(clearance 0)
		)
		(min_thickness 0.25)
		(filled_areas_thickness no)
		(keepout
			(tracks allowed)
			(vias allowed)
			(pads allowed)
			(copperpour not_allowed)
			(footprints allowed)
		)
		(placement
			(enabled no)
			(sheetname "")
		)
		(fill
			(thermal_gap 0.5)
			(thermal_bridge_width 0.5)
		)
		(polygon
			(pts
				(xy 224.7015 140.847) (xy 225.8 140.855) (xy 225.8 139.255) (xy 228.75 139.255) (xy 228.75 142.905)
				(xy 224.7 142.905)
			)
		)
	)
	(zone
		(net 0)
		(net_name "")
		(layers "In1.Cu" "In2.Cu" "In3.Cu" "In4.Cu")
		(name "RF_connector_cutout")
		(hatch edge 0.5)
		(connect_pads
			(clearance 0)
		)
		(min_thickness 0.25)
		(filled_areas_thickness no)
		(keepout
			(tracks allowed)
			(vias allowed)
			(pads allowed)
			(copperpour not_allowed)
			(footprints allowed)
		)
		(placement
			(enabled no)
			(sheetname "")
		)
		(fill
			(thermal_gap 0.5)
			(thermal_bridge_width 0.5)
		)
		(polygon
			(pts
				(xy 225.05 135.155) (xy 229.15 135.155) (xy 229.15 139.255) (xy 225.05 139.255)
			)
		)
	)
	(zone
		(net 417)
		(net_name "GND")
		(layers "In1.Cu" "In3.Cu" "In5.Cu" "In8.Cu" "In10.Cu" "In12.Cu")
		(hatch edge 0.5)
		(connect_pads
			(clearance 0.1)
		)
		(min_thickness 0.1)
		(filled_areas_thickness no)
		(fill yes
			(thermal_gap 0.5)
			(thermal_bridge_width 0.5)
		)
		(polygon
			(pts
				(xy 174.45 115.75) (xy 229.6 115.75) (xy 229.6 155.9) (xy 174.45 155.9)
			)
		)
	)
	(zone
		(net 50)
		(net_name "+3V3")
		(layer "In2.Cu")
		(hatch edge 0.5)
		(priority 17)
		(connect_pads yes
			(clearance 0.12)
		)
		(min_thickness 0.12)
		(filled_areas_thickness no)
		(fill yes
			(thermal_gap 0.2)
			(thermal_bridge_width 0.2)
		)
		(polygon
			(pts
				(xy 174.45 137.62) (xy 178 137.62) (xy 178 139.4) (xy 178.8 140.2) (xy 186.6 140.2) (xy 188.8 142.6)
				(xy 192.67 142.48) (xy 192.96 142.77) (xy 192.96 144.36) (xy 192.96 146.72) (xy 192.74 146.94) (xy 190.38 146.94)
				(xy 189.27 148.05) (xy 174.47 148.05) (xy 174.45 148.03)
			)
		)
	)
	(zone
		(net 649)
		(net_name "VDD")
		(layer "In2.Cu")
		(hatch edge 0.5)
		(priority 9)
		(connect_pads
			(clearance 0.1)
		)
		(min_thickness 0.25)
		(filled_areas_thickness no)
		(fill yes
			(thermal_gap 0.5)
			(thermal_bridge_width 0.5)
		)
		(polygon
			(pts
				(xy 218.641615 149.4086) (xy 218.652731 145.654721) (xy 218.471123 145.474977) (xy 218.518609 137.468609)
				(xy 217 135.95) (xy 216.8 135.95) (xy 216.5 135.65) (xy 216.5 126.6) (xy 218.3 124.8) (xy 229.6 124.8)
				(xy 229.6 149.8) (xy 219.02 149.8)
			)
		)
	)
	(zone
		(net 418)
		(net_name "+2V5")
		(layer "In2.Cu")
		(hatch edge 0.5)
		(priority 1)
		(connect_pads yes
			(clearance 0.12)
		)
		(min_thickness 0.12)
		(filled_areas_thickness no)
		(fill yes
			(thermal_gap 0.2)
			(thermal_bridge_width 0.2)
		)
		(polygon
			(pts
				(xy 196.975539 140.634461) (xy 196.968467 138.579461) (xy 197.250539 138.299461) (xy 199.756477 138.293523)
				(xy 201 137) (xy 201 133.96) (xy 200.696588 133.65) (xy 200.693872 131.848014) (xy 201 131.548159)
				(xy 201 130.25) (xy 200.49 129.745023) (xy 197.490008 129.742044) (xy 197.11 129.36) (xy 193.720539 129.3583)
				(xy 193.720539 133.36) (xy 189.426623 137.619708) (xy 178.4 137.619183) (xy 178.4 139.2) (xy 179 139.8)
				(xy 186.8 139.8) (xy 189 142.1) (xy 195.5 142.1)
			)
		)
	)
	(zone
		(net 417)
		(net_name "GND")
		(layer "In4.Cu")
		(hatch edge 0.5)
		(priority 13)
		(connect_pads
			(clearance 0.2)
		)
		(min_thickness 0.25)
		(filled_areas_thickness no)
		(fill yes
			(thermal_gap 0.5)
			(thermal_bridge_width 0.5)
		)
		(polygon
			(pts
				(xy 186.95 140.1) (xy 185.154574 141.9) (xy 185.15 146.979065) (xy 188.628768 146.985842) (xy 189.349548 146.25)
				(xy 189.347874 144.648766) (xy 190.152441 143.85) (xy 190.7 143.85) (xy 190.7 149.95) (xy 188.75 151.9)
				(xy 188.25 151.9) (xy 188.05 152.1) (xy 188.05 155.8) (xy 174.5 155.8) (xy 174.5 137.4) (xy 180.45 137.4)
				(xy 181.075 138.025) (xy 181.081232 138.827858) (xy 181.767422 139.55) (xy 186.4 139.55)
			)
		)
	)
	(zone
		(net 47)
		(net_name "+1V05")
		(layer "In4.Cu")
		(hatch edge 0.5)
		(priority 12)
		(connect_pads
			(clearance 0.1)
		)
		(min_thickness 0.25)
		(filled_areas_thickness no)
		(fill yes
			(thermal_gap 0.5)
			(thermal_bridge_width 0.5)
		)
		(polygon
			(pts
				(xy 212.5 115.8) (xy 221.2 115.8) (xy 221.2 123.46) (xy 219.66 125) (xy 215.9 125) (xy 214.25 123.33)
				(xy 212.86 123.33) (xy 212.5 123)
			)
		)
	)
	(zone
		(net 47)
		(net_name "+1V05")
		(layer "In4.Cu")
		(hatch edge 0.5)
		(priority 20)
		(connect_pads
			(clearance 0.12)
		)
		(min_thickness 0.12)
		(filled_areas_thickness no)
		(fill yes
			(thermal_gap 0.2)
			(thermal_bridge_width 0.2)
		)
		(polygon
			(pts
				(xy 189.15 146.149) (xy 189.15 144.599) (xy 191.325 142.424) (xy 191.916712 142.426255) (xy 193.28 141.214442)
				(xy 193.28 139.32) (xy 194.34 138.26) (xy 195.12 138.26) (xy 195.25 138.39) (xy 195.25 138.82) (xy 195.09 138.98)
				(xy 195.09 139.24) (xy 195.22 139.37) (xy 195.22 139.79) (xy 195.13 139.88) (xy 194.99 139.88) (xy 194.92 139.95)
				(xy 194.92 140.61) (xy 195.04 140.73) (xy 196.75 140.73) (xy 196.91 140.52) (xy 196.91 140.22) (xy 197.08 140.01)
				(xy 197.6 139.999) (xy 197.875 140.274) (xy 198.325 140.274) (xy 198.6 139.999) (xy 199.15 139.999)
				(xy 199.4 140.249) (xy 199.4 140.299) (xy 199.95 140.299) (xy 200.225 140.024) (xy 200.225 137.299)
				(xy 199.547192 136.621192) (xy 199.55 133.75) (xy 198.3 132.474) (xy 196.525 132.474) (xy 196.375 132.624)
				(xy 196.375 132.974) (xy 192.075 137.274) (xy 190.225 137.274) (xy 185.45 142.049) (xy 185.45 146.799)
				(xy 188.5 146.799)
			)
		)
	)
	(zone
		(net 49)
		(net_name "VDDAUX")
		(layer "In4.Cu")
		(hatch edge 0.5)
		(connect_pads yes
			(clearance 0.12)
		)
		(min_thickness 0.12)
		(filled_areas_thickness no)
		(fill yes
			(thermal_gap 0.15)
			(thermal_bridge_width 0.15)
		)
		(polygon
			(pts
				(xy 197.8 130.1) (xy 198.75 130.1) (xy 199.056516 130.406516) (xy 199.900098 130.407412) (xy 201.42687 131.75786)
				(xy 204.269631 131.744631) (xy 208.9 136.375) (xy 208.9 144.95) (xy 215.175 151.225) (xy 219.275 151.225)
				(xy 222.9 147.6) (xy 222.9 142.1) (xy 215.9 135.1) (xy 215.9 128.1) (xy 216.9 127.1) (xy 229.483395 127.1)
				(xy 229.551314 151.608931) (xy 229.55 154.28) (xy 219.44 154.29) (xy 218.88 153.91) (xy 217.1185 153.9185)
				(xy 215.5835 153.9185) (xy 214.96 154.59) (xy 213.06 154.585654) (xy 212.760005 154.285702) (xy 211.884 154.286)
				(xy 203.2 145.602) (xy 203.2 138.7) (xy 201.4 136.9) (xy 200.15 136.9) (xy 199.8 136.5) (xy 199.8 133.6)
				(xy 198.45 132.25) (xy 197.55 132.25) (xy 197.299848 132) (xy 197.299 130.601)
			)
		)
	)
	(zone
		(net 50)
		(net_name "+3V3")
		(layer "In6.Cu")
		(hatch edge 0.5)
		(priority 1)
		(connect_pads yes
			(clearance 0.12)
		)
		(min_thickness 0.12)
		(filled_areas_thickness no)
		(fill yes
			(thermal_gap 0.2)
			(thermal_bridge_width 0.2)
		)
		(polygon
			(pts
				(xy 174.55 115.75) (xy 184.75 115.75) (xy 184.75 120) (xy 186.75 120) (xy 186.75 118.275) (xy 187 118.033766)
				(xy 196.75 118) (xy 196.75 119.25) (xy 200.75 122.320466) (xy 200.75 126.75) (xy 203 128.949982)
				(xy 203 129.28) (xy 200.5 131.75) (xy 185.21 131.75) (xy 185.21 132.455) (xy 181.0475 136.6175)
				(xy 181.05 138.25) (xy 179 138.25) (xy 177.5 139.75) (xy 177.5 143.75) (xy 177.75 144) (xy 181 144)
				(xy 181.5 144.5) (xy 182.25 144.5) (xy 183.75 146) (xy 183.75 147.25) (xy 186 149.5) (xy 189.5 149.5)
				(xy 190.25 148.75) (xy 192.5 148.75) (xy 194.25 147) (xy 195.25 147) (xy 196.5 148.25) (xy 197.75 148.25)
				(xy 198.25 148.75) (xy 198.25 150.75) (xy 199.25 151.75) (xy 205 151.75) (xy 206 150.75) (xy 209.5 150.75)
				(xy 210.25 149.925) (xy 210.25 144.25) (xy 212.25 142.25) (xy 212.25 138.25) (xy 212 138) (xy 209.25 138)
				(xy 209.25 136.25) (xy 218.5 136.25) (xy 218.5 134.75) (xy 216.25 134.75) (xy 213.25 131.75) (xy 213.25 115.82)
				(xy 220.096276 115.828724) (xy 221.45 115.825) (xy 229.6 115.825) (xy 229.6 155.875) (xy 174.55 155.875)
			)
		)
	)
	(zone
		(net 47)
		(net_name "+1V05")
		(layer "In6.Cu")
		(hatch edge 0.5)
		(connect_pads yes
			(clearance 0.12)
		)
		(min_thickness 0.12)
		(filled_areas_thickness no)
		(fill yes
			(thermal_gap 0.2)
			(thermal_bridge_width 0.2)
		)
		(polygon
			(pts
				(xy 185.5 132) (xy 200.25 132) (xy 200.25 137.25) (xy 203.97 140.75) (xy 205 140.75) (xy 207 138.75)
				(xy 211.5 138.75) (xy 211.75 139) (xy 211.75 141.25) (xy 208.087513 144.837487) (xy 204.936692 144.838308)
				(xy 204.95 144.825) (xy 191.83 144.825) (xy 190.94 145.715) (xy 190.94 146.025) (xy 190.19 146.775)
				(xy 185.55 146.775) (xy 182.75 143.7) (xy 182.75 139.75) (xy 182.5 139.5) (xy 181.5 139.5) (xy 181.36 139.25)
				(xy 181.36 136.75) (xy 185.5 132.75)
			)
		)
	)
	(zone
		(net 90)
		(net_name "+5V")
		(layer "In6.Cu")
		(name "+5V")
		(hatch edge 0.5)
		(priority 1)
		(connect_pads yes
			(clearance 0.1)
		)
		(min_thickness 0.25)
		(filled_areas_thickness no)
		(fill yes
			(thermal_gap 0.5)
			(thermal_bridge_width 0.5)
		)
		(polygon
			(pts
				(xy 177.99 139.7375) (xy 179.188179 138.539321) (xy 181.103307 138.540807) (xy 181.1 139.6375) (xy 181.2 139.7375)
				(xy 182.25 139.7375) (xy 182.4 139.8875) (xy 182.4 143.5875) (xy 182.25 143.7375) (xy 178 143.7375)
				(xy 177.85 143.5875) (xy 177.85 139.8875) (xy 178 139.7375)
			)
		)
	)
	(zone
		(net 649)
		(net_name "VDD")
		(layer "In6.Cu")
		(hatch edge 0.5)
		(priority 1)
		(connect_pads yes
			(clearance 0.12)
		)
		(min_thickness 0.12)
		(filled_areas_thickness no)
		(fill yes
			(thermal_gap 0.2)
			(thermal_bridge_width 0.2)
		)
		(polygon
			(pts
				(xy 204.07 140.325) (xy 204.93 140.325) (xy 206.882061 138.372939) (xy 208.975 138.375981) (xy 208.975 135.975)
				(xy 218.1 135.975) (xy 218.1 135.052664) (xy 216.125 135.05) (xy 212.815452 131.745622) (xy 212.82 115.82)
				(xy 185 115.75) (xy 185 119.75) (xy 186.5 119.75) (xy 186.5 118) (xy 186.775002 117.75) (xy 197 117.75)
				(xy 197 119.25) (xy 201 122.214916) (xy 201 126.578878) (xy 203.25 128.75) (xy 203.25 129.5) (xy 200.75 132)
				(xy 200.75 137.05)
			)
		)
	)
	(zone
		(net 48)
		(net_name "+1V8")
		(layer "In7.Cu")
		(hatch edge 0.5)
		(connect_pads
			(clearance 0.12)
		)
		(min_thickness 0.12)
		(filled_areas_thickness no)
		(fill yes
			(thermal_gap 0.2)
			(thermal_bridge_width 0.2)
		)
		(polygon
			(pts
				(xy 227.25 146.5) (xy 222.75 150.75) (xy 189.8 150.75) (xy 189.8 143) (xy 189.4 139.8) (xy 188.6 139)
				(xy 187.2 139.4) (xy 186.4 139.4) (xy 184.75 137.90631) (xy 178.387848 137.905) (xy 177.507596 138.778137)
				(xy 177.5 139.805016) (xy 177.792667 140.005015) (xy 177.8 143.559901) (xy 176.200222 145.157394)
				(xy 176.197207 145.805112) (xy 175.899702 146.100864) (xy 174.5 146.105) (xy 174.5 115.805) (xy 192.2 115.805)
				(xy 192.2 121.405) (xy 190.5 121.405) (xy 190 121.905) (xy 190 122.705) (xy 193.716746 126.398459)
				(xy 193.725516 133.605) (xy 194.255746 134.13418) (xy 194.254041 134.748062) (xy 192.504499 136.587268)
				(xy 192.510757 140.108192) (xy 191.54779 141.094452) (xy 191.546788 141.645829) (xy 192.424269 142.481891)
				(xy 195.089575 142.471721) (xy 200.756188 148.145272) (xy 206.75 148.131911) (xy 208.975 145.75)
				(xy 222.75 145.75) (xy 225 143.5) (xy 225 140.75) (xy 220 135.75) (xy 220 134.25) (xy 221.25 134.25)
				(xy 227.25 140.13)
			)
		)
	)
	(zone
		(net 47)
		(net_name "+1V05")
		(layer "In7.Cu")
		(hatch edge 0.5)
		(priority 15)
		(connect_pads yes
			(clearance 0.12)
		)
		(min_thickness 0.25)
		(filled_areas_thickness no)
		(fill yes
			(thermal_gap 0.5)
			(thermal_bridge_width 0.5)
		)
		(polygon
			(pts
				(xy 211.99 139.98) (xy 211.38 139.37) (xy 209.58 139.37) (xy 208.975 139.98) (xy 208.975 145.28)
				(xy 222.65 145.28) (xy 224.5 143.25) (xy 224.5 141) (xy 219.5 135.75) (xy 219.5 132.5) (xy 218.75 131.75)
				(xy 218.75 115.755) (xy 211.25 115.755) (xy 211.25 120.13) (xy 213.075 121.955) (xy 213.075 134.73)
				(xy 214.6 136.25) (xy 218.45 136.25) (xy 222.74 140.54) (xy 222.7375 141.7125) (xy 221.82 142.63)
				(xy 218.275 142.63) (xy 215.625 139.98)
			)
		)
	)
	(zone
		(net 418)
		(net_name "+2V5")
		(layer "In7.Cu")
		(hatch edge 0.5)
		(priority 6)
		(connect_pads
			(clearance 0.1)
		)
		(min_thickness 0.25)
		(filled_areas_thickness no)
		(fill yes
			(thermal_gap 0.5)
			(thermal_bridge_width 0.5)
		)
		(polygon
			(pts
				(xy 219.225 115.805) (xy 229.8 115.805) (xy 229.8 155.705) (xy 229.6 155.905) (xy 180.8 155.905)
				(xy 180.8 151.200688) (xy 184.195688 151.200688) (xy 184.2 151.205) (xy 185.4 150.005) (xy 185.4 140.4)
				(xy 188.4 139.4) (xy 189 140) (xy 189.4 143) (xy 189.4 150.969) (xy 189.786 151.205) (xy 223 151.205)
				(xy 227.625 146.58) (xy 227.625 140.13) (xy 221.25 133.75) (xy 219.881664 133.75) (xy 219.887318 132.392318)
				(xy 219.225 131.73)
			)
		)
	)
	(zone
		(net 90)
		(net_name "+5V")
		(layer "In9.Cu")
		(hatch edge 0.5)
		(priority 11)
		(connect_pads
			(clearance 0.1)
		)
		(min_thickness 0.25)
		(filled_areas_thickness no)
		(fill yes
			(thermal_gap 0.5)
			(thermal_bridge_width 0.5)
		)
		(polygon
			(pts
				(xy 189.15 115.8) (xy 194.4 115.8) (xy 194.4 118.201) (xy 189.101 123.5) (xy 188.9 123.5) (xy 188.7 123.7)
				(xy 188.7 138.74) (xy 188.341005 139.1) (xy 188.348659 145.848659) (xy 188.706083 146.206083) (xy 188.7 152.6)
				(xy 188.7 155.8) (xy 174.6 155.8) (xy 174.5 155.7) (xy 174.5 140.9) (xy 174.7 140.7) (xy 178.2 140.7)
				(xy 180.1 138.8) (xy 180.1 138.4) (xy 181.3 137.2) (xy 184.4 137.2) (xy 185.3 136.3) (xy 185.3 119.6)
			)
		)
	)
	(zone
		(net 90)
		(net_name "+5V")
		(layer "In11.Cu")
		(hatch edge 0.5)
		(priority 8)
		(connect_pads
			(clearance 0.12)
		)
		(min_thickness 0.25)
		(filled_areas_thickness no)
		(fill yes
			(thermal_gap 0.5)
			(thermal_bridge_width 0.5)
		)
		(polygon
			(pts
				(xy 182.075 145.825) (xy 181.4 146.5) (xy 179.116088 146.5) (xy 178.016088 147.6) (xy 174.45 147.6)
				(xy 174.45 155.875) (xy 229.7 155.875) (xy 229.7 115.95) (xy 229.625 115.875) (xy 219.475 115.875)
				(xy 219.025 116.325) (xy 219.025 135.89) (xy 218.6 136.31302) (xy 212.816032 136.319273) (xy 212.385 136.75033)
				(xy 212.385 139.51) (xy 213.3 140.425) (xy 213.3 145.725) (xy 210.85 148.175) (xy 210.55 148.175)
				(xy 210.5 148.225) (xy 210.5 148.825) (xy 211.2 149.525) (xy 211.2 151.575) (xy 209.974 152.801)
				(xy 197.3245 152.801) (xy 190.3485 145.825)
			)
		)
	)
	(zone
		(net 137)
		(net_name "SD_VDD")
		(layer "In11.Cu")
		(hatch edge 0.5)
		(priority 10)
		(connect_pads
			(clearance 0.12)
		)
		(min_thickness 0.12)
		(filled_areas_thickness no)
		(fill yes
			(thermal_gap 0.2)
			(thermal_bridge_width 0.2)
		)
		(polygon
			(pts
				(xy 196.3 121) (xy 199.3 124) (xy 199.3 124.6) (xy 198.8 125.1) (xy 198.8 126.9) (xy 199.7 127.8)
				(xy 200.725 127.8) (xy 201 127.525) (xy 201 122.85) (xy 201.15 122.7) (xy 206.89 122.7) (xy 210.33 126.14)
				(xy 210.33 133.63) (xy 212.69 135.99) (xy 218.38 135.99) (xy 218.796664 135.573336) (xy 218.807825 117.93175)
				(xy 196.307825 117.93175)
			)
		)
	)
	(zone
		(net 417)
		(net_name "GND")
		(layer "In11.Cu")
		(hatch edge 0.5)
		(priority 19)
		(connect_pads
			(clearance 0.2)
		)
		(min_thickness 0.25)
		(filled_areas_thickness no)
		(fill yes
			(thermal_gap 0.5)
			(thermal_bridge_width 0.5)
		)
		(polygon
			(pts
				(xy 174.5 147.2) (xy 177.902003 147.2) (xy 179.45 145.65) (xy 186.75 145.65) (xy 186.75 137.3) (xy 186.5 137.1)
				(xy 174.5 137.1)
			)
		)
	)
)
